G04 ================== begin FILE IDENTIFICATION RECORD ==================*
G04 Layout Name:  9127_F0T_Expander_BD_F_v02_0110_1240.brd*
G04 Film Name:    pmt*
G04 File Format:  Gerber RS274X*
G04 File Origin:  Cadence Allegro 17.2-S081*
G04 Origin Date:  Wed Jan 11 16:06:13 2023*
G04 *
G04 Layer:  DRAWING FORMAT/TITLE_BLOCK_A*
G04 Layer:  VIA CLASS/PASTEMASK_TOP*
G04 Layer:  PACKAGE GEOMETRY/PASTEMASK_TOP*
G04 Layer:  DRAWING FORMAT/TITLE_BLOCK*
G04 Layer:  PIN/PASTEMASK_TOP*
G04 Layer:  MANUFACTURING/PHOTOPLOT_OUTLINE*
G04 Layer:  DRAWING FORMAT/TITLE_DATA_PMT*
G04 *
G04 Offset:    (0.00 0.00)*
G04 Mirror:    No*
G04 Mode:      Positive*
G04 Rotation:  0*
G04 FullContactRelief:  No*
G04 UndefLineWidth:     6.00*
G04 ================== end FILE IDENTIFICATION RECORD ====================*
%FSLAX25Y25*MOIN*%
%IR0*IPPOS*OFA0.00000B0.00000*MIA0B0*SFA1.00000B1.00000*%
%AMMACRO189*
4,1,5,.10039,-.10039,
-.08858,-.10039,
-.10039,-.08858,
-.10039,.10039,
.10039,.10039,
.10039,-.10039,
0.0*
%
%ADD189MACRO189*%
%AMMACRO45*
4,1,32,-.01575,.06201,
-.01575,.0502,
.00197,.0502,
.00197,.04035,
-.01575,.04035,
-.01575,.03248,
.00197,.03248,
.00197,.02461,
-.01575,.02461,
-.01575,.01673,
.00197,.01673,
.00197,.00886,
-.01575,.00886,
-.01575,.00098,
.00197,.00098,
.00197,-.00689,
-.01575,-.00689,
-.01575,-.01476,
.00197,-.01476,
.00197,-.02264,
-.01575,-.02264,
-.01575,-.03051,
.00197,-.03051,
.00197,-.03839,
-.01575,-.03839,
-.01575,-.04626,
.00197,-.04626,
.00197,-.05413,
-.01575,-.05413,
-.01575,-.06201,
.01575,-.06201,
.01575,.06201,
-.01575,.06201,
0.0*
%
%ADD45MACRO45*%
%AMMACRO216*
4,1,5,-.10039,-.10039,
-.10039,.08858,
-.08858,.10039,
.10039,.10039,
.10039,-.10039,
-.10039,-.10039,
0.0*
%
%ADD216MACRO216*%
%AMMACRO155*
4,1,5,.05512,.05512,
-.04134,.05512,
-.05512,.04134,
-.05512,-.05512,
.05512,-.05512,
.05512,.05512,
0.0*
%
%ADD155MACRO155*%
%AMMACRO209*
4,1,8,.06299,-.02953,
.06299,.02953,
-.06299,.02953,
-.06299,-.02953,
-.01968,-.02953,
-.01968,.01771,
.01968,.01771,
.01968,-.02953,
.06299,-.02953,
0.0*
%
%ADD209MACRO209*%
%ADD210R,.231X.035*%
%ADD195R,.02X.007*%
%ADD165R,.109X.04*%
%ADD124R,.17X.024*%
%ADD102R,.135X.05*%
%ADD188R,.022X.007*%
%ADD99O,.137X.062*%
%ADD190R,.007X.022*%
%AMMACRO137*
4,1,21,-.017,0.0,
-.016916,.000955,
-.016668,.001881,
-.016263,.00275,
-.015713,.003535,
-.015035,.004213,
-.01425,.004763,
-.013381,.005168,
-.012455,.005416,
-.0115,.0055,
.017,.0055,
.017,-.0055,
-.0115,-.0055,
-.012455,-.005416,
-.013381,-.005168,
-.01425,-.004763,
-.015035,-.004213,
-.015713,-.003535,
-.016263,-.00275,
-.016668,-.001881,
-.016916,-.000955,
-.017,0.0,
0.0*
%
%ADD137MACRO137*%
%ADD125R,.111X.095*%
%ADD69R,.032X.007*%
%ADD47R,.0041X.016*%
%ADD10C,.03*%
%ADD149R,.024X.007*%
%AMMACRO117*
4,1,21,0.0,.017,
.000955,.016916,
.001881,.016668,
.00275,.016263,
.003535,.015713,
.004213,.015035,
.004763,.01425,
.005168,.013381,
.005416,.012455,
.0055,.0115,
.0055,-.017,
-.0055,-.017,
-.0055,.0115,
-.005416,.012455,
-.005168,.013381,
-.004763,.01425,
-.004213,.015035,
-.003535,.015713,
-.00275,.016263,
-.001881,.016668,
-.000955,.016916,
0.0,.017,
0.0*
%
%ADD117MACRO117*%
%ADD88R,.016X.0041*%
%ADD70C,.04*%
%ADD51O,.137X.064*%
%ADD215R,.095X.13*%
%ADD150R,.007X.024*%
%ADD172R,.015X.009*%
%AMMACRO83*
4,1,8,-.01771,-.01476,
.01772,-.01476,
.01772,.01476,
-.01771,.01476,
-.01771,.00492,
.00394,.00492,
.00394,-.00492,
-.01771,-.00492,
-.01771,-.01476,
0.0*
%
%ADD83MACRO83*%
%ADD64R,.024X.009*%
%ADD37R,.119X.063*%
%ADD220C,.061*%
%ADD184C,.016*%
%ADD171R,.009X.015*%
%ADD136R,.063X.119*%
%ADD116R,.138X.063*%
%AMMACRO108*
4,1,8,-.01476,.01771,
-.01476,-.01772,
.01476,-.01772,
.01476,.01771,
.00492,.01771,
.00492,-.00394,
-.00492,-.00394,
-.00492,.01771,
-.01476,.01771,
0.0*
%
%ADD108MACRO108*%
%ADD63R,.009X.024*%
%ADD194R,.006X.028*%
%ADD147R,.063X.138*%
%AMMACRO133*
4,1,21,.0035,-.0135,
.003447,-.014108,
.003289,-.014697,
.003031,-.01525,
.002681,-.01575,
.00225,-.016181,
.00175,-.016531,
.001197,-.016789,
.000608,-.016947,
0.0,-.017,
-.000608,-.016947,
-.001197,-.016789,
-.00175,-.016531,
-.00225,-.016181,
-.002681,-.01575,
-.003031,-.01525,
-.003289,-.014697,
-.003447,-.014108,
-.0035,-.0135,
-.0035,.017,
.0035,.017,
.0035,-.0135,
0.0*
%
%ADD133MACRO133*%
%AMMACRO131*
4,1,21,.0135,.0035,
.014108,.003447,
.014697,.003289,
.01525,.003031,
.01575,.002681,
.016181,.00225,
.016531,.00175,
.016789,.001197,
.016947,.000608,
.017,0.0,
.016947,-.000608,
.016789,-.001197,
.016531,-.00175,
.016181,-.00225,
.01575,-.002681,
.01525,-.003031,
.014697,-.003289,
.014108,-.003447,
.0135,-.0035,
-.017,-.0035,
-.017,.0035,
.0135,.0035,
0.0*
%
%ADD131MACRO131*%
%ADD76R,.069X.105*%
%ADD96C,.018*%
%ADD61R,.073X.138*%
%ADD42R,.107X.078*%
%ADD120R,.13X.0848*%
%ADD98C,.064*%
%ADD55R,.078X.107*%
%ADD185C,.048*%
%ADD222R,.061X.061*%
%ADD65R,.067X.067*%
%AMMACRO94*
4,1,28,-.00566,.00492,
-.00733,.00659,
-.01122,.00269,
-.011659,.002174,
-.011998,.001588,
-.01223,.000951,
-.012348,.000284,
-.012348,-.000393,
-.012231,-.001061,
-.012,-.001697,
-.011661,-.002284,
-.011226,-.002803,
-.01119,-.00284,
-.00284,-.01119,
-.002326,-.011631,
-.001744,-.011978,
-.00111,-.012217,
-.000444,-.012343,
.000233,-.012352,
.000902,-.012243,
.001541,-.012019,
.002132,-.011688,
.002656,-.011259,
.00269,-.01122,
.00659,-.00733,
.00492,-.00566,
.0123,.00172,
.00172,.0123,
-.00566,.00492,
0.0*
%
%ADD94MACRO94*%
%AMMACRO13*
4,1,28,-.00748,-.00052,
-.00984,-.00052,
-.00984,-.00603,
-.009782,-.006705,
-.009607,-.007359,
-.009321,-.007974,
-.008933,-.008529,
-.008455,-.009009,
-.0079,-.009398,
-.007286,-.009685,
-.006632,-.009861,
-.005957,-.00992,
-.00591,-.00992,
.00591,-.00992,
.006585,-.009869,
.007242,-.009701,
.007859,-.009421,
.008418,-.009039,
.008903,-.008565,
.009297,-.008015,
.009591,-.007404,
.009773,-.006751,
.00984,-.006077,
.00984,-.00603,
.00984,-.00052,
.00748,-.00052,
.00748,.00991,
-.00748,.00991,
-.00748,-.00052,
0.0*
%
%ADD13MACRO13*%
%AMMACRO74*
4,1,5,.00492,.01673,
-.00492,.01673,
-.00492,-.01673,
.00098,-.01673,
.00492,-.0128,
.00492,.01673,
0.0*
%
%ADD74MACRO74*%
%AMMACRO30*
4,1,28,-.00052,.00748,
-.00052,.00984,
-.00603,.00984,
-.006705,.009782,
-.007359,.009607,
-.007974,.009321,
-.008529,.008933,
-.009009,.008455,
-.009398,.0079,
-.009685,.007286,
-.009861,.006632,
-.00992,.005957,
-.00992,.00591,
-.00992,-.00591,
-.009869,-.006585,
-.009701,-.007242,
-.009421,-.007859,
-.009039,-.008418,
-.008565,-.008903,
-.008015,-.009297,
-.007404,-.009591,
-.006751,-.009773,
-.006077,-.00984,
-.00603,-.00984,
-.00052,-.00984,
-.00052,-.00748,
.00991,-.00748,
.00991,.00748,
-.00052,.00748,
0.0*
%
%ADD30MACRO30*%
%AMMACRO202*
4,1,8,.0034,-.0082,
-.0034,-.0082,
-.0082,-.0034,
-.0082,.00341,
-.00341,.0082,
.0034,.0082,
.0082,.0034,
.0082,-.0034,
.0034,-.0082,
0.0*
%
%ADD202MACRO202*%
%AMMACRO203*
4,1,8,-.0082,-.0034,
-.0082,.0034,
-.0034,.0082,
.00341,.0082,
.0082,.00341,
.0082,-.0034,
.0034,-.0082,
-.0034,-.0082,
-.0082,-.0034,
0.0*
%
%ADD203MACRO203*%
%AMMACRO95*
4,1,28,-.00493,.00565,
-.0066,.00732,
-.0027,.01121,
-.002185,.011649,
-.001599,.011989,
-.000962,.012222,
-.000295,.01234,
.000382,.012342,
.001049,.012225,
.001686,.011994,
.002273,.011657,
.002793,.011222,
.00283,.01119,
.01119,.00283,
.011629,.002313,
.011974,.00173,
.012212,.001096,
.012337,.00043,
.012344,-.000247,
.012234,-.000915,
.012009,-.001554,
.011677,-.002145,
.011247,-.002668,
.01121,-.0027,
.00732,-.0066,
.00565,-.00493,
-.00173,-.0123,
-.0123,-.00173,
-.00493,.00565,
0.0*
%
%ADD95MACRO95*%
%AMMACRO15*
4,1,28,-.00748,.00051,
-.00984,.00051,
-.00984,.00602,
-.009782,.006695,
-.009607,.007349,
-.009321,.007964,
-.008933,.008519,
-.008455,.008998,
-.0079,.009388,
-.007287,.009675,
-.006632,.009851,
-.005958,.00991,
-.00591,.00991,
.00591,.00991,
.006585,.009859,
.007242,.009691,
.007859,.009411,
.008418,.009029,
.008903,.008555,
.009297,.008005,
.00959,.007394,
.009773,.006742,
.00984,.006068,
.00984,.00602,
.00984,.00051,
.00748,.00051,
.00748,-.00992,
-.00748,-.00992,
-.00748,.00051,
0.0*
%
%ADD15MACRO15*%
%AMMACRO29*
4,1,28,.00051,.00748,
.00051,.00984,
.00602,.00984,
.006695,.009782,
.007349,.009607,
.007964,.009321,
.008519,.008933,
.008998,.008455,
.009388,.0079,
.009675,.007287,
.009851,.006632,
.00991,.005958,
.00991,.00591,
.00991,-.00591,
.009859,-.006585,
.009691,-.007242,
.009411,-.007859,
.009029,-.008418,
.008555,-.008903,
.008005,-.009297,
.007394,-.00959,
.006742,-.009773,
.006068,-.00984,
.00602,-.00984,
.00051,-.00984,
.00051,-.00748,
-.00992,-.00748,
-.00992,.00748,
.00051,.00748,
0.0*
%
%ADD29MACRO29*%
%AMMACRO109*
4,1,9,-.01476,.01181,
-.01476,-.01771,
-.00492,-.01771,
-.00492,.00394,
.00492,.00394,
.00492,-.01771,
.01476,-.01771,
.01476,.01772,
-.00886,.01772,
-.01476,.01181,
0.0*
%
%ADD109MACRO109*%
%AMMACRO82*
4,1,9,-.01181,-.01476,
.01771,-.01476,
.01771,-.00492,
-.00394,-.00492,
-.00394,.00492,
.01771,.00492,
.01771,.01476,
-.01772,.01476,
-.01772,-.00886,
-.01181,-.01476,
0.0*
%
%ADD82MACRO82*%
%AMMACRO73*
4,1,8,-.01821,.0246,
.01821,.0246,
.01821,.01476,
-.00837,.01476,
-.00837,-.01477,
.01821,-.01477,
.01821,-.02461,
-.01821,-.02461,
-.01821,.0246,
0.0*
%
%ADD73MACRO73*%
%ADD142R,.02X.01*%
%AMMACRO49*
4,1,40,-.00984,-.00472,
.00984,-.00472,
.010182,-.004691,
.010513,-.004603,
.010824,-.004458,
.011105,-.004262,
.011348,-.00402,
.011545,-.00374,
.01169,-.003429,
.01178,-.003098,
.01181,-.00276,
.01181,.00276,
.011779,.003101,
.011689,.003432,
.011543,.003742,
.011346,.004023,
.011102,.004264,
.010821,.00446,
.01051,.004604,
.010178,.004691,
.00984,.00472,
-.00984,.00472,
-.010182,.004691,
-.010513,.004603,
-.010824,.004458,
-.011105,.004262,
-.011348,.00402,
-.011545,.00374,
-.01169,.003429,
-.01178,.003098,
-.01181,.00276,
-.01181,-.00276,
-.011779,-.003101,
-.011689,-.003432,
-.011543,-.003742,
-.011346,-.004023,
-.011102,-.004264,
-.010821,-.00446,
-.01051,-.004604,
-.010178,-.004691,
-.00984,-.00472,
0.0*
%
%ADD49MACRO49*%
%ADD34R,.01X.02*%
%ADD27R,.02X.02*%
%AMMACRO50*
4,1,40,-.00472,.00984,
-.00472,-.00984,
-.004691,-.010182,
-.004603,-.010513,
-.004458,-.010824,
-.004262,-.011105,
-.00402,-.011348,
-.00374,-.011545,
-.003429,-.01169,
-.003098,-.01178,
-.00276,-.01181,
.00276,-.01181,
.003101,-.011779,
.003432,-.011689,
.003742,-.011543,
.004023,-.011346,
.004264,-.011102,
.00446,-.010821,
.004604,-.01051,
.004691,-.010178,
.00472,-.00984,
.00472,.00984,
.004691,.010182,
.004603,.010513,
.004458,.010824,
.004262,.011105,
.00402,.011348,
.00374,.011545,
.003429,.01169,
.003098,.01178,
.00276,.01181,
-.00276,.01181,
-.003101,.011779,
-.003432,.011689,
-.003742,.011543,
-.004023,.011346,
-.004264,.011102,
-.00446,.010821,
-.004604,.01051,
-.004691,.010178,
-.00472,.00984,
0.0*
%
%ADD50MACRO50*%
%ADD31R,.02X.02*%
%ADD181R,.014X.01*%
%ADD134R,.05X.01*%
%ADD60R,.032X.01*%
%ADD182R,.015X.01*%
%ADD180R,.01X.014*%
%ADD141R,.122X.132*%
%ADD59R,.01X.05*%
%ADD58R,.01X.032*%
%ADD179R,.01X.015*%
%ADD164R,.04X.022*%
%ADD153R,.061X.01*%
%ADD85R,.011X.032*%
%ADD77R,.06X.02*%
%ADD56R,.024X.011*%
%ADD46R,.032X.012*%
%ADD229R,.02X.024*%
%ADD169R,.022X.04*%
%ADD87R,.015X.012*%
%ADD41R,.011X.024*%
%ADD26R,.05X.04*%
%ADD162R,.061X.012*%
%AMMACRO138*
4,1,32,.01575,-.06201,
.01575,-.0502,
-.00197,-.0502,
-.00197,-.04035,
.01575,-.04035,
.01575,-.03248,
-.00197,-.03248,
-.00197,-.02461,
.01575,-.02461,
.01575,-.01673,
-.00197,-.01673,
-.00197,-.00886,
.01575,-.00886,
.01575,-.00098,
-.00197,-.00098,
-.00197,.00689,
.01575,.00689,
.01575,.01476,
-.00197,.01476,
-.00197,.02264,
.01575,.02264,
.01575,.03051,
-.00197,.03051,
-.00197,.03839,
.01575,.03839,
.01575,.04626,
-.00197,.04626,
-.00197,.05413,
.01575,.05413,
.01575,.06201,
-.01575,.06201,
-.01575,-.06201,
.01575,-.06201,
0.0*
%
%ADD138MACRO138*%
%ADD79R,.012X.015*%
%ADD25R,.04X.05*%
%ADD226R,.012X.061*%
%ADD186R,.018X.011*%
%ADD183R,.04X.015*%
%ADD166R,.032X.024*%
%ADD157R,.054X.011*%
%ADD110R,.028X.01*%
%ADD101R,.02X.018*%
%ADD75R,.036X.011*%
%ADD52R,.05X.015*%
%ADD228R,.052X.014*%
%ADD223R,.042X.024*%
%ADD211R,.091X.02*%
%AMMACRO208*
4,1,8,-.06299,.02953,
-.06299,-.02953,
.06299,-.02953,
.06299,.02953,
.01968,.02953,
.01968,-.01771,
-.01968,-.01771,
-.01968,.02953,
-.06299,.02953,
0.0*
%
%ADD208MACRO208*%
%ADD187R,.011X.018*%
%ADD158R,.011X.054*%
%ADD140R,.018X.012*%
%ADD127R,.029X.01*%
%AMMACRO119*
4,1,21,0.0,-.017,
-.000955,-.016916,
-.001881,-.016668,
-.00275,-.016263,
-.003535,-.015713,
-.004213,-.015035,
-.004763,-.01425,
-.005168,-.013381,
-.005416,-.012455,
-.0055,-.0115,
-.0055,.017,
.0055,.017,
.0055,-.0115,
.005416,-.012455,
.005168,-.013381,
.004763,-.01425,
.004213,-.015035,
.003535,-.015713,
.00275,-.016263,
.001881,-.016668,
.000955,-.016916,
0.0,-.017,
0.0*
%
%ADD119MACRO119*%
%AMMACRO115*
4,1,21,.017,0.0,
.016916,-.000955,
.016668,-.001881,
.016263,-.00275,
.015713,-.003535,
.015035,-.004213,
.01425,-.004763,
.013381,-.005168,
.012455,-.005416,
.0115,-.0055,
-.017,-.0055,
-.017,.0055,
.0115,.0055,
.012455,.005416,
.013381,.005168,
.01425,.004763,
.015035,.004213,
.015713,.003535,
.016263,.00275,
.016668,.001881,
.016916,.000955,
.017,0.0,
0.0*
%
%ADD115MACRO115*%
%ADD106R,.034X.014*%
%ADD105R,.053X.022*%
%ADD100R,.018X.02*%
%AMMACRO80*
21,1,.016,.0041,0.0,0.0,135.*%
%ADD80MACRO80*%
%ADD68R,.036X.012*%
%ADD23R,.01X.028*%
%ADD213R,.27X.126*%
%ADD191R,.032X.034*%
%ADD174R,.014X.034*%
%ADD173R,.011X.028*%
%ADD168R,.024X.042*%
%ADD160R,.022X.053*%
%ADD159R,.044X.014*%
%ADD148R,.04X.036*%
%ADD129R,.01X.029*%
%ADD107R,.014X.052*%
%ADD103R,.052X.024*%
%ADD28R,.024X.016*%
%ADD231O,.044X.071*%
%ADD193R,.053X.015*%
%ADD163R,.036X.032*%
%ADD152R,.014X.044*%
%ADD104R,.024X.017*%
%ADD81R,.024X.052*%
%ADD54R,.016X.024*%
%ADD44R,.146X.116*%
%ADD36R,.138X.115*%
%ADD230R,.036X.024*%
%ADD176R,.054X.024*%
%ADD161R,.017X.024*%
%ADD72R,.115X.138*%
%ADD53R,.056X.04*%
%ADD43R,.032X.028*%
%ADD38R,.032X.036*%
%AMMACRO22*
4,1,8,.01771,.01476,
-.01772,.01476,
-.01772,-.01476,
.01771,-.01476,
.01771,-.00492,
-.00394,-.00492,
-.00394,.00492,
.01771,.00492,
.01771,.01476,
0.0*
%
%ADD22MACRO22*%
%ADD227R,.048X.04*%
%ADD218R,.056X.05*%
%ADD207R,.016X.044*%
%ADD205R,.024X.054*%
%ADD201R,.028X.024*%
%ADD198R,.022X.056*%
%ADD197R,.128X.135*%
%ADD177R,.054X.016*%
%ADD113R,.046X.024*%
%ADD32R,.028X.032*%
%ADD12R,.04X.056*%
%ADD204R,.016X.054*%
%ADD200R,.04X.048*%
%ADD146R,.1692X.13*%
%ADD97R,.048X.014*%
%ADD90R,.054X.044*%
%ADD89R,.024X.028*%
%ADD86R,.052X.028*%
%ADD17R,.024X.046*%
%ADD225R,.068X.022*%
%ADD192R,.058X.014*%
%ADD126R,.071X.046*%
%ADD114R,.046X.017*%
%ADD91R,.044X.054*%
%ADD78R,.071X.028*%
%ADD217R,.048X.025*%
%ADD178R,.059X.014*%
%ADD170R,.063X.046*%
%ADD122R,.091X.081*%
%ADD33R,.046X.071*%
%ADD18R,.017X.046*%
%ADD214R,.014X.059*%
%ADD167R,.025X.048*%
%ADD67R,.012X.079*%
%ADD233O,.044X.087*%
%ADD128R,.14X.14*%
%ADD232R,.059X.017*%
%AMMACRO144*
4,1,21,-.0135,-.0035,
-.014108,-.003447,
-.014697,-.003289,
-.01525,-.003031,
-.01575,-.002681,
-.016181,-.00225,
-.016531,-.00175,
-.016789,-.001197,
-.016947,-.000608,
-.017,0.0,
-.016947,.000608,
-.016789,.001197,
-.016531,.00175,
-.016181,.00225,
-.01575,.002681,
-.01525,.003031,
-.014697,.003289,
-.014108,.003447,
-.0135,.0035,
.017,.0035,
.017,-.0035,
-.0135,-.0035,
0.0*
%
%ADD144MACRO144*%
%ADD11C,.256*%
%ADD224R,.017X.059*%
%ADD199R,.038X.056*%
%ADD156R,.056X.048*%
%ADD154C,.009*%
%AMMACRO130*
4,1,21,-.0035,.0135,
-.003447,.014108,
-.003289,.014697,
-.003031,.01525,
-.002681,.01575,
-.00225,.016181,
-.00175,.016531,
-.001197,.016789,
-.000608,.016947,
0.0,.017,
.000608,.016947,
.001197,.016789,
.00175,.016531,
.00225,.016181,
.002681,.01575,
.003031,.01525,
.003289,.014697,
.003447,.014108,
.0035,.0135,
.0035,-.017,
-.0035,-.017,
-.0035,.0135,
0.0*
%
%ADD130MACRO130*%
%ADD175R,.134X.134*%
%ADD121R,.099X.042*%
%ADD39R,.048X.056*%
%ADD221R,.069X.046*%
%ADD151R,.144X.144*%
%ADD40C,.394*%
%ADD196R,.059X.048*%
%ADD212R,.048X.059*%
%ADD219R,.189X.186*%
%ADD132R,.166X.166*%
%ADD143R,.079X.059*%
%ADD139R,.069X.077*%
%AMMACRO112*
4,1,28,.00492,.00566,
.00659,.00733,
.00269,.01122,
.002174,.011659,
.001588,.011998,
.000951,.01223,
.000284,.012348,
-.000393,.012348,
-.001061,.012231,
-.001697,.012,
-.002284,.011661,
-.002803,.011226,
-.00284,.01119,
-.01119,.00284,
-.011631,.002326,
-.011978,.001744,
-.012217,.00111,
-.012343,.000444,
-.012352,-.000233,
-.012243,-.000902,
-.012019,-.001541,
-.011688,-.002132,
-.011259,-.002656,
-.01122,-.00269,
-.00733,-.00659,
-.00566,-.00492,
.00172,-.0123,
.0123,-.00172,
.00492,.00566,
0.0*
%
%ADD112MACRO112*%
%AMMACRO93*
4,1,28,.00566,-.00492,
.00733,-.00659,
.01122,-.00269,
.011659,-.002174,
.011998,-.001588,
.01223,-.000951,
.012348,-.000284,
.012348,.000393,
.012231,.001061,
.012,.001697,
.011661,.002284,
.011226,.002803,
.01119,.00284,
.00284,.01119,
.002326,.011631,
.001744,.011978,
.00111,.012217,
.000444,.012343,
-.000233,.012352,
-.000902,.012243,
-.001541,.012019,
-.002132,.011688,
-.002656,.011259,
-.00269,.01122,
-.00659,.00733,
-.00492,.00566,
-.0123,-.00172,
-.00172,-.0123,
.00566,-.00492,
0.0*
%
%ADD93MACRO93*%
%ADD84R,.089X.085*%
%AMMACRO62*
4,1,28,-.00492,-.00566,
-.00659,-.00733,
-.00269,-.01122,
-.002174,-.011659,
-.001588,-.011998,
-.000951,-.01223,
-.000284,-.012348,
.000393,-.012348,
.001061,-.012231,
.001697,-.012,
.002284,-.011661,
.002803,-.011226,
.00284,-.01119,
.01119,-.00284,
.011631,-.002326,
.011978,-.001744,
.012217,-.00111,
.012343,-.000444,
.012352,.000233,
.012243,.000902,
.012019,.001541,
.011688,.002132,
.011259,.002656,
.01122,.00269,
.00733,.00659,
.00566,.00492,
-.00172,.0123,
-.0123,.00172,
-.00492,-.00566,
0.0*
%
%ADD62MACRO62*%
%AMMACRO20*
4,1,28,.00052,-.00748,
.00052,-.00984,
.00603,-.00984,
.006705,-.009782,
.007359,-.009607,
.007974,-.009321,
.008529,-.008933,
.009009,-.008455,
.009398,-.0079,
.009685,-.007286,
.009861,-.006632,
.00992,-.005957,
.00992,-.00591,
.00992,.00591,
.009869,.006585,
.009701,.007242,
.009421,.007859,
.009039,.008418,
.008565,.008903,
.008015,.009297,
.007404,.009591,
.006751,.009773,
.006077,.00984,
.00603,.00984,
.00052,.00984,
.00052,.00748,
-.00991,.00748,
-.00991,-.00748,
.00052,-.00748,
0.0*
%
%ADD20MACRO20*%
%AMMACRO16*
4,1,28,.00748,.00052,
.00984,.00052,
.00984,.00603,
.009782,.006705,
.009607,.007359,
.009321,.007974,
.008933,.008529,
.008455,.009009,
.0079,.009398,
.007286,.009685,
.006632,.009861,
.005957,.00992,
.00591,.00992,
-.00591,.00992,
-.006585,.009869,
-.007242,.009701,
-.007859,.009421,
-.008418,.009039,
-.008903,.008565,
-.009297,.008015,
-.009591,.007404,
-.009773,.006751,
-.00984,.006077,
-.00984,.00603,
-.00984,.00052,
-.00748,.00052,
-.00748,-.00991,
.00748,-.00991,
.00748,.00052,
0.0*
%
%ADD16MACRO16*%
%ADD118R,.168X.168*%
%ADD57R,.085X.089*%
%ADD35R,.059X.079*%
%ADD24R,.099X.067*%
%ADD71R,.067X.099*%
%AMMACRO145*
4,1,5,.01673,-.00492,
.01673,.00492,
-.01673,.00492,
-.01673,-.00098,
-.0128,-.00492,
.01673,-.00492,
0.0*
%
%ADD145MACRO145*%
%AMMACRO111*
4,1,28,.00565,.00493,
.00732,.0066,
.01121,.0027,
.011649,.002185,
.011989,.001599,
.012222,.000962,
.01234,.000295,
.012342,-.000382,
.012225,-.001049,
.011994,-.001686,
.011657,-.002273,
.011222,-.002793,
.01119,-.00283,
.00283,-.01119,
.002313,-.011629,
.00173,-.011974,
.001096,-.012212,
.00043,-.012337,
-.000247,-.012344,
-.000915,-.012234,
-.001554,-.012009,
-.002145,-.011677,
-.002668,-.011247,
-.0027,-.01121,
-.0066,-.00732,
-.00493,-.00565,
-.0123,.00173,
-.00173,.0123,
.00565,.00493,
0.0*
%
%ADD111MACRO111*%
%AMMACRO92*
4,1,28,.00493,-.00565,
.0066,-.00732,
.0027,-.01121,
.002185,-.011649,
.001599,-.011989,
.000962,-.012222,
.000295,-.01234,
-.000382,-.012342,
-.001049,-.012225,
-.001686,-.011994,
-.002273,-.011657,
-.002793,-.011222,
-.00283,-.01119,
-.01119,-.00283,
-.011629,-.002313,
-.011974,-.00173,
-.012212,-.001096,
-.012337,-.00043,
-.012344,.000247,
-.012234,.000915,
-.012009,.001554,
-.011677,.002145,
-.011247,.002668,
-.01121,.0027,
-.00732,.0066,
-.00565,.00493,
.00173,.0123,
.0123,.00173,
.00493,-.00565,
0.0*
%
%ADD92MACRO92*%
%AMMACRO66*
4,1,28,-.00565,-.00493,
-.00732,-.0066,
-.01121,-.0027,
-.011649,-.002185,
-.011989,-.001599,
-.012222,-.000962,
-.01234,-.000295,
-.012342,.000382,
-.012225,.001049,
-.011994,.001686,
-.011657,.002273,
-.011222,.002793,
-.01119,.00283,
-.00283,.01119,
-.002313,.011629,
-.00173,.011974,
-.001096,.012212,
-.00043,.012337,
.000247,.012344,
.000915,.012234,
.001554,.012009,
.002145,.011677,
.002668,.011247,
.0027,.01121,
.0066,.00732,
.00493,.00565,
.0123,-.00173,
.00173,-.0123,
-.00565,-.00493,
0.0*
%
%ADD66MACRO66*%
%AMMACRO19*
4,1,28,-.00051,-.00748,
-.00051,-.00984,
-.00602,-.00984,
-.006695,-.009782,
-.007349,-.009607,
-.007964,-.009321,
-.008519,-.008933,
-.008998,-.008455,
-.009388,-.0079,
-.009675,-.007287,
-.009851,-.006632,
-.00991,-.005958,
-.00991,-.00591,
-.00991,.00591,
-.009859,.006585,
-.009691,.007242,
-.009411,.007859,
-.009029,.008418,
-.008555,.008903,
-.008005,.009297,
-.007394,.00959,
-.006742,.009773,
-.006068,.00984,
-.00602,.00984,
-.00051,.00984,
-.00051,.00748,
.00992,.00748,
.00992,-.00748,
-.00051,-.00748,
0.0*
%
%ADD19MACRO19*%
%AMMACRO14*
4,1,28,.00748,-.00051,
.00984,-.00051,
.00984,-.00602,
.009782,-.006695,
.009607,-.007349,
.009321,-.007964,
.008933,-.008519,
.008455,-.008998,
.0079,-.009388,
.007287,-.009675,
.006632,-.009851,
.005958,-.00991,
.00591,-.00991,
-.00591,-.00991,
-.006585,-.009859,
-.007242,-.009691,
-.007859,-.009411,
-.008418,-.009029,
-.008903,-.008555,
-.009297,-.008005,
-.00959,-.007394,
-.009773,-.006742,
-.00984,-.006068,
-.00984,-.00602,
-.00984,-.00051,
-.00748,-.00051,
-.00748,.00992,
.00748,.00992,
.00748,-.00051,
0.0*
%
%ADD14MACRO14*%
%AMMACRO123*
4,1,6,.1063,.04134,
.1063,-.01378,
.03543,-.01378,
.03543,-.04134,
-.1063,-.04134,
-.1063,.04134,
.1063,.04134,
0.0*
%
%ADD123MACRO123*%
%AMMACRO135*
4,1,8,.0246,.01821,
.0246,-.01821,
.01476,-.01821,
.01476,.00837,
-.01477,.00837,
-.01477,-.01821,
-.02461,-.01821,
-.02461,.01821,
.0246,.01821,
0.0*
%
%ADD135MACRO135*%
%AMMACRO21*
4,1,9,.01181,.01476,
-.01771,.01476,
-.01771,.00492,
.00394,.00492,
.00394,-.00492,
-.01771,-.00492,
-.01771,-.01476,
.01772,-.01476,
.01772,.00886,
.01181,.01476,
0.0*
%
%ADD21MACRO21*%
%ADD234C,.006*%
G75*
%LPD*%
G75*
G54D100*
X207354Y200864D03*
X204204D03*
X309716D03*
X306566D03*
X390470Y1516448D03*
X393620D03*
X408928Y200864D03*
X404053Y1516556D03*
X400903D03*
X412078Y200864D03*
X485485Y552726D03*
X488635D03*
X562079Y200864D03*
X558929D03*
X664441D03*
X661291D03*
X869165D03*
X866015D03*
X912085Y323302D03*
Y329602D03*
X915235Y323302D03*
X923902D03*
X920752D03*
X915235Y329602D03*
X923902D03*
X920752D03*
X943787Y336817D03*
X935137D03*
X938287D03*
X943787Y330517D03*
X935137D03*
X938287D03*
X942572Y552726D03*
X945722D03*
X946937Y336817D03*
Y330517D03*
X1399659Y552726D03*
X1402809D03*
G54D200*
X938357Y798194D03*
X943475D03*
X938357Y804886D03*
X943475D03*
G54D101*
X214191Y1429058D03*
Y1432208D03*
Y1429058D03*
Y1425908D03*
X221543Y1428961D03*
Y1432111D03*
Y1428961D03*
Y1425811D03*
X373264Y372604D03*
Y375754D03*
X393620Y1513298D03*
Y1516448D03*
Y1519598D03*
Y1516448D03*
X400903Y1513406D03*
Y1516556D03*
Y1519706D03*
Y1516556D03*
X411487Y1498124D03*
X418839Y1498027D03*
D03*
Y1494877D03*
X411487Y1498124D03*
Y1494974D03*
Y1501274D03*
X418839Y1501177D03*
X872736Y385705D03*
Y388855D03*
X915235Y326452D03*
Y323302D03*
Y326452D03*
X920752D03*
D03*
Y323302D03*
X915235Y329602D03*
X920752D03*
X938287Y333667D03*
Y330517D03*
X943787Y333667D03*
Y330517D03*
X938287Y336817D03*
Y333667D03*
X943787Y336817D03*
Y333667D03*
X1025399Y1316576D03*
Y1313426D03*
X1744524Y372604D03*
Y375754D03*
G54D110*
X356790Y454076D03*
Y456044D03*
Y458012D03*
X364664D03*
Y456044D03*
Y454076D03*
X470758Y472487D03*
Y470519D03*
Y468551D03*
X462884Y472487D03*
Y470519D03*
Y468551D03*
X813876Y452012D03*
Y450044D03*
Y448076D03*
X821750Y452012D03*
Y450044D03*
Y448076D03*
X1270963Y458012D03*
Y456044D03*
Y454076D03*
X1278837Y458012D03*
Y456044D03*
Y454076D03*
X1735924Y458012D03*
Y456044D03*
Y454076D03*
X1728050Y458012D03*
Y456044D03*
Y454076D03*
G54D111*
X361815Y1221308D03*
X818902D03*
X1275988D03*
X1733075D03*
G54D201*
X932117Y806210D03*
Y802470D03*
G54D120*
X412752Y898688D03*
Y921718D03*
G54D102*
X226566Y836900D03*
Y904200D03*
X238062Y826900D03*
Y846900D03*
Y894200D03*
Y914200D03*
X306966Y868900D03*
X307966Y939400D03*
X318462Y858900D03*
Y878900D03*
X319462Y929400D03*
Y949400D03*
X521372Y982854D03*
X532868Y972854D03*
Y992854D03*
X754354Y1417617D03*
X765850Y1407617D03*
Y1427617D03*
X780265Y883294D03*
X781479Y933808D03*
X791761Y873294D03*
Y893294D03*
X792975Y923808D03*
Y943808D03*
X915799Y506429D03*
X927295Y496429D03*
Y516429D03*
X989695Y705383D03*
X1001191Y695383D03*
Y715383D03*
X1287323Y999634D03*
X1298819Y989634D03*
Y1009634D03*
X1404030Y954473D03*
X1392534Y964473D03*
X1404030Y974473D03*
X1430174Y976075D03*
X1441670Y966075D03*
Y986075D03*
X1552266Y980400D03*
X1563762Y970400D03*
Y990400D03*
X1584776Y906608D03*
X1573280Y916608D03*
X1584776Y926608D03*
X1623653Y881353D03*
X1623084Y952120D03*
X1635149Y871353D03*
Y891353D03*
X1634580Y942120D03*
Y962120D03*
G54D210*
X965740Y1359941D03*
Y1414863D03*
G54D112*
X359716Y1223407D03*
X816803D03*
X1273889D03*
X1730976D03*
G54D121*
X410968Y1064305D03*
Y1078675D03*
X434336Y691514D03*
Y705884D03*
X499098Y1064305D03*
Y1078675D03*
X1325142Y1064305D03*
Y1078675D03*
X1413272Y1064305D03*
Y1078675D03*
G54D130*
X422988Y326886D03*
X424563D03*
X421413D03*
X419839D03*
X437161D03*
X435587D03*
X427713D03*
X429287D03*
X430862D03*
X434012D03*
X432437D03*
X426138D03*
X1330298Y329978D03*
X1331872D03*
X1325573D03*
X1333447D03*
X1335022D03*
X1328723D03*
X1327148D03*
X1323998D03*
X1322424D03*
X1339746D03*
X1338172D03*
X1336597D03*
G54D103*
X294959Y19408D03*
Y14408D03*
Y29408D03*
Y24408D03*
X315825Y14408D03*
Y19408D03*
Y29408D03*
Y24408D03*
X1462675Y17645D03*
Y32645D03*
Y27645D03*
Y22645D03*
X1483541Y17645D03*
Y32645D03*
Y22645D03*
Y27645D03*
G54D211*
X958771Y1367717D03*
Y1383465D03*
Y1379528D03*
Y1375591D03*
Y1371654D03*
Y1399213D03*
Y1395276D03*
Y1391339D03*
Y1387402D03*
Y1407087D03*
Y1403150D03*
X972709Y1381496D03*
Y1377559D03*
Y1373622D03*
Y1369685D03*
Y1397245D03*
Y1393308D03*
Y1389370D03*
Y1385434D03*
Y1405119D03*
Y1401182D03*
G54D202*
X943716Y861015D03*
Y857865D03*
G54D220*
X1030635Y754546D03*
Y764546D03*
Y774546D03*
Y784546D03*
Y794546D03*
Y804546D03*
Y814546D03*
G54D10*
X6385Y997697D03*
X22792Y997712D03*
X16647Y997670D03*
X11449Y997669D03*
X16463Y1536219D03*
X16080Y1541684D03*
X21080Y1543113D03*
X34987Y997724D03*
X29275Y997737D03*
X24074Y1496519D03*
X26017Y1543931D03*
X36364Y1544384D03*
X31221Y1544634D03*
X31105Y1549755D03*
X50285Y172879D03*
X51946Y997678D03*
X46108Y997664D03*
X40334Y997805D03*
X46818Y1544660D03*
X52264Y1545189D03*
X41522Y1545112D03*
X68448Y997793D03*
X62211Y997892D03*
X57214Y997884D03*
X57598Y1544760D03*
X61611Y1539765D03*
X77688Y847363D03*
X97033Y679427D03*
X111733Y154865D03*
X158929Y382600D03*
X159020Y465177D03*
X159044Y552674D03*
X158982Y564371D03*
Y559371D03*
X158198Y596321D03*
X159020Y591388D03*
X158220Y606190D03*
X159042Y601257D03*
X159046Y621005D03*
X159049Y611126D03*
X158242Y616069D03*
X158555Y637979D03*
X159023Y630886D03*
X158219Y625950D03*
X214095Y154865D03*
X213594Y462800D03*
X213662Y549469D03*
X213797Y554598D03*
X214000Y619500D03*
Y625400D03*
X241825Y380718D03*
X246141Y387884D03*
X244960Y393858D03*
X242398Y404718D03*
X242561Y412718D03*
X243278Y628696D03*
X248984Y628670D03*
X249867Y645941D03*
X243078Y645900D03*
X253186Y391496D03*
X252004Y384718D03*
X251601Y408718D03*
X252819Y400718D03*
X256091Y542712D03*
X256120Y620788D03*
X280600Y894200D03*
X279500Y904200D03*
X294841Y317911D03*
X286784Y858900D03*
X287471Y868900D03*
X288580Y929400D03*
X288084Y939400D03*
X310665Y540335D03*
X310756Y622912D03*
X316457Y154865D03*
X345631Y1174897D03*
X342399Y1198783D03*
X344444Y1211312D03*
X383900Y744100D03*
X384600Y750005D03*
X382607Y764500D03*
X386500Y782100D03*
X383200Y790225D03*
X411800Y790900D03*
X408967Y854329D03*
X416200Y786700D03*
X420400Y790700D03*
X423104Y892213D03*
X431600Y777564D03*
X466458Y154865D03*
X472148Y996052D03*
X477248D03*
X471443Y1001144D03*
X477248Y1001052D03*
X467878Y1042357D03*
X461897Y1041794D03*
X486623Y655447D03*
X491006Y1000497D03*
X484497Y1001466D03*
X491647Y1011963D03*
X492042Y1020491D03*
X491210Y1027453D03*
X499263Y665627D03*
X508833Y765565D03*
X495574Y1004176D03*
X495663Y1015420D03*
X497073Y1026059D03*
X501422Y1037680D03*
X526210Y768013D03*
X518782Y754155D03*
X556334Y755432D03*
X568820Y154865D03*
X567445Y738419D03*
X575295Y743494D03*
X579444Y784955D03*
X584200Y790791D03*
X596871Y949646D03*
X616015Y382600D03*
X616106Y465177D03*
X616130Y552674D03*
X616068Y564371D03*
Y559371D03*
X616128Y601257D03*
X616106Y591388D03*
X615306Y606190D03*
X615284Y596321D03*
X616132Y621005D03*
X616135Y611126D03*
X615328Y616069D03*
X615641Y637979D03*
X615305Y625950D03*
X616109Y630886D03*
X610562Y648262D03*
X651602Y704366D03*
X671182Y154865D03*
X670680Y462800D03*
X670748Y549469D03*
X670770Y554598D03*
X671086Y619500D03*
Y625400D03*
X664168Y684077D03*
X661346Y763137D03*
X661846Y779137D03*
X661346Y771137D03*
Y787137D03*
X674416Y689694D03*
X674846Y763137D03*
X675346Y779137D03*
X674846Y771137D03*
Y787137D03*
X702046Y393858D03*
X700364Y628696D03*
X700164Y645900D03*
X699272Y707772D03*
X708305Y387884D03*
X709905Y400718D03*
X713206Y620788D03*
X706070Y628670D03*
X706953Y645941D03*
X711738Y691609D03*
X713401Y709949D03*
X721141Y730734D03*
X715607Y747977D03*
X716346Y760137D03*
X719846Y764137D03*
X716346Y768637D03*
X719846Y756137D03*
Y772637D03*
X724994Y690625D03*
X726897Y750559D03*
X751927Y317911D03*
X740530Y1524113D03*
X744188Y1624699D03*
X768460Y448957D03*
X767751Y540335D03*
X767842Y622912D03*
X754862Y1592302D03*
X753985Y1620898D03*
X773544Y154865D03*
X776094Y441165D03*
X774099Y446595D03*
X770545Y900475D03*
X802291Y1211461D03*
X795411Y1212399D03*
X790361Y1447895D03*
X790754Y1441399D03*
X790296Y1463459D03*
X787038Y1460533D03*
X790989Y1455695D03*
X787885Y1631364D03*
X813635Y762000D03*
X811279Y869693D03*
X809500Y887500D03*
X810500Y900000D03*
X802606Y1175026D03*
X825977Y327207D03*
X819977Y317368D03*
Y324648D03*
X820196Y332149D03*
X834282Y536085D03*
X827284Y721262D03*
X829484Y903759D03*
X826204Y1444689D03*
X826219Y1455244D03*
X830400Y1473900D03*
X843284Y721262D03*
X836284Y721273D03*
X850377Y1443959D03*
X850744Y1461959D03*
X847600Y1474100D03*
X865331Y717919D03*
X852284Y721273D03*
X865012Y727387D03*
X865567Y849885D03*
X861832Y846197D03*
X864760Y840928D03*
X861599Y836900D03*
X867179Y855265D03*
X861663Y853141D03*
X862776Y862467D03*
X863726Y872719D03*
X863091Y867659D03*
X863792Y877798D03*
X852774Y1001027D03*
X860514Y1000691D03*
X859900Y1008686D03*
X880138Y549603D03*
X879449Y568863D03*
X877339Y574408D03*
X879449Y562703D03*
X879055Y582828D03*
X875887Y682223D03*
X881836Y682219D03*
X869970Y704561D03*
X882765Y713846D03*
X879190Y821364D03*
X867858Y845174D03*
X867876Y836956D03*
X868123Y865298D03*
Y860298D03*
Y875298D03*
Y870298D03*
Y880298D03*
Y885298D03*
X879147Y896530D03*
X879664Y901568D03*
X874002Y1009399D03*
X868934Y1009274D03*
X879086Y1009110D03*
X878954Y1446432D03*
X878245Y1465859D03*
X875800Y1478600D03*
X878244Y1471359D03*
X889414Y544911D03*
X887939Y558338D03*
X893536Y558394D03*
X897689Y544660D03*
X891527Y728033D03*
X896161Y824930D03*
X889190Y821364D03*
X884190D03*
X899190Y821269D03*
X886664Y825717D03*
X894154Y896438D03*
X899103Y899321D03*
X889154Y896438D03*
X884154D03*
X896654Y903807D03*
X891654Y900773D03*
X886654D03*
X884110Y1009264D03*
X889202Y1009184D03*
X899313Y1009197D03*
X894225Y1009250D03*
X892616Y1446517D03*
X892101Y1467602D03*
X893200Y1478600D03*
X905114Y551773D03*
X903710Y544382D03*
X902236Y689332D03*
Y694332D03*
X906457Y723731D03*
X901226Y796828D03*
X904940Y821364D03*
X908378Y825308D03*
X901690Y825699D03*
X904154Y896438D03*
X914154D03*
X909154D03*
X901654Y903844D03*
X911654Y900773D03*
X906654D03*
X911352Y1012137D03*
X904484Y1011004D03*
X923544Y154865D03*
X920544Y570607D03*
X920870Y575763D03*
X919328Y685622D03*
X928672Y703241D03*
X929822Y709770D03*
X927662Y821009D03*
X925302Y825658D03*
X922431Y821308D03*
X924154Y896438D03*
X919154D03*
X916654Y900773D03*
X921654D03*
X926654D03*
X918503Y1009401D03*
X929069Y1009103D03*
X923576Y1009292D03*
X931159Y1379427D03*
X920360Y1387039D03*
X931199Y1371951D03*
X931159Y1390827D03*
Y1406027D03*
X920235Y1443493D03*
X921629Y1463235D03*
X921653Y1476971D03*
X937567Y306013D03*
X938858Y844582D03*
X938820Y836863D03*
X938984Y849888D03*
X939000Y863474D03*
X939042Y854928D03*
X945100Y852400D03*
X946482Y869624D03*
X939309Y879021D03*
X939269Y868921D03*
X938729Y874396D03*
X934525Y1009346D03*
X939966Y1009184D03*
X945166Y1009189D03*
X939559Y1398427D03*
X953692Y696577D03*
X955576Y1009333D03*
X960845Y1008941D03*
X950389Y1009350D03*
X972792Y710988D03*
X966466Y1009238D03*
X971798Y1009319D03*
X980018Y1009991D03*
X988192Y327561D03*
X994830Y326789D03*
X988045Y355812D03*
X1001443Y357523D03*
X1011862Y354276D03*
X1005814Y1351584D03*
X1025906Y154865D03*
X1025418Y310476D03*
X1018820Y311772D03*
X1013664Y311359D03*
X1025885Y352848D03*
X1021406Y1323530D03*
X1019109Y1353132D03*
X1024316Y1358339D03*
X1019330Y1380797D03*
X1041496Y311094D03*
X1030418Y310476D03*
X1045939Y332533D03*
X1037934Y847222D03*
X1029913Y853842D03*
X1038432Y946661D03*
X1034196Y1309624D03*
X1038996Y1376272D03*
X1050632Y314539D03*
X1047063Y361176D03*
X1053358Y826499D03*
X1049174Y1315612D03*
X1062053Y1437930D03*
X1053194Y1456493D03*
X1073102Y382600D03*
X1073193Y465177D03*
X1073217Y552674D03*
X1073155Y564371D03*
Y559371D03*
X1073215Y601257D03*
X1072371Y596321D03*
X1073193Y591388D03*
X1072393Y606190D03*
X1072415Y616069D03*
X1073222Y611126D03*
X1073219Y621005D03*
X1072728Y637979D03*
X1072392Y625950D03*
X1073196Y630886D03*
X1109113Y706901D03*
X1122228Y683055D03*
X1128268Y154865D03*
X1138571Y329148D03*
X1127767Y462800D03*
X1127857Y554598D03*
X1127835Y549469D03*
X1128173Y619500D03*
Y625400D03*
X1133869Y648421D03*
X1130970Y689694D03*
X1155998Y380718D03*
X1159133Y393858D03*
X1156571Y404718D03*
X1156734Y412718D03*
X1157451Y628696D03*
X1157251Y645900D03*
X1152485Y775642D03*
X1156485Y779142D03*
X1159485Y834142D03*
Y820642D03*
X1169668Y373503D03*
X1166177Y384718D03*
X1167359Y391496D03*
X1160314Y387884D03*
X1165774Y408718D03*
X1166992Y400718D03*
X1170264Y542712D03*
X1170293Y620788D03*
X1163157Y628670D03*
X1164040Y645941D03*
X1168985Y775642D03*
X1164985Y779142D03*
X1160485Y775642D03*
X1175485Y833642D03*
X1167485Y834142D03*
Y820642D03*
X1175485Y820142D03*
X1181155Y329703D03*
X1180312Y319267D03*
X1183485Y834142D03*
Y820642D03*
X1209014Y317911D03*
X1230630Y154865D03*
X1224838Y540335D03*
X1224929Y622912D03*
X1256938Y894863D03*
X1252381Y1207061D03*
X1268457Y864487D03*
Y854487D03*
Y859487D03*
Y879487D03*
Y869487D03*
Y874487D03*
Y889487D03*
Y884487D03*
X1261622Y907067D03*
X1259802Y1174426D03*
X1257411Y1211284D03*
X1272351Y1230750D03*
X1282055Y857317D03*
X1279822Y968916D03*
X1296770Y828775D03*
X1299990Y847500D03*
X1295943Y855500D03*
X1299855Y862312D03*
X1299488Y868440D03*
X1295758Y877783D03*
X1301482Y881783D03*
X1301314Y873484D03*
X1301379Y889783D03*
X1295799Y885783D03*
X1318063Y359511D03*
X1317000Y817500D03*
X1321000Y814200D03*
X1313000D03*
X1325007Y360259D03*
X1334071Y757675D03*
X1334340Y768876D03*
X1325000Y817500D03*
X1333000D03*
X1337000Y814200D03*
X1329000D03*
X1322500Y915300D03*
X1334500Y911643D03*
X1326500Y911500D03*
X1338500Y915300D03*
X1330500D03*
X1345000Y814200D03*
X1353000D03*
X1349000Y817500D03*
X1341000D03*
X1344500Y911500D03*
X1351380Y915164D03*
X1349566Y1102794D03*
X1365000Y817500D03*
X1368381Y814312D03*
X1357000Y817500D03*
X1361000Y814200D03*
X1368000Y911500D03*
X1364500Y915300D03*
X1361000Y911500D03*
X1356500Y915000D03*
X1380631Y154865D03*
X1380544Y815248D03*
X1371604Y817398D03*
X1384090Y817377D03*
X1375600Y814702D03*
X1382000Y911500D03*
X1371500Y915300D03*
X1378500D03*
X1375000Y911500D03*
X1386322Y996052D03*
X1385617Y1001144D03*
X1376071Y1041794D03*
X1382052Y1042357D03*
X1401583Y832491D03*
X1395998Y837744D03*
X1397000Y850343D03*
X1402500Y856000D03*
X1398909Y872000D03*
X1391422Y996052D03*
X1398671Y1001466D03*
X1391422Y1001052D03*
X1405180Y1000497D03*
X1405821Y1011963D03*
X1409748Y1004176D03*
X1406216Y1020491D03*
X1410397Y1027097D03*
X1405384Y1027452D03*
X1409837Y1015420D03*
X1415596Y1037680D03*
X1416396Y1538143D03*
X1416319Y1543379D03*
X1415241Y1556416D03*
X1415962Y1564320D03*
X1432806Y947059D03*
X1428212Y933016D03*
X1432818Y941439D03*
X1421560Y1511532D03*
X1431788Y1503314D03*
X1426593Y1503302D03*
X1424573Y1548351D03*
X1423817Y1569486D03*
X1443428Y1029000D03*
X1436448Y1549610D03*
X1444598Y1566170D03*
X1461585Y939543D03*
X1461441Y944864D03*
X1456669Y933701D03*
X1482993Y154865D03*
X1530189Y382600D03*
X1530280Y465177D03*
X1530304Y552674D03*
X1530242Y559371D03*
Y564371D03*
X1529458Y596321D03*
X1530302Y601257D03*
X1530280Y591388D03*
X1529480Y606190D03*
X1530309Y611126D03*
X1529502Y616069D03*
X1530306Y621005D03*
X1530283Y630886D03*
X1529815Y637979D03*
X1529479Y625950D03*
X1535221Y971822D03*
X1562810Y954054D03*
X1578448Y683787D03*
X1566655Y707314D03*
X1585355Y154865D03*
X1584854Y462800D03*
X1584944Y554598D03*
X1584922Y549469D03*
X1585260Y619500D03*
Y625400D03*
X1586978Y652399D03*
X1590707Y1451470D03*
X1587746Y1465452D03*
X1613085Y380718D03*
X1613658Y404718D03*
X1613821Y412718D03*
X1614538Y628696D03*
X1614338Y645900D03*
X1608750Y788150D03*
X1603251Y797012D03*
X1609400Y803800D03*
X1609800Y817300D03*
X1602595Y802852D03*
X1603966Y816799D03*
X1602862Y829738D03*
X1611522Y1540314D03*
X1617925Y370700D03*
X1616220Y393858D03*
X1624446Y391496D03*
X1617401Y387884D03*
X1623264Y384718D03*
X1622861Y408718D03*
X1624079Y400718D03*
X1627351Y542712D03*
X1627380Y620788D03*
X1620244Y628670D03*
X1621127Y645941D03*
X1621111Y687047D03*
X1620600Y699930D03*
X1620500Y717830D03*
X1621200Y732430D03*
X1621700Y750630D03*
X1616655Y769300D03*
X1629500Y782300D03*
X1629700Y795700D03*
X1628400Y809400D03*
X1625500Y826900D03*
X1639300Y708900D03*
X1640100Y723200D03*
X1635300Y743400D03*
X1634541Y761759D03*
X1666101Y317911D03*
X1687717Y154865D03*
X1681925Y540335D03*
X1682016Y622912D03*
X1716700Y1174526D03*
X1729553Y1230788D03*
X1757879Y879213D03*
X1757933Y897260D03*
X1757914Y884667D03*
X1757805Y913336D03*
X1757275Y926200D03*
X1756060Y1010750D03*
X1761745Y1010616D03*
X1773278Y1010643D03*
X1767133Y1010601D03*
X1782357Y919151D03*
X1789774Y918954D03*
X1790820Y1010736D03*
X1779761Y1010668D03*
X1785473Y1010655D03*
X1782088Y1430956D03*
X1786936Y1467917D03*
X1804600Y910175D03*
X1795764Y918695D03*
X1796594Y1010595D03*
X1807688Y1010616D03*
X1802432Y1010609D03*
X1795100Y1463678D03*
X1795147Y1478147D03*
X1814900Y907025D03*
X1813114Y973235D03*
X1818934Y1010724D03*
X1812697D03*
X1903466Y2079348D03*
X1915566D03*
X1927666Y2067248D03*
Y2079348D03*
X1949818Y2056098D03*
X1939605Y2057393D03*
G54D20*
X9272Y105001D03*
X16773Y242078D03*
X12803Y248371D03*
X16773Y262078D03*
X12803Y268371D03*
X12173Y1496782D03*
X9515Y1556883D03*
X25879Y51296D03*
Y55305D03*
X29787Y67527D03*
Y63527D03*
Y59527D03*
X27897Y106495D03*
X32415Y177448D03*
X24581Y206864D03*
X23752Y242078D03*
Y262078D03*
X33414Y250599D03*
Y270599D03*
X26537Y292608D03*
X34753Y281272D03*
X31457Y536726D03*
Y531726D03*
Y552726D03*
Y540726D03*
Y544726D03*
X33175Y629311D03*
Y625311D03*
X48384Y177606D03*
X41288Y478982D03*
Y483982D03*
Y487982D03*
Y499982D03*
Y491982D03*
X43582Y597393D03*
X50237Y631212D03*
X43674Y1093757D03*
X42510Y1248448D03*
X59232Y847718D03*
X53207Y1072761D03*
X67567Y1091656D03*
X61268Y1213720D03*
X65386Y1544571D03*
X77258Y151540D03*
X80717Y168697D03*
X80912Y191941D03*
X82881Y224321D03*
X83259Y571614D03*
Y575614D03*
X72002Y575841D03*
X81797Y686107D03*
X71718Y843118D03*
X97869Y149768D03*
X104805Y192665D03*
Y196665D03*
X104900Y204864D03*
X115165Y252371D03*
X130268Y106495D03*
X126943Y206864D03*
X119135Y242078D03*
X126114D03*
X135776Y250599D03*
X147171Y554555D03*
Y558555D03*
Y562555D03*
X154083Y382600D03*
Y463600D03*
X153451Y595588D03*
Y591588D03*
X153483Y603600D03*
X153451Y599588D03*
X153483Y611600D03*
Y619600D03*
X153451Y607588D03*
X153483Y615600D03*
Y623600D03*
Y627600D03*
Y637969D03*
Y641974D03*
X179620Y151540D03*
X196981Y68581D03*
Y80581D03*
X183079Y168697D03*
X183274Y191941D03*
X185243Y224321D03*
X206306Y58013D03*
X202524Y114488D03*
X200231Y149768D03*
X207167Y196665D03*
Y192665D03*
X207262Y204864D03*
X229305Y206864D03*
X221497Y242078D03*
X228476D03*
X217527Y252371D03*
X221283Y458800D03*
X230083Y553700D03*
X221483Y545800D03*
X230083Y557700D03*
X230527Y1474522D03*
X230526Y1478442D03*
Y1486442D03*
X232621Y106495D03*
X238138Y250599D03*
X233747Y384718D03*
Y380718D03*
Y392718D03*
Y396718D03*
Y400718D03*
Y404718D03*
Y408718D03*
Y412718D03*
X244908Y675832D03*
X232526Y1510442D03*
X232531Y1518578D03*
X252183Y453873D03*
Y458859D03*
X251368Y542712D03*
X249369Y816300D03*
X248369Y836800D03*
X249368Y1506058D03*
X251668Y1517958D03*
X281982Y151540D03*
X285441Y168697D03*
X285636Y191941D03*
X287605Y224321D03*
X312164Y35007D03*
X308668Y58013D03*
X299343Y68581D03*
Y80581D03*
X304886Y114488D03*
X302593Y149768D03*
X309529Y192665D03*
Y196665D03*
X309624Y204864D03*
X323859Y242078D03*
X319889Y252371D03*
X326940Y306652D03*
X318568Y545912D03*
Y626912D03*
X334983Y106495D03*
X331667Y206864D03*
X330838Y242078D03*
X340500Y250599D03*
X350508Y458334D03*
Y450334D03*
X346908Y1146071D03*
X360881Y1170370D03*
X354250Y1191599D03*
X371383Y488816D03*
X377369Y764500D03*
X366951Y943480D03*
X375915Y959812D03*
Y955812D03*
Y951812D03*
Y963812D03*
Y967812D03*
Y971812D03*
X387803Y168697D03*
X387998Y191941D03*
X389967Y224321D03*
X391151Y470382D03*
X379069Y745300D03*
X392678Y868286D03*
X387500Y1547700D03*
Y1555700D03*
X407248Y114488D03*
X407039Y331589D03*
Y335589D03*
X402784Y467560D03*
Y479560D03*
X405871Y889786D03*
X407448Y1446807D03*
X419958Y35983D03*
X411891Y192665D03*
Y196665D03*
X411986Y204864D03*
X418616Y425413D03*
X421156Y455301D03*
Y459101D03*
Y463101D03*
X424784Y474560D03*
X414272Y889551D03*
X413684Y1523296D03*
X431983Y151540D03*
X427099Y1537088D03*
X427619Y1550211D03*
X452594Y149768D03*
X455642Y328285D03*
Y324685D03*
Y344033D03*
Y340433D03*
Y336159D03*
Y332559D03*
Y351907D03*
Y348307D03*
X443656Y424601D03*
Y428101D03*
Y431601D03*
X456602Y464809D03*
Y472809D03*
X445923Y508999D03*
X453460Y638279D03*
X456768Y1012325D03*
Y1016325D03*
X448574Y1022766D03*
Y1034266D03*
Y1030266D03*
X455652Y1043140D03*
X455575Y1047047D03*
X473860Y242078D03*
X469890Y252371D03*
X465886Y495669D03*
Y516609D03*
X459268Y1002180D03*
Y1007180D03*
X484984Y106495D03*
X481668Y206864D03*
X480839Y242078D03*
X490501Y250599D03*
X488393Y387089D03*
Y391589D03*
X488543Y536726D03*
Y531726D03*
Y544726D03*
Y540726D03*
X490261Y629311D03*
Y625311D03*
X481845Y652906D03*
X485268Y1031680D03*
X498374Y478982D03*
Y483982D03*
Y487982D03*
Y499982D03*
Y491982D03*
X500668Y597393D03*
X507323Y631212D03*
X502586Y660441D03*
X504074Y1004766D03*
Y996766D03*
Y1008766D03*
X503941Y1020258D03*
X504074Y1030766D03*
X494268Y1032180D03*
X518690Y749443D03*
X508077Y989235D03*
X512074Y1000766D03*
Y1004766D03*
Y996766D03*
Y1016266D03*
Y1020266D03*
Y1030766D03*
X534345Y151540D03*
X537804Y168697D03*
X537999Y191941D03*
X539968Y224321D03*
X538669Y345723D03*
Y359223D03*
Y354723D03*
Y350223D03*
Y363723D03*
Y377223D03*
Y372723D03*
Y368223D03*
Y386223D03*
Y390723D03*
X529088Y575841D03*
X535507Y779889D03*
X532169Y840700D03*
X551706Y68581D03*
Y80581D03*
X554956Y149768D03*
X548669Y345723D03*
Y350223D03*
Y359223D03*
Y354723D03*
Y377223D03*
Y372723D03*
Y368223D03*
Y363723D03*
Y381723D03*
X540345Y571614D03*
Y575614D03*
X552956Y684509D03*
Y700509D03*
Y688509D03*
Y692509D03*
Y696509D03*
Y704509D03*
Y708509D03*
Y712509D03*
Y716509D03*
Y720509D03*
X555609Y841388D03*
X561031Y58013D03*
X557249Y114488D03*
X561892Y192665D03*
Y196665D03*
X561987Y204864D03*
X572252Y252371D03*
X570486Y747079D03*
X587346Y106495D03*
X584030Y206864D03*
X583201Y242078D03*
X576222D03*
X588772Y957207D03*
X576286Y961807D03*
X588415Y1509687D03*
X592863Y250599D03*
X604257Y554555D03*
Y558555D03*
Y562555D03*
X597968Y1493658D03*
Y1497558D03*
X598068Y1501458D03*
X594164Y1505794D03*
X611169Y382600D03*
Y463600D03*
X610537Y595588D03*
Y591588D03*
X610569Y603600D03*
X610537Y599588D03*
X610569Y611600D03*
Y619600D03*
X610537Y607588D03*
X610569Y615600D03*
Y623600D03*
Y627600D03*
Y637969D03*
Y641974D03*
X636707Y151540D03*
X640166Y168697D03*
X640361Y191941D03*
X642330Y224321D03*
X663393Y58013D03*
X654068Y68581D03*
Y80581D03*
X659611Y114488D03*
X657318Y149768D03*
X664254Y192665D03*
Y196665D03*
X664349Y204864D03*
X658810Y666275D03*
X660926Y710129D03*
X678584Y242078D03*
X685563D03*
X674614Y252371D03*
X678369Y458800D03*
X678569Y545800D03*
Y558800D03*
Y562800D03*
X689708Y106495D03*
X686392Y206864D03*
X695225Y250599D03*
X690833Y384718D03*
Y380718D03*
Y392718D03*
Y396718D03*
Y400718D03*
Y404718D03*
Y408718D03*
Y412718D03*
X687169Y553700D03*
Y557700D03*
X701994Y675832D03*
X709269Y453873D03*
Y458859D03*
X708454Y542712D03*
X716258Y696718D03*
X713333Y783453D03*
X727829Y756137D03*
Y764137D03*
X720179Y779958D03*
X727829Y768137D03*
Y772137D03*
X739069Y151540D03*
X742528Y168697D03*
X742723Y191941D03*
X744692Y224321D03*
X735883Y1606600D03*
X735234Y1634485D03*
X735250Y1630030D03*
X765755Y58013D03*
X756430Y68581D03*
Y80581D03*
X761973Y114488D03*
X759680Y149768D03*
X766616Y196665D03*
Y192665D03*
X766711Y204864D03*
X780946Y242078D03*
X776976Y252371D03*
X775654Y545912D03*
Y626912D03*
X783232Y1427432D03*
Y1431432D03*
Y1439432D03*
X781486Y1458066D03*
X774615Y1449870D03*
X792070Y106495D03*
X788754Y206864D03*
X787925Y242078D03*
X797587Y250599D03*
X784026Y306652D03*
X784575Y442498D03*
X784607Y450510D03*
Y446510D03*
X799327Y1436559D03*
X807594Y444334D03*
Y452334D03*
X811807Y836919D03*
X815307Y893419D03*
X803995Y1146071D03*
X806327Y1436559D03*
X807988Y1476616D03*
X828469Y483816D03*
X829983Y758500D03*
Y762500D03*
Y780500D03*
Y776500D03*
Y794500D03*
Y798500D03*
Y812500D03*
Y816500D03*
X822217Y830038D03*
X819807Y900919D03*
X817925Y1171120D03*
X844890Y168697D03*
X845085Y191941D03*
X847054Y224321D03*
X848237Y465382D03*
X845768Y831558D03*
X839299Y839953D03*
X845840Y839292D03*
X842941Y879459D03*
X845728Y875507D03*
X843251Y871459D03*
X842941Y883459D03*
X844161Y892564D03*
X842848Y887490D03*
X837983Y901500D03*
X845214Y1440859D03*
X834187Y1444849D03*
X845227Y1448959D03*
Y1444959D03*
Y1457959D03*
X858792Y68581D03*
Y80581D03*
X864335Y114488D03*
X863744Y713170D03*
Y705170D03*
X864483Y768000D03*
Y786000D03*
Y804000D03*
Y822000D03*
X856711Y831469D03*
X856742Y843459D03*
Y847459D03*
Y839459D03*
Y863459D03*
Y859459D03*
Y855459D03*
Y851459D03*
Y867459D03*
Y879459D03*
Y875459D03*
Y871459D03*
Y892959D03*
Y883459D03*
Y887759D03*
X868117Y58013D03*
X868978Y192665D03*
Y196665D03*
X869073Y204864D03*
X875567Y337342D03*
X866937Y491303D03*
Y479303D03*
X872551Y554703D03*
Y558703D03*
Y574703D03*
Y586828D03*
X871977Y698388D03*
X889069Y151540D03*
X883460Y309368D03*
Y305368D03*
Y313368D03*
Y325368D03*
Y321368D03*
Y317368D03*
Y329368D03*
Y337342D03*
Y333368D03*
X888937Y486303D03*
X895483Y529633D03*
X881744Y686970D03*
Y698970D03*
X886744Y718570D03*
X890364Y1102760D03*
X886200Y1257451D03*
X886727Y1440859D03*
Y1448859D03*
Y1464859D03*
X886702Y1452663D03*
X886727Y1472859D03*
X909680Y149768D03*
X902243Y362369D03*
Y370369D03*
X913636Y547348D03*
X909944Y683770D03*
Y695770D03*
Y699770D03*
X899897Y1081764D03*
X904958Y1222723D03*
X919828Y304585D03*
X913942Y441754D03*
X916482Y471642D03*
Y479442D03*
Y475442D03*
X929135Y561578D03*
Y565578D03*
X929119Y585578D03*
Y589578D03*
X929135Y594329D03*
Y598329D03*
X923933Y704111D03*
X914257Y1104659D03*
Y1100659D03*
X924711Y1472100D03*
X942070Y106495D03*
X939420Y192035D03*
X945626Y236866D03*
X930635Y305255D03*
X941660Y351281D03*
X938982Y440942D03*
Y444442D03*
Y447942D03*
X945630Y536726D03*
Y531726D03*
Y544726D03*
Y540726D03*
X939353Y883790D03*
X939355Y887508D03*
X947572Y316739D03*
X955461Y478982D03*
Y483982D03*
Y487982D03*
Y499982D03*
Y491982D03*
X957755Y597393D03*
X947348Y629311D03*
Y625311D03*
X952667Y792505D03*
X957540Y846665D03*
X950626Y846635D03*
X947753Y878216D03*
X956181Y870278D03*
X947897Y899890D03*
X954341Y1102760D03*
X950177Y1257451D03*
X964410Y631212D03*
X963874Y1081764D03*
X978234Y1100659D03*
Y1104659D03*
X968935Y1222723D03*
X991431Y151540D03*
X982608Y338972D03*
X981089Y343112D03*
X982608Y331972D03*
X981089Y346612D03*
X986175Y575841D03*
X982604Y848597D03*
X984686Y837159D03*
X986918Y1104622D03*
X986955Y1100302D03*
X1008792Y68581D03*
Y80581D03*
X994890Y168697D03*
X995085Y191941D03*
X997054Y224321D03*
X997432Y571614D03*
Y575614D03*
X1018117Y58013D03*
X1014335Y114488D03*
X1012042Y149768D03*
X1018978Y196665D03*
Y192665D03*
X1011654Y196620D03*
X1019073Y204864D03*
X1018186Y837659D03*
X1017902Y958822D03*
X1013991Y1353714D03*
X1013944Y1363533D03*
X1013966Y1372734D03*
X1013961Y1376752D03*
X1041116Y206864D03*
X1033308Y242078D03*
X1040287D03*
X1029338Y252371D03*
X1032971Y847222D03*
X1030388Y954222D03*
X1044432Y106495D03*
X1049949Y250599D03*
X1058708Y314539D03*
Y322843D03*
Y328156D03*
Y319243D03*
X1058595Y339509D03*
X1058708Y331756D03*
X1058187Y360151D03*
Y364276D03*
X1068256Y382600D03*
Y463600D03*
X1061344Y554555D03*
Y558555D03*
Y562555D03*
X1067624Y595588D03*
Y591588D03*
X1067656Y603600D03*
X1067624Y599588D03*
X1067656Y611600D03*
Y619600D03*
X1067624Y607588D03*
X1067656Y615600D03*
Y623600D03*
Y627600D03*
Y637969D03*
Y641974D03*
X1093793Y151540D03*
X1097252Y168697D03*
X1097447Y191941D03*
X1099416Y224321D03*
X1120479Y58013D03*
X1111154Y68581D03*
Y80581D03*
X1116697Y114488D03*
X1114404Y149768D03*
X1112961Y168713D03*
X1121340Y192665D03*
Y196665D03*
X1121435Y204864D03*
X1120483Y329000D03*
Y334000D03*
Y339000D03*
X1115897Y666275D03*
X1118013Y710129D03*
X1135670Y242078D03*
X1131700Y252371D03*
X1128983Y329000D03*
Y334000D03*
Y339000D03*
X1135456Y458800D03*
X1135656Y545800D03*
Y558800D03*
Y562800D03*
X1146794Y106495D03*
X1143478Y206864D03*
X1142649Y242078D03*
X1152311Y250599D03*
X1147920Y392718D03*
Y384718D03*
Y380718D03*
Y404718D03*
Y408718D03*
Y396718D03*
Y400718D03*
Y412718D03*
X1144256Y553700D03*
Y557700D03*
X1166356Y453873D03*
Y458859D03*
X1165541Y542712D03*
X1159081Y675832D03*
X1187067Y324142D03*
X1177653Y774434D03*
X1196155Y151540D03*
X1199614Y168697D03*
X1199809Y191941D03*
X1201778Y224321D03*
X1191947Y329398D03*
X1213516Y68581D03*
Y80581D03*
X1219059Y114488D03*
X1216766Y149768D03*
X1215323Y168713D03*
X1222841Y58013D03*
X1223702Y192665D03*
Y196665D03*
X1223797Y204864D03*
X1238032Y242078D03*
X1234062Y252371D03*
X1232741Y545912D03*
Y626912D03*
X1249156Y106495D03*
X1245840Y206864D03*
X1245011Y242078D03*
X1254673Y250599D03*
X1241113Y306652D03*
X1260983Y336000D03*
X1264681Y450334D03*
Y458334D03*
X1264677Y894866D03*
X1261081Y1146071D03*
X1255923Y1192376D03*
X1260168Y1523458D03*
X1260129Y1527334D03*
X1260168Y1543558D03*
X1260129Y1531334D03*
Y1539334D03*
X1260153Y1535385D03*
X1285556Y488816D03*
X1284997Y768576D03*
Y780576D03*
X1276654Y848145D03*
X1276750Y864487D03*
Y859487D03*
X1276738Y852029D03*
X1276750Y874487D03*
Y869487D03*
Y879487D03*
Y889487D03*
Y884487D03*
X1286983Y919500D03*
X1283359Y933598D03*
X1275011Y1171120D03*
X1301976Y168697D03*
X1302171Y191941D03*
X1298483Y326500D03*
Y337000D03*
Y330000D03*
Y333500D03*
X1290983Y819500D03*
Y839500D03*
Y843500D03*
Y847500D03*
Y851500D03*
Y863500D03*
Y867000D03*
X1290978Y885783D03*
X1317685Y168713D03*
X1304140Y224321D03*
X1305324Y470382D03*
X1316957Y467560D03*
Y479560D03*
X1303983Y942500D03*
X1334131Y35983D03*
X1321421Y114488D03*
X1326064Y196665D03*
Y192665D03*
X1326159Y204864D03*
X1332789Y425413D03*
X1335329Y455301D03*
Y459101D03*
Y463101D03*
X1332483Y558500D03*
Y562500D03*
Y566500D03*
X1324483D03*
X1332483Y574500D03*
Y586500D03*
Y578500D03*
Y582500D03*
X1324483D03*
Y586500D03*
X1332483Y590500D03*
Y605000D03*
X1324483Y590500D03*
X1332483Y609000D03*
Y613000D03*
Y621000D03*
X1324483Y613000D03*
X1332483Y637000D03*
Y633000D03*
Y625000D03*
Y629000D03*
X1324483D03*
Y633000D03*
Y637000D03*
X1332483Y653500D03*
Y649500D03*
X1324483Y645000D03*
X1332483Y665500D03*
Y657500D03*
X1324483D03*
X1332483Y669500D03*
X1324483Y677500D03*
Y681500D03*
Y673500D03*
X1332483D03*
Y681500D03*
Y677500D03*
Y696500D03*
Y700500D03*
X1324483Y704500D03*
X1332483D03*
Y712500D03*
Y716500D03*
X1324483Y720500D03*
Y728500D03*
Y724500D03*
X1332483Y728500D03*
Y724500D03*
Y720500D03*
X1324453Y736464D03*
X1346156Y151540D03*
X1338957Y474560D03*
X1342276Y749675D03*
Y745675D03*
Y741675D03*
Y737675D03*
Y765675D03*
Y761675D03*
Y757675D03*
Y753675D03*
Y769675D03*
Y781675D03*
X1366767Y149768D03*
X1358227Y327777D03*
Y331377D03*
Y335651D03*
Y339251D03*
Y343525D03*
Y347125D03*
Y351399D03*
Y354999D03*
X1357829Y424601D03*
Y428101D03*
Y431601D03*
X1362748Y1022766D03*
Y1034266D03*
Y1030266D03*
X1384063Y252371D03*
X1373442Y1002180D03*
Y1007180D03*
X1370942Y1012325D03*
Y1016325D03*
X1369826Y1043140D03*
X1369749Y1047047D03*
X1399157Y106495D03*
X1395841Y206864D03*
X1395012Y242078D03*
X1388033D03*
X1390934Y361371D03*
Y356871D03*
X1388569Y577192D03*
X1388570Y627817D03*
X1399442Y1031680D03*
X1404674Y250599D03*
X1412548Y478982D03*
Y483982D03*
Y487982D03*
Y499982D03*
Y491982D03*
X1402717Y536726D03*
Y531726D03*
Y544726D03*
Y540726D03*
X1414842Y597393D03*
X1404435Y629311D03*
Y625311D03*
X1402483Y652000D03*
Y660000D03*
X1415483Y689000D03*
X1402483Y703000D03*
Y707000D03*
X1415483Y705000D03*
Y713000D03*
Y709000D03*
Y733000D03*
X1415452Y720894D03*
X1415483Y749000D03*
Y753000D03*
Y757000D03*
X1415506Y765343D03*
X1411081Y815683D03*
X1410983Y832000D03*
Y828000D03*
X1410932Y823934D03*
X1410885Y819817D03*
X1410983Y848000D03*
Y840000D03*
Y836000D03*
Y852000D03*
Y864000D03*
Y856000D03*
Y880000D03*
Y868000D03*
Y884000D03*
Y896000D03*
Y900000D03*
X1414052Y992307D03*
X1408442Y1032180D03*
X1411594Y1539557D03*
X1411102Y1562235D03*
X1421497Y631212D03*
X1423483Y681000D03*
Y685000D03*
Y689000D03*
Y697000D03*
Y701000D03*
Y713000D03*
Y709000D03*
Y705000D03*
Y725000D03*
Y729000D03*
Y733000D03*
Y741000D03*
Y745000D03*
Y749000D03*
Y753000D03*
Y757000D03*
X1432483Y774500D03*
Y798500D03*
Y790500D03*
Y794500D03*
Y818500D03*
Y834500D03*
Y838500D03*
Y842500D03*
X1421197Y939292D03*
X1428064Y951563D03*
X1428004Y947595D03*
X1418248Y1004766D03*
X1426248Y1000766D03*
X1418248Y996766D03*
Y1008766D03*
X1426248Y1004766D03*
Y996766D03*
Y1016266D03*
X1418252Y1020250D03*
X1426248Y1020266D03*
X1418248Y1030766D03*
X1426248D03*
X1426454Y1494706D03*
X1429424Y1524252D03*
X1448518Y151540D03*
X1446190Y320861D03*
Y325361D03*
Y329861D03*
Y334361D03*
Y338861D03*
Y343361D03*
Y347861D03*
Y352361D03*
Y356861D03*
X1443262Y575841D03*
X1440483Y766500D03*
Y774500D03*
Y770500D03*
Y782500D03*
Y798500D03*
Y794500D03*
Y790500D03*
Y786500D03*
Y814500D03*
Y810500D03*
Y830500D03*
Y826500D03*
Y818500D03*
Y834500D03*
Y838500D03*
Y842500D03*
X1465879Y68581D03*
Y80581D03*
X1451977Y168697D03*
X1452172Y191941D03*
X1454141Y224321D03*
X1456190Y320861D03*
Y325361D03*
Y329861D03*
Y334361D03*
Y338861D03*
Y343361D03*
Y347861D03*
Y352361D03*
X1454519Y571614D03*
Y575614D03*
X1459601Y950980D03*
X1479880Y38244D03*
X1475204Y58013D03*
X1471422Y114488D03*
X1469129Y149768D03*
X1467686Y168713D03*
X1476065Y196665D03*
Y192665D03*
X1476160Y204864D03*
X1469600Y947600D03*
X1498203Y206864D03*
X1490395Y242078D03*
X1497374D03*
X1486425Y252371D03*
X1493029Y358700D03*
Y354200D03*
X1484983Y685630D03*
X1485483Y727500D03*
X1501519Y106495D03*
X1507036Y250599D03*
X1502483Y769000D03*
Y813000D03*
X1500266Y907240D03*
X1525343Y382600D03*
Y463600D03*
X1518431Y554555D03*
Y558555D03*
Y562555D03*
X1524711Y595588D03*
Y591588D03*
X1524743Y603600D03*
X1524711Y599588D03*
X1524743Y611600D03*
Y619600D03*
X1524711Y607588D03*
X1524743Y615600D03*
Y623600D03*
Y627600D03*
Y637969D03*
Y641974D03*
X1520368Y968739D03*
X1546630Y969737D03*
X1550880Y151540D03*
X1554339Y168697D03*
X1554534Y191941D03*
X1556503Y224321D03*
X1561362Y316363D03*
Y325363D03*
X1551362Y316363D03*
Y325363D03*
X1561362Y329863D03*
Y334363D03*
Y343363D03*
X1551362Y329863D03*
Y334363D03*
Y343363D03*
X1561362Y352363D03*
X1577566Y58013D03*
X1568241Y68581D03*
Y80581D03*
X1573784Y114488D03*
X1571491Y149768D03*
X1570048Y168713D03*
X1578427Y192665D03*
Y196665D03*
X1578522Y204864D03*
X1574683Y341600D03*
X1572984Y666275D03*
X1575100Y710129D03*
X1592757Y242078D03*
X1588787Y252371D03*
X1592543Y458800D03*
X1592743Y545800D03*
X1593791Y1442557D03*
X1603881Y106495D03*
X1600565Y206864D03*
X1599736Y242078D03*
X1609398Y250599D03*
X1611780Y336252D03*
Y344252D03*
Y340252D03*
X1605007Y384718D03*
Y380718D03*
Y392718D03*
Y400718D03*
Y404718D03*
Y408718D03*
Y396718D03*
Y412718D03*
X1601343Y553700D03*
Y557700D03*
X1602349Y1468023D03*
X1606586Y1527334D03*
X1623443Y453873D03*
Y458859D03*
X1622628Y542712D03*
X1616168Y675832D03*
X1614085Y699917D03*
Y717817D03*
X1614385Y732417D03*
X1619485Y828117D03*
X1615668Y1528558D03*
X1619268Y1539358D03*
X1615368Y1535258D03*
X1634085Y711417D03*
X1641485Y728117D03*
X1630485Y744317D03*
X1629785Y762717D03*
X1643733Y881999D03*
X1644081Y917241D03*
X1643839Y952125D03*
X1653242Y151540D03*
X1656701Y168697D03*
X1656896Y191941D03*
X1658865Y224321D03*
X1651298Y871345D03*
X1651835Y909279D03*
X1651442Y942136D03*
X1670603Y68581D03*
Y80581D03*
X1676146Y114488D03*
X1673853Y149768D03*
X1672410Y168713D03*
X1679928Y58013D03*
X1680789Y192665D03*
Y196665D03*
X1680884Y204864D03*
X1691149Y252371D03*
X1689828Y545912D03*
Y626912D03*
X1706243Y106495D03*
X1702927Y206864D03*
X1695119Y242078D03*
X1702098D03*
X1698200Y306652D03*
X1711760Y250599D03*
X1721768Y458334D03*
Y450334D03*
X1718168Y1146071D03*
X1732098Y1171120D03*
X1742643Y488816D03*
X1753090Y879199D03*
X1753145Y897279D03*
X1757183Y935100D03*
X1772965Y68581D03*
Y80581D03*
X1759063Y168697D03*
X1759258Y191941D03*
X1761227Y224321D03*
X1762411Y470382D03*
X1774044Y471560D03*
Y479560D03*
X1782290Y58013D03*
X1778508Y114488D03*
X1774772Y168713D03*
X1783151Y196665D03*
Y192665D03*
X1783246Y204864D03*
X1789876Y425413D03*
X1790117Y1430956D03*
X1792645Y200716D03*
X1792416Y455301D03*
Y459101D03*
Y463101D03*
X1796044Y474560D03*
X1805032Y985060D03*
X1792546Y989660D03*
X1798321Y1103246D03*
X1794157Y1257937D03*
X1814916Y424601D03*
Y428101D03*
Y431601D03*
X1807854Y1082250D03*
X1822214Y1101145D03*
Y1105145D03*
X1812915Y1223209D03*
G54D212*
X976763Y311927D03*
Y320273D03*
X983063Y311927D03*
Y320273D03*
G54D221*
X1045145Y812262D03*
Y825844D03*
G54D11*
X13780Y1226024D03*
X79331Y1186654D03*
X390354Y1141024D03*
X536418Y1086654D03*
X854291Y1225118D03*
X993504Y1170748D03*
X1304528Y1141024D03*
X1450591Y1086654D03*
X1761614Y1215000D03*
X1827165Y1235630D03*
G54D122*
X411109Y1116611D03*
X443237D03*
X476696D03*
X508824D03*
X1325283D03*
X1357411D03*
X1390870D03*
X1422998D03*
G54D113*
X392821Y34022D03*
Y25754D03*
X409947Y34022D03*
Y25754D03*
X1268294Y327801D03*
Y336069D03*
X1285420Y327801D03*
Y336069D03*
X1306994Y34022D03*
Y25754D03*
X1324120Y34022D03*
Y25754D03*
X1582437Y335455D03*
Y343723D03*
X1599563Y335455D03*
Y343723D03*
G54D230*
X1776778Y818696D03*
G54D104*
X307313Y316731D03*
Y319290D03*
X299833Y316731D03*
Y321849D03*
Y319290D03*
X307313Y321849D03*
X764399Y316731D03*
Y319290D03*
X756919Y316731D03*
Y321849D03*
Y319290D03*
X764399Y321849D03*
X877801Y710611D03*
Y713170D03*
X870321Y710611D03*
Y715729D03*
Y713170D03*
X877801Y715729D03*
X1221486Y316731D03*
Y319290D03*
X1214006Y316731D03*
Y321849D03*
Y319290D03*
X1221486Y321849D03*
X1671093Y316731D03*
Y321849D03*
Y319290D03*
X1678573Y316731D03*
Y319290D03*
Y321849D03*
G54D140*
X423215Y1122634D03*
X455343D03*
X488802D03*
X520930D03*
X1337389D03*
X1369517D03*
X1402976D03*
X1435104D03*
G54D203*
X944695Y874268D03*
X950691Y857440D03*
X947541D03*
X950691Y861440D03*
X947541D03*
X947845Y874268D03*
G54D131*
X416886Y331413D03*
Y344012D03*
Y332988D03*
Y339287D03*
Y337713D03*
Y329839D03*
Y336138D03*
Y334563D03*
Y340862D03*
Y342437D03*
Y347161D03*
Y345587D03*
X1319471Y334505D03*
Y336080D03*
Y342379D03*
Y340805D03*
Y332931D03*
Y339230D03*
Y337655D03*
Y343954D03*
Y350253D03*
Y347104D03*
Y348679D03*
Y345529D03*
G54D21*
X14360Y160100D03*
X60595Y455494D03*
X110758Y117621D03*
X213120D03*
X315482D03*
X465483D03*
X515681Y452494D03*
X567845Y117621D03*
X670207D03*
X772569D03*
X922569D03*
X974768Y455494D03*
X1024931Y117621D03*
X1127293D03*
X1229655D03*
X1379656D03*
X1429855Y452494D03*
X1482018Y117621D03*
X1584380D03*
X1686742D03*
G54D123*
X417211Y1126178D03*
X449339D03*
X482798D03*
X514926D03*
X1331385D03*
X1363513D03*
X1396972D03*
X1429100D03*
G54D132*
X428500Y338500D03*
X1331085Y341592D03*
G54D114*
X392821Y28608D03*
Y31168D03*
X409947Y28608D03*
Y31168D03*
X1268294Y333215D03*
Y330655D03*
X1285420Y333215D03*
Y330655D03*
X1306994Y28608D03*
Y31168D03*
X1324120Y28608D03*
Y31168D03*
X1582437Y340869D03*
Y338309D03*
X1599563Y340869D03*
Y338309D03*
G54D204*
X944439Y944423D03*
X941880D03*
X939321D03*
X936762D03*
Y967455D03*
X939321D03*
X941880D03*
X944439D03*
X959794Y944423D03*
X957235D03*
X952117D03*
X949558D03*
X946998D03*
X954676D03*
X957235Y967455D03*
X946998D03*
X949558D03*
X952117D03*
X954676D03*
X959794D03*
G54D12*
X14751Y66681D03*
X7271D03*
X11011Y75343D03*
X117708Y153296D03*
X125188D03*
X121448Y161958D03*
X133095Y450750D03*
X140575D03*
X136835Y459412D03*
X197929Y99259D03*
X194189Y107921D03*
X201669D03*
X227550Y153296D03*
X220070D03*
X223810Y161958D03*
X296551Y107921D03*
X300291Y99259D03*
X304031Y107921D03*
X322432Y153296D03*
X326172Y161958D03*
X328945Y560043D03*
X329912Y153296D03*
X332685Y551381D03*
X336425Y560043D03*
X402653Y99259D03*
X398913Y107921D03*
X406393D03*
X472433Y153296D03*
X479913D03*
X476173Y161958D03*
X552654Y99259D03*
X548914Y107921D03*
X556394D03*
X582275Y153296D03*
X574795D03*
X578535Y161958D03*
X597661Y450750D03*
X590181D03*
X593921Y459412D03*
X651276Y107921D03*
X655016Y99259D03*
X658756Y107921D03*
X684637Y153296D03*
X677157D03*
X680897Y161958D03*
X757378Y99259D03*
X753638Y107921D03*
X761118D03*
X779519Y153296D03*
X783259Y161958D03*
X786999Y153296D03*
X789771Y551381D03*
X786031Y560043D03*
X793511D03*
X859740Y99259D03*
X856000Y107921D03*
X863480D03*
X929519Y153296D03*
X936999D03*
X933259Y161958D03*
X1009740Y99259D03*
X1006000Y107921D03*
X1013480D03*
X1039361Y153296D03*
X1031881D03*
X1035621Y161958D03*
X1054748Y450750D03*
X1047268D03*
X1051008Y459412D03*
X1108362Y107921D03*
X1112102Y99259D03*
X1115842Y107921D03*
X1141723Y153296D03*
X1134243D03*
X1137983Y161958D03*
X1214464Y99259D03*
X1210724Y107921D03*
X1218204D03*
X1236605Y153296D03*
X1244085D03*
X1240345Y161958D03*
X1246858Y551381D03*
X1243118Y560043D03*
X1250598D03*
X1316826Y99259D03*
X1313086Y107921D03*
X1320566D03*
X1394086Y153296D03*
X1386606D03*
X1390346Y161958D03*
X1466827Y99259D03*
X1463087Y107921D03*
X1470567D03*
X1496448Y153296D03*
X1488968D03*
X1492708Y161958D03*
X1511835Y450750D03*
X1504355D03*
X1508095Y459412D03*
X1569189Y99259D03*
X1565449Y107921D03*
X1572929D03*
X1591330Y153296D03*
X1595070Y161958D03*
X1598810Y153296D03*
X1671551Y99259D03*
X1667811Y107921D03*
X1675291D03*
X1693692Y153296D03*
X1701172D03*
X1697432Y161958D03*
X1703945Y551381D03*
X1700205Y560043D03*
X1707685D03*
X1773913Y99259D03*
X1770173Y107921D03*
X1777653D03*
G54D231*
X1795453Y812874D03*
Y834922D03*
G54D213*
X980085Y1480881D03*
Y1498597D03*
X1017867Y1480881D03*
Y1498597D03*
G54D105*
X310628Y328844D03*
Y336324D03*
X320274Y328844D03*
Y336324D03*
Y332584D03*
X767714Y328844D03*
Y336324D03*
X777360Y328844D03*
Y336324D03*
Y332584D03*
X859838Y685230D03*
Y692710D03*
Y688970D03*
X869484Y685230D03*
Y692710D03*
X896074Y940895D03*
X886428D03*
Y944635D03*
X896074Y948375D03*
X886428D03*
X1224801Y328844D03*
X1234447D03*
X1224801Y336324D03*
X1234447D03*
Y332584D03*
X1681888Y328844D03*
X1691534D03*
X1681888Y336324D03*
X1691534D03*
Y332584D03*
G54D141*
X419061Y1143544D03*
Y1167756D03*
X446889Y1143544D03*
Y1167756D03*
X484648Y1143544D03*
Y1167756D03*
X512476Y1143544D03*
Y1167756D03*
X1333235Y1143544D03*
Y1167756D03*
X1361063Y1143544D03*
Y1167756D03*
X1398822Y1143544D03*
Y1167756D03*
X1426650Y1143544D03*
Y1167756D03*
G54D30*
X9837Y252371D03*
Y272371D03*
X8427Y284118D03*
X16396Y1464612D03*
X16307Y1496782D03*
X12724Y1501619D03*
X29115Y97667D03*
X24931Y102495D03*
X30844Y241681D03*
X31787Y289272D03*
Y285272D03*
X28491Y527726D03*
Y548726D03*
X30209Y621311D03*
X35247Y1078372D03*
X38057Y177606D03*
X38322Y495982D03*
X50510Y529269D03*
X49541Y688473D03*
X51680Y1124923D03*
X41902Y1193263D03*
X48941Y1192250D03*
X51428Y1213709D03*
X60320Y483388D03*
X57209Y608311D03*
X56266Y843118D03*
X64601Y1071656D03*
Y1075656D03*
Y1067656D03*
Y1083656D03*
Y1087656D03*
Y1079656D03*
X58302Y1209720D03*
X85241Y141247D03*
X78262D03*
X74292Y147540D03*
X84631Y678107D03*
Y682107D03*
X84233Y1021048D03*
X94903Y145768D03*
X91528Y1021177D03*
X101839Y172665D03*
Y180665D03*
Y176665D03*
Y168665D03*
Y184665D03*
Y188665D03*
X101934Y200864D03*
Y208864D03*
Y212864D03*
Y216864D03*
Y221864D03*
X101931Y225719D03*
X112199Y248371D03*
X108321Y1027361D03*
X131477Y97667D03*
X127293Y102495D03*
X121722Y134838D03*
Y138838D03*
X133206Y241681D03*
X151117Y378600D03*
Y459600D03*
X151205Y554555D03*
X151237Y562567D03*
X151205Y558555D03*
X150517Y631421D03*
X180624Y141247D03*
X176654Y147540D03*
X183349Y80140D03*
Y76140D03*
Y84140D03*
X194060Y76587D03*
Y72587D03*
X197265Y145768D03*
X187603Y141247D03*
X204201Y172665D03*
Y180665D03*
Y176665D03*
Y168665D03*
Y184665D03*
Y188665D03*
X204296Y208864D03*
Y212864D03*
Y216864D03*
Y221864D03*
X204293Y225719D03*
X214561Y248371D03*
X229655Y102495D03*
X224084Y134838D03*
Y138838D03*
X230781Y388718D03*
X218317Y462800D03*
X218517Y549800D03*
X227117Y549700D03*
X218517Y562800D03*
Y558800D03*
X218917Y621400D03*
Y625400D03*
X227554Y1494361D03*
X227560Y1482442D03*
Y1490442D03*
X229565Y1514578D03*
X220032Y1515642D03*
X219732Y1522542D03*
X229565Y1526578D03*
Y1522578D03*
X233839Y97667D03*
X235568Y241681D03*
X246583Y1514169D03*
Y1510142D03*
X249217Y445873D03*
Y449873D03*
Y462859D03*
X248402Y546712D03*
X248782Y675889D03*
X279016Y147540D03*
X283886Y27156D03*
X285711Y84140D03*
Y76140D03*
Y80140D03*
X289965Y141247D03*
X282986D03*
X287032Y317873D03*
X296422Y76587D03*
Y72587D03*
X299627Y145768D03*
X306563Y180665D03*
Y172665D03*
Y176665D03*
Y168665D03*
Y184665D03*
X299608Y196286D03*
X306563Y188665D03*
X306658Y208864D03*
Y212864D03*
Y216864D03*
Y221864D03*
X306655Y225719D03*
X325423Y15806D03*
Y19806D03*
Y11806D03*
Y27806D03*
Y23806D03*
Y31806D03*
X326446Y134838D03*
Y138838D03*
X316923Y248371D03*
X317425Y350850D03*
X315602Y541912D03*
Y622912D03*
X336201Y97667D03*
X332017Y102495D03*
X337930Y241681D03*
X347542Y454334D03*
X350873Y1171120D03*
X361493Y406532D03*
X361837Y447357D03*
X370541Y458309D03*
Y454309D03*
Y462309D03*
X376117Y750000D03*
X374417Y786400D03*
X372949Y939976D03*
Y943812D03*
Y947812D03*
X388073Y84140D03*
Y80140D03*
Y76140D03*
X386931Y401923D03*
X388185Y466409D03*
Y474382D03*
Y487382D03*
Y482382D03*
Y478382D03*
X389687Y864408D03*
X384534Y1539700D03*
Y1543700D03*
Y1551700D03*
Y1559700D03*
X408925Y180665D03*
Y172665D03*
Y176665D03*
Y168665D03*
Y184665D03*
Y188665D03*
X401601Y196620D03*
X409020Y208864D03*
Y212864D03*
Y216864D03*
Y221864D03*
X409017Y225719D03*
X399818Y471560D03*
Y475560D03*
X400717Y789000D03*
X398926Y860535D03*
Y864409D03*
X398868Y868286D03*
X396842Y948536D03*
X397037Y971780D03*
X409207Y1098826D03*
X404632Y1442942D03*
X416920Y26534D03*
X417015Y22627D03*
X416992Y30483D03*
X416955Y834800D03*
X417221Y1523296D03*
X424741Y1546372D03*
X439966Y141247D03*
X432987D03*
X429017Y147540D03*
X440690Y435101D03*
Y439101D03*
Y443101D03*
Y447101D03*
Y452601D03*
X434608Y620456D03*
X442353Y711199D03*
X441335Y1098826D03*
X431741Y1550158D03*
X449628Y145768D03*
X453636Y468809D03*
X443154Y620456D03*
X450494Y634279D03*
X443525Y640876D03*
X450489Y642588D03*
X445608Y1026266D03*
X454108Y1024766D03*
X466924Y248371D03*
X467908Y461864D03*
X462920Y491669D03*
Y499669D03*
Y503669D03*
Y507669D03*
Y512669D03*
X474794Y1098826D03*
X486202Y97667D03*
X482018Y102495D03*
X476447Y134838D03*
Y138838D03*
X487931Y241681D03*
X475324Y347995D03*
Y352495D03*
X475427Y360089D03*
X485324Y347995D03*
Y352495D03*
X485427Y360089D03*
X475427Y364589D03*
Y369089D03*
Y373589D03*
X485427Y364589D03*
Y369089D03*
Y373589D03*
X475427Y378089D03*
Y382589D03*
Y387089D03*
Y391589D03*
X485427Y378089D03*
Y382589D03*
X476635Y468784D03*
Y472784D03*
Y476784D03*
X485577Y527726D03*
Y548726D03*
X487295Y621311D03*
X478923Y648968D03*
X495408Y495982D03*
X499697Y655149D03*
X495451Y685006D03*
Y689006D03*
Y697006D03*
Y693006D03*
X506258Y844649D03*
X501108Y1000766D03*
Y1016266D03*
Y1012266D03*
X506922Y1098826D03*
X517406Y483388D03*
X507596Y529269D03*
X514295Y608311D03*
X510787Y969933D03*
X510739Y973885D03*
X538074Y80140D03*
Y76140D03*
Y84140D03*
X535349Y141247D03*
X531379Y147540D03*
X535703Y381723D03*
X532084Y394309D03*
X539541Y779889D03*
X525197Y1103717D03*
X548785Y76587D03*
Y72587D03*
X542328Y141247D03*
X551990Y145768D03*
X545703Y386223D03*
Y390723D03*
X552698Y738558D03*
X544719Y746514D03*
X548615Y1021177D03*
X541320Y1021048D03*
X558926Y180665D03*
Y172665D03*
Y176665D03*
Y168665D03*
Y184665D03*
Y188665D03*
X559021Y208864D03*
Y212864D03*
Y216864D03*
Y221864D03*
X559018Y225719D03*
X569286Y248371D03*
X567537Y743122D03*
X561304Y754992D03*
X572131Y776700D03*
Y780700D03*
X564862Y1026933D03*
X572274Y1526224D03*
X588564Y97667D03*
X584380Y102495D03*
X578809Y134838D03*
Y138838D03*
X573320Y957207D03*
X585449Y1497687D03*
Y1493687D03*
X582232Y1514042D03*
X585449Y1501687D03*
X581483Y1505724D03*
X590293Y241681D03*
X608203Y378600D03*
Y459600D03*
X608291Y554555D03*
Y558555D03*
X608323Y562567D03*
X607603Y631421D03*
X633741Y147540D03*
X640436Y76140D03*
Y84140D03*
Y80140D03*
X651147Y76587D03*
Y72587D03*
X644690Y141247D03*
X637711D03*
X653363Y759137D03*
Y767137D03*
Y763137D03*
Y779137D03*
Y775137D03*
Y771137D03*
Y783137D03*
Y787137D03*
X654352Y145768D03*
X661288Y180665D03*
Y172665D03*
Y176665D03*
Y168665D03*
Y184665D03*
Y188665D03*
X661383Y208864D03*
Y212864D03*
Y216864D03*
Y221864D03*
X661380Y225719D03*
X658059Y660402D03*
X662080Y689694D03*
X666863Y763137D03*
Y779137D03*
Y771137D03*
Y787137D03*
X681171Y134838D03*
Y138838D03*
X671648Y248371D03*
X675403Y462800D03*
X675603Y549800D03*
X684203Y549700D03*
X676003Y621400D03*
Y625400D03*
X690926Y97667D03*
X686742Y102495D03*
X692655Y241681D03*
X687867Y388718D03*
X706303Y445873D03*
Y449873D03*
Y462859D03*
X705488Y546712D03*
X705868Y675889D03*
X717306Y691609D03*
X704102Y709303D03*
X707107Y728050D03*
X724863Y760137D03*
X742798Y84140D03*
Y76140D03*
Y80140D03*
X747052Y141247D03*
X740073D03*
X736103Y147540D03*
X744118Y317873D03*
X736247Y1622015D03*
X753509Y72562D03*
Y76587D03*
X756714Y145768D03*
X763650Y180665D03*
Y172665D03*
Y176665D03*
Y168665D03*
Y184665D03*
Y188665D03*
X756326Y196620D03*
X763745Y200864D03*
Y208864D03*
Y212864D03*
Y216864D03*
Y221864D03*
X783533Y134838D03*
Y138838D03*
X774010Y248371D03*
X774511Y350850D03*
X772688Y541912D03*
Y622912D03*
X780278Y1443445D03*
X780266Y1435432D03*
X771727Y1454305D03*
X793288Y97667D03*
X789104Y102495D03*
X795017Y241681D03*
X788641Y442510D03*
Y450510D03*
Y446510D03*
X811994Y305368D03*
Y309368D03*
X803994Y305368D03*
Y309368D03*
X811994Y313368D03*
X803994D03*
X811994Y317368D03*
Y321368D03*
Y325368D03*
X803994Y317368D03*
Y321368D03*
Y325368D03*
X811994Y329368D03*
X803994D03*
X811994Y333368D03*
X803994Y337368D03*
Y333368D03*
X811994Y346368D03*
X803994D03*
X811994Y350368D03*
X811991Y354741D03*
X804628Y448334D03*
X808841Y840919D03*
X807960Y1171120D03*
X807146Y1404769D03*
X805011Y1484354D03*
X818900Y441389D03*
X827627Y456309D03*
Y448309D03*
Y452309D03*
X817080Y742502D03*
X827017Y766500D03*
Y784500D03*
Y802500D03*
Y820500D03*
X820494Y933571D03*
X831221Y1440849D03*
Y1448849D03*
X825927Y1462461D03*
X831239Y1454525D03*
X845160Y76140D03*
Y80140D03*
Y84140D03*
X845271Y461382D03*
Y469382D03*
Y473382D03*
Y482382D03*
Y477382D03*
X838359Y827459D03*
X846157Y827686D03*
X840781Y843790D03*
Y847490D03*
X842826Y835459D03*
Y851459D03*
X840254Y863413D03*
X840381Y855395D03*
X840254Y867413D03*
X842261Y1461959D03*
X855871Y76587D03*
Y72587D03*
X858688Y196620D03*
X862262Y340454D03*
X850491Y414760D03*
X861748Y414533D03*
X850491Y418760D03*
X863971Y487303D03*
Y483303D03*
X860778Y701170D03*
Y709170D03*
X860578Y722670D03*
X861517Y756000D03*
Y760000D03*
Y764000D03*
Y778000D03*
Y782000D03*
Y774000D03*
Y792000D03*
Y796000D03*
Y800000D03*
Y814000D03*
Y810000D03*
X853848Y827468D03*
X861517Y818000D03*
X853776Y835459D03*
X866012Y180665D03*
Y172665D03*
Y176665D03*
Y168665D03*
Y184665D03*
Y188665D03*
X866107Y208864D03*
Y212864D03*
Y216864D03*
Y221864D03*
X872494Y309368D03*
Y305368D03*
Y313368D03*
Y325368D03*
Y321368D03*
Y317368D03*
Y329368D03*
Y333368D03*
X880494Y341342D03*
Y345342D03*
X869430Y549771D03*
X869585Y562703D03*
Y570703D03*
Y566703D03*
Y578703D03*
Y582828D03*
X878778Y694970D03*
Y690970D03*
X873245Y794227D03*
X897052Y141247D03*
X890073D03*
X886103Y147540D03*
X888404Y341537D03*
X882257Y415264D03*
X883778Y727178D03*
Y722770D03*
X881937Y1087375D03*
X885592Y1202266D03*
X892631Y1201253D03*
X895118Y1222712D03*
X883761Y1444859D03*
Y1460859D03*
Y1476859D03*
Y1468859D03*
X906714Y145768D03*
X899277Y358369D03*
Y354369D03*
Y374369D03*
Y366369D03*
X906978Y687770D03*
Y691770D03*
X907778Y718970D03*
X903851Y948607D03*
X911291Y1076659D03*
Y1080659D03*
Y1084659D03*
Y1088659D03*
Y1092659D03*
Y1096659D03*
X898370Y1133926D03*
X901992Y1218723D03*
X917084Y310985D03*
X917903Y547348D03*
X926169Y557641D03*
Y569578D03*
Y573578D03*
Y577578D03*
Y581578D03*
X927723Y798271D03*
X922357Y1449536D03*
X921721Y1468100D03*
X943288Y97667D03*
X939104Y102495D03*
X933533Y134838D03*
Y138838D03*
X945683Y226852D03*
X936016Y451442D03*
Y455442D03*
Y459442D03*
Y463442D03*
Y468942D03*
X942664Y527726D03*
Y548726D03*
X944382Y621311D03*
X940603Y792330D03*
X944644Y864862D03*
X944581Y883146D03*
X936345Y891216D03*
X945914Y1087375D03*
X952495Y495982D03*
X949545Y782467D03*
X949701Y799233D03*
X949470Y786366D03*
X952081Y899890D03*
X962347Y1133926D03*
X949569Y1202122D03*
X956608Y1201253D03*
X959095Y1222712D03*
X974493Y483388D03*
X964683Y529269D03*
X971382Y608311D03*
X973602Y831799D03*
X973608Y827907D03*
X975268Y1076659D03*
Y1088659D03*
Y1084659D03*
Y1080659D03*
Y1092659D03*
Y1096659D03*
X965969Y1218723D03*
X992435Y141247D03*
X988465Y147540D03*
X994694Y314653D03*
X979642Y328472D03*
Y335472D03*
X981720Y825159D03*
Y829159D03*
Y833159D03*
X995160Y84140D03*
Y76140D03*
Y80140D03*
X1005871Y72587D03*
Y76587D03*
X999414Y141247D03*
X1009076Y145768D03*
X1005701Y1021177D03*
X1011021Y1357938D03*
X1011009Y1368835D03*
X1011004Y1380797D03*
X1016012Y180665D03*
Y172665D03*
Y176665D03*
Y168665D03*
Y184665D03*
Y188665D03*
X1016107Y200864D03*
Y208864D03*
Y212864D03*
Y216864D03*
Y221864D03*
X1016104Y225719D03*
X1026372Y248371D03*
X1016412Y754546D03*
Y771974D03*
Y775974D03*
X1016375Y815046D03*
X1016412Y825981D03*
Y818974D03*
X1015220Y833659D03*
X1015720Y848680D03*
X1014936Y954222D03*
X1021948Y1026933D03*
X1041466Y102495D03*
X1035895Y134838D03*
Y138838D03*
X1040180Y1309487D03*
X1035957Y1357372D03*
X1035900Y1361287D03*
X1035908Y1365009D03*
X1045650Y97667D03*
X1047379Y241681D03*
X1055742Y310574D03*
X1055629Y343509D03*
X1055221Y356151D03*
Y368276D03*
X1054504Y1311436D03*
X1054550Y1315605D03*
X1048453Y1323611D03*
X1058352Y1456486D03*
X1065290Y378600D03*
Y459600D03*
X1065378Y554555D03*
Y558555D03*
X1065410Y562567D03*
X1064690Y631421D03*
X1090827Y147540D03*
X1097522Y76140D03*
Y80140D03*
Y84140D03*
X1108233Y72587D03*
Y76587D03*
X1101776Y141247D03*
X1094797D03*
X1111438Y145768D03*
X1118374Y180665D03*
Y172665D03*
Y176665D03*
Y168665D03*
Y188665D03*
Y184665D03*
X1118469Y200864D03*
Y208864D03*
Y212864D03*
Y216864D03*
Y221864D03*
X1118466Y225719D03*
X1115146Y660402D03*
X1119167Y689694D03*
X1138257Y134838D03*
Y138838D03*
X1128734Y248371D03*
X1132490Y462800D03*
X1132690Y549800D03*
X1133090Y621400D03*
Y625400D03*
X1148012Y97667D03*
X1143828Y102495D03*
X1149741Y241681D03*
X1144954Y388718D03*
X1141290Y549700D03*
X1163390Y445873D03*
Y449873D03*
Y462859D03*
X1162575Y546712D03*
X1162955Y675889D03*
X1179853Y339103D03*
X1199884Y84140D03*
Y76140D03*
Y80140D03*
X1204138Y141247D03*
X1197159D03*
X1193189Y147540D03*
X1201205Y317873D03*
X1210595Y72587D03*
Y76587D03*
X1213800Y145768D03*
X1220736Y180665D03*
Y172665D03*
Y176665D03*
Y168665D03*
Y184665D03*
Y188665D03*
X1213412Y196620D03*
X1220831Y200864D03*
Y208864D03*
Y212864D03*
Y216864D03*
Y221864D03*
X1220828Y225719D03*
X1231096Y248371D03*
X1231598Y350850D03*
X1229775Y541912D03*
Y622912D03*
X1250374Y97667D03*
X1246190Y102495D03*
X1240619Y134838D03*
Y138838D03*
X1252103Y241681D03*
X1247632Y1531342D03*
X1259017Y327000D03*
X1261715Y454334D03*
X1268807Y914949D03*
Y918956D03*
X1265046Y1171120D03*
X1257150Y1519459D03*
X1275666Y406532D03*
X1276010Y447357D03*
X1284714Y458309D03*
Y454309D03*
Y462309D03*
X1282031Y776576D03*
Y772576D03*
Y784576D03*
X1278017Y914000D03*
X1302246Y84140D03*
Y76140D03*
Y80140D03*
X1301104Y401923D03*
X1302358Y466409D03*
Y474382D03*
Y487382D03*
Y482382D03*
Y478382D03*
X1295583Y796321D03*
X1288017Y827500D03*
Y831500D03*
Y823500D03*
Y835500D03*
Y859500D03*
Y855500D03*
X1288012Y877783D03*
Y881783D03*
Y889767D03*
X1291017Y919500D03*
X1315774Y196620D03*
X1313991Y471560D03*
Y475560D03*
X1331093Y26534D03*
X1331165Y30483D03*
X1331188Y22627D03*
X1323098Y168665D03*
Y176665D03*
Y172665D03*
Y180665D03*
Y184665D03*
Y188665D03*
X1323193Y200864D03*
Y208864D03*
Y212864D03*
Y216864D03*
Y221864D03*
X1323190Y225719D03*
X1321517Y558500D03*
Y562500D03*
Y574500D03*
Y578500D03*
X1329517Y594500D03*
X1321517D03*
Y605000D03*
Y621000D03*
Y609000D03*
Y625000D03*
X1329517Y641000D03*
X1321517Y653500D03*
Y641000D03*
Y649500D03*
Y665500D03*
Y669500D03*
Y685500D03*
X1329517D03*
X1321517Y700500D03*
Y696500D03*
Y716500D03*
Y712500D03*
Y732500D03*
X1329517D03*
X1323381Y1098826D03*
X1347160Y141247D03*
X1343190Y147540D03*
X1339310Y773675D03*
X1354139Y141247D03*
X1363801Y145768D03*
X1354863Y435101D03*
Y439101D03*
Y443101D03*
Y447101D03*
Y452601D03*
X1359782Y1026266D03*
X1368282Y1024766D03*
X1355509Y1098826D03*
X1381097Y248371D03*
X1377968Y320871D03*
Y325371D03*
Y343371D03*
Y338871D03*
Y334371D03*
Y329871D03*
Y347871D03*
Y361371D03*
Y356871D03*
Y352371D03*
X1400375Y97667D03*
X1396191Y102495D03*
X1390620Y134838D03*
Y138838D03*
X1387968Y320871D03*
Y325371D03*
Y329871D03*
Y343371D03*
Y338871D03*
Y334371D03*
Y352371D03*
Y347871D03*
X1399751Y527726D03*
Y548726D03*
X1385258Y569000D03*
Y565000D03*
Y561000D03*
X1385604Y581317D03*
X1385258Y615500D03*
Y611500D03*
Y607500D03*
X1385603Y623692D03*
X1391517Y652000D03*
X1399517Y656000D03*
X1391517D03*
Y660000D03*
X1391017Y675000D03*
X1399017D03*
X1391517Y699000D03*
X1399517D03*
X1391517Y703000D03*
Y707000D03*
X1399017Y722000D03*
X1391017D03*
X1388968Y1098826D03*
X1402104Y241681D03*
X1409582Y495982D03*
X1401469Y621311D03*
X1412517Y681000D03*
Y685000D03*
Y697000D03*
Y701000D03*
Y717000D03*
Y725000D03*
Y729000D03*
Y741000D03*
Y745000D03*
Y761000D03*
X1408017Y844000D03*
Y860000D03*
Y876000D03*
Y872000D03*
Y888000D03*
Y892000D03*
Y904000D03*
X1407831Y911137D03*
Y915186D03*
X1411085Y988403D03*
X1415282Y1000766D03*
Y1016266D03*
Y1012266D03*
X1416681Y1548217D03*
X1416039Y1569486D03*
X1431580Y483388D03*
X1421770Y529269D03*
X1428469Y608311D03*
X1420517Y717000D03*
X1429517Y766500D03*
X1420517Y761000D03*
X1429517Y770500D03*
Y782500D03*
Y786500D03*
Y802500D03*
Y814500D03*
Y810500D03*
Y830500D03*
Y826500D03*
Y846500D03*
X1425050Y943390D03*
X1432611Y1001519D03*
X1421096Y1098826D03*
X1423494Y1498545D03*
X1426456Y1520364D03*
X1449522Y141247D03*
X1445552Y147540D03*
X1434700Y359673D03*
X1437517Y802500D03*
Y846500D03*
X1435973Y951902D03*
X1440129Y1001518D03*
X1439371Y1103717D03*
X1451602Y26393D03*
Y30393D03*
X1451318Y39193D03*
X1452247Y84140D03*
Y76140D03*
Y80140D03*
X1462958Y72587D03*
Y76587D03*
X1456501Y141247D03*
X1453224Y356861D03*
X1458713Y928177D03*
X1461865Y932887D03*
X1455493Y1021048D03*
X1462788Y1021177D03*
X1466163Y145768D03*
X1473099Y168665D03*
Y176665D03*
Y172665D03*
Y180665D03*
Y184665D03*
Y188665D03*
X1473194Y200864D03*
Y208864D03*
Y212864D03*
Y216864D03*
Y221864D03*
X1473191Y225719D03*
X1480063Y327200D03*
Y322700D03*
Y340700D03*
Y331700D03*
Y345200D03*
Y358700D03*
Y354200D03*
Y349700D03*
X1482017Y681630D03*
Y677630D03*
Y697630D03*
Y689630D03*
Y693630D03*
Y706500D03*
Y750500D03*
X1466717Y939543D03*
X1466681Y943496D03*
X1471017Y972000D03*
X1479035Y1026933D03*
X1493139Y19043D03*
Y15043D03*
Y23043D03*
Y31043D03*
Y27043D03*
Y35043D03*
X1492982Y138838D03*
Y134838D03*
X1483459Y248371D03*
X1490063Y322700D03*
Y327200D03*
Y331700D03*
Y340700D03*
Y349700D03*
Y345200D03*
X1490030Y368576D03*
X1490017Y706500D03*
X1482517Y731500D03*
Y723500D03*
Y735500D03*
Y743500D03*
Y739500D03*
X1490017Y750500D03*
X1502737Y97667D03*
X1498553Y102495D03*
X1504466Y241681D03*
X1499517Y765000D03*
Y781000D03*
Y773000D03*
Y777000D03*
X1507017Y792000D03*
X1499017D03*
X1499517Y785000D03*
Y809000D03*
Y817000D03*
Y825000D03*
Y821000D03*
Y829000D03*
X1507017Y836000D03*
X1499017D03*
X1504300Y907240D03*
X1522377Y378600D03*
Y459600D03*
X1522465Y554555D03*
Y558555D03*
X1522497Y562567D03*
X1521777Y631421D03*
X1538225Y352053D03*
X1554609Y84140D03*
Y76140D03*
Y80140D03*
X1547914Y147540D03*
X1558863Y141247D03*
X1551884D03*
X1548396Y352363D03*
X1551231Y956600D03*
X1565320Y72587D03*
Y76587D03*
X1568525Y145768D03*
X1575461Y168665D03*
Y176665D03*
Y172665D03*
Y180665D03*
Y184665D03*
Y188665D03*
X1575556Y200864D03*
Y208864D03*
Y212864D03*
Y216864D03*
Y221864D03*
X1575553Y225719D03*
X1571717Y336200D03*
X1572233Y660402D03*
X1576254Y689694D03*
X1595344Y134838D03*
Y138838D03*
X1585821Y248371D03*
X1589577Y462800D03*
X1589777Y549800D03*
Y558800D03*
Y562800D03*
X1590177Y621400D03*
Y625400D03*
X1590799Y1446488D03*
X1605099Y97667D03*
X1600915Y102495D03*
X1606828Y241681D03*
X1602041Y388718D03*
X1598377Y549700D03*
X1601629Y1471973D03*
X1603620Y1539334D03*
X1603608Y1543373D03*
X1616814Y344252D03*
Y340252D03*
X1620477Y445873D03*
Y449873D03*
Y462859D03*
X1619662Y546712D03*
X1620042Y675889D03*
X1656971Y84140D03*
Y80140D03*
Y76140D03*
X1654246Y141247D03*
X1650276Y147540D03*
X1658292Y317873D03*
X1667682Y72587D03*
Y76587D03*
X1661225Y141247D03*
X1670887Y145768D03*
X1670499Y196620D03*
X1677823Y168665D03*
Y176665D03*
Y172665D03*
Y180665D03*
Y188665D03*
Y184665D03*
X1677918Y200864D03*
Y208864D03*
Y212864D03*
Y216864D03*
Y221864D03*
X1677915Y225719D03*
X1688183Y248371D03*
X1688685Y350850D03*
X1686862Y541912D03*
Y622912D03*
X1707461Y97667D03*
X1703277Y102495D03*
X1697706Y134838D03*
Y138838D03*
X1709190Y241681D03*
X1718802Y454334D03*
X1722133Y1171120D03*
X1732753Y406532D03*
X1733097Y447357D03*
X1741801Y458309D03*
Y454309D03*
Y462309D03*
X1758191Y401923D03*
X1750125Y884649D03*
X1749359Y915451D03*
X1754217Y931100D03*
X1759333Y80140D03*
Y76140D03*
Y84140D03*
X1770044Y72587D03*
Y76587D03*
X1772861Y196620D03*
X1759445Y466409D03*
X1771078Y467560D03*
X1759445Y474382D03*
Y487382D03*
Y482382D03*
X1771078Y475560D03*
X1759445Y478382D03*
X1761024Y824383D03*
Y820883D03*
X1780185Y168665D03*
Y176665D03*
Y172665D03*
Y180665D03*
Y184665D03*
Y188665D03*
X1789705Y196531D03*
X1780280Y200864D03*
Y208864D03*
Y212864D03*
Y216864D03*
Y221864D03*
X1780277Y225719D03*
X1778485Y924546D03*
X1789580Y985060D03*
X1789894Y1087861D03*
X1783147Y1462700D03*
X1800588Y1201739D03*
X1793549Y1202756D03*
X1803075Y1223198D03*
X1800038Y1444543D03*
X1799915Y1476733D03*
X1811950Y435101D03*
Y439101D03*
Y443101D03*
Y447101D03*
Y452601D03*
X1819248Y1077145D03*
Y1081145D03*
Y1089145D03*
Y1085145D03*
Y1093145D03*
Y1097145D03*
X1810327Y1134412D03*
X1809949Y1219209D03*
G54D222*
X1030635Y824546D03*
G54D150*
X468408Y1007854D03*
X473133D03*
X471558D03*
X469983D03*
Y1026752D03*
X471558D03*
X473133D03*
X468408D03*
X479432Y1007854D03*
X477857D03*
X476282D03*
X474708D03*
X481007D03*
X482582D03*
Y1026752D03*
X481007D03*
X479432D03*
X477857D03*
X476282D03*
X474708D03*
X1382582Y1007854D03*
Y1026752D03*
X1393606Y1007854D03*
X1392031D03*
X1390456D03*
X1388882D03*
X1395181D03*
X1396756D03*
X1387307D03*
X1385732D03*
X1384157D03*
X1396756Y1026752D03*
X1395181D03*
X1384157D03*
X1385732D03*
X1387307D03*
X1393606D03*
X1392031D03*
X1390456D03*
X1388882D03*
G54D40*
X23622Y1604724D03*
X62205Y765197D03*
X74016Y333464D03*
X102224Y70866D03*
X409488Y1604724D03*
X433130Y70866D03*
X463387Y286221D03*
X463386Y765197D03*
X661674Y23622D03*
X785039Y1547638D03*
X890217Y23622D03*
X920473Y765196D03*
X1055905Y1547637D03*
X1118760Y23622D03*
X1347303Y70866D03*
X1377559Y286220D03*
Y765197D03*
X1431457Y1604724D03*
X1575846Y23622D03*
X1766929Y333464D03*
X1778740Y765197D03*
X1795010Y23622D03*
X1817323Y1604724D03*
G54D151*
X475495Y1017303D03*
X1389669D03*
G54D232*
X1796437Y818780D03*
Y826457D03*
Y829016D03*
Y821339D03*
Y823898D03*
G54D214*
X990699Y783295D03*
X993258D03*
X990699Y806295D03*
X993258D03*
X1006053Y783295D03*
X998376D03*
X1003494D03*
X1000935D03*
X995817D03*
X998376Y806295D03*
X995817D03*
X1000935D03*
X1006053D03*
X1003494D03*
G54D205*
X933810Y944423D03*
Y967455D03*
X962746Y944423D03*
Y967455D03*
G54D22*
X19478Y160100D03*
X65713Y455494D03*
X115876Y117621D03*
X218238D03*
X320600D03*
X470601D03*
X520799Y452494D03*
X572963Y117621D03*
X675325D03*
X777687D03*
X927687D03*
X979886Y455494D03*
X1030049Y117621D03*
X1132411D03*
X1234773D03*
X1384774D03*
X1434973Y452494D03*
X1487136Y117621D03*
X1589498D03*
X1691860D03*
G54D160*
X650958Y672360D03*
Y682006D03*
X658438Y672360D03*
Y682006D03*
X654698D03*
X767282Y1595014D03*
X763542D03*
X759802D03*
Y1604660D03*
X767282D03*
X806318Y1387865D03*
X813798D03*
Y1397511D03*
X806318D03*
X810058D03*
X924932Y687237D03*
Y696883D03*
X928672D03*
X932412Y687237D03*
Y696883D03*
X954023Y711157D03*
X961503D03*
X954023Y720803D03*
X961503D03*
X957763D03*
X1108045Y672360D03*
Y682006D03*
X1115525Y672360D03*
Y682006D03*
X1111785D03*
X1565132Y672360D03*
X1572612D03*
X1565132Y682006D03*
X1572612D03*
X1568872D03*
G54D106*
X311947Y342319D03*
X303285D03*
Y344878D03*
X311947Y347437D03*
X303285D03*
X652595Y653161D03*
X643933D03*
X652595Y658279D03*
X643933D03*
Y655720D03*
X760371Y342319D03*
Y344878D03*
Y347437D03*
X769033Y342319D03*
Y347437D03*
X1101020Y653161D03*
Y658279D03*
Y655720D03*
X1109682Y653161D03*
Y658279D03*
X1217458Y342319D03*
Y344878D03*
Y347437D03*
X1226120Y342319D03*
Y347437D03*
X1558107Y653161D03*
Y658279D03*
Y655720D03*
X1566769Y653161D03*
Y658279D03*
X1674545Y342319D03*
Y344878D03*
Y347437D03*
X1683207Y342319D03*
Y347437D03*
G54D115*
X390780Y748036D03*
Y750005D03*
Y751973D03*
Y753942D03*
Y755910D03*
Y757879D03*
Y759847D03*
Y761816D03*
Y763784D03*
Y765753D03*
Y767721D03*
Y769690D03*
Y771658D03*
Y773627D03*
Y775595D03*
Y777564D03*
X1763480Y880636D03*
Y882605D03*
Y884573D03*
Y886542D03*
Y888510D03*
Y890479D03*
Y892447D03*
Y894416D03*
Y896384D03*
Y898353D03*
Y900321D03*
Y902290D03*
Y904258D03*
Y906227D03*
Y908195D03*
Y910164D03*
G54D223*
X1042925Y1315612D03*
X1032295D03*
Y1319352D03*
X1042925Y1323092D03*
X1032295D03*
G54D31*
X19075Y281129D03*
Y287035D03*
X26161D03*
Y281129D03*
X42690Y454376D03*
X48596D03*
X42690Y461462D03*
X48596D03*
X108643Y136742D03*
X115729Y142648D03*
Y136742D03*
X108643Y142648D03*
X211005Y136742D03*
Y142648D03*
X218091D03*
Y136742D03*
X243078Y633786D03*
Y640872D03*
X248984Y633786D03*
Y640872D03*
X313367Y136742D03*
X320453Y142648D03*
Y136742D03*
X313367Y142648D03*
X463368Y136742D03*
X470454Y142648D03*
Y136742D03*
X463368Y142648D03*
X482532Y421374D03*
X488438D03*
X482532Y428460D03*
X488438D03*
X497776Y451376D03*
Y458462D03*
X503682D03*
Y451376D03*
X565730Y136742D03*
Y142648D03*
X572816D03*
Y136742D03*
X668092D03*
Y142648D03*
X675178D03*
Y136742D03*
X700164Y633786D03*
Y640872D03*
X706070Y633786D03*
Y640872D03*
X770454Y136742D03*
X777540Y142648D03*
Y136742D03*
X770454Y142648D03*
X920454Y136742D03*
X927540Y142648D03*
Y136742D03*
X920454Y142648D03*
X946064Y242721D03*
X940158D03*
X946064Y249807D03*
X940158D03*
X956863Y454376D03*
Y461462D03*
X962769Y454376D03*
Y461462D03*
X1022816Y136742D03*
Y142648D03*
X1029902D03*
Y136742D03*
X1125178D03*
X1132264Y142648D03*
Y136742D03*
X1125178Y142648D03*
X1157251Y633786D03*
Y640872D03*
X1163157Y633786D03*
Y640872D03*
X1227540Y136742D03*
X1234626Y142648D03*
Y136742D03*
X1227540Y142648D03*
X1295453Y938043D03*
Y930957D03*
X1289547D03*
Y938043D03*
X1377541Y136742D03*
X1384627Y142648D03*
Y136742D03*
X1377541Y142648D03*
X1411950Y451376D03*
Y458462D03*
X1417856D03*
Y451376D03*
X1432499Y1508327D03*
X1426593D03*
Y1515413D03*
X1432499D03*
X1479903Y136742D03*
Y142648D03*
X1486989D03*
Y136742D03*
X1582265D03*
X1589351Y142648D03*
Y136742D03*
X1582265Y142648D03*
X1603363Y1456276D03*
X1597457D03*
Y1463362D03*
X1603363D03*
X1620244Y633786D03*
X1614338D03*
X1620244Y640872D03*
X1614338D03*
X1684627Y136742D03*
X1691713Y142648D03*
Y136742D03*
X1684627Y142648D03*
G54D142*
X414519Y1253318D03*
Y1261804D03*
X512830Y1253318D03*
Y1261804D03*
X980085Y1486681D03*
Y1492797D03*
X1017867Y1486681D03*
Y1492797D03*
X1328693Y1253318D03*
Y1261804D03*
X1427004Y1253318D03*
Y1261804D03*
G54D13*
X12786Y82445D03*
X10292Y96728D03*
X14292D03*
X15948Y135809D03*
X11999Y135881D03*
X19855Y135904D03*
X12709Y170319D03*
X18826Y232994D03*
X11781Y1529404D03*
X10852Y1538639D03*
X6560Y1547628D03*
X18434Y1548699D03*
X20709Y170319D03*
X36201Y233076D03*
X24091Y233063D03*
X27966Y233051D03*
X29127Y1198716D03*
X27222Y1438644D03*
X48643Y445436D03*
X41643Y467436D03*
X46192Y636328D03*
X42192D03*
X50192D03*
X36692D03*
X40700Y1086663D03*
X58224Y467576D03*
X66224D03*
X53643Y467436D03*
X67684Y599742D03*
X54192Y636328D03*
X63988Y625184D03*
X57553Y1202752D03*
X53056Y1206881D03*
X54339Y1487989D03*
X60013Y1550212D03*
X66291Y1628319D03*
X73381Y88546D03*
X69381D03*
X77711Y173090D03*
X73711D03*
X77938Y184347D03*
X76877Y216699D03*
X80766Y259627D03*
X75819Y285000D03*
X79819D03*
X83819D03*
X83684Y599742D03*
X79684D03*
X71684D03*
X75684D03*
X73968Y662609D03*
X75049Y828235D03*
Y835649D03*
X70941Y1586782D03*
X74291Y1628319D03*
X78291D03*
X82291D03*
X70291D03*
X89845Y275318D03*
X87684Y599742D03*
X91057Y1025319D03*
X86291Y1628319D03*
X107607Y127840D03*
X117607D03*
X106796Y147846D03*
X121661Y127845D03*
X121840Y142954D03*
X120926Y232951D03*
X126453Y233063D03*
X130328Y233051D03*
X127235Y452598D03*
X138563Y233076D03*
X146400Y452317D03*
X175743Y88546D03*
X171743D03*
X179743D03*
X180073Y173090D03*
X176073D03*
X180300Y184347D03*
X179239Y216699D03*
X178181Y285000D03*
X182181D03*
X183752Y88546D03*
X183128Y259627D03*
X192207Y275318D03*
X186181Y285000D03*
X210482Y88821D03*
X214389Y88916D03*
X206533Y88893D03*
X211969Y127840D03*
X209158Y147846D03*
X219969Y127840D03*
X224023Y127845D03*
X224202Y142954D03*
X223288Y232951D03*
X228815Y233063D03*
X217939Y611981D03*
X221809Y611993D03*
X221084Y1479997D03*
X229753Y1534232D03*
X240925Y233076D03*
X232690Y233051D03*
X243278Y620880D03*
X247278D03*
X236498Y1475657D03*
X237753Y1534232D03*
X251278Y620880D03*
X278105Y88546D03*
X274105D03*
X278435Y173090D03*
X282105Y88546D03*
X286114D03*
X282435Y173090D03*
X282662Y184347D03*
X281601Y216699D03*
X285490Y259627D03*
X294569Y275318D03*
X280543Y285000D03*
X284543D03*
X288543D03*
X280500Y855731D03*
Y865831D03*
X286300Y890931D03*
Y901231D03*
X282300Y926431D03*
X282400Y936531D03*
X308895Y88893D03*
X312331Y127840D03*
X311520Y147867D03*
X312263Y311832D03*
X304543Y328959D03*
X316751Y88916D03*
X312844Y88821D03*
X322331Y127840D03*
X326385Y127845D03*
X326564Y142954D03*
X325650Y232951D03*
X331177Y233063D03*
X343287Y233076D03*
X335052Y233051D03*
X342285Y562229D03*
X341748Y1137221D03*
X341455Y1182062D03*
X342152Y1203535D03*
X338322Y1190987D03*
X347591Y394025D03*
X357748Y1137221D03*
X353748D03*
X349748D03*
X345471Y1181992D03*
X346387Y1203497D03*
X350402Y1203535D03*
X354402D03*
X358402D03*
X350400Y1195511D03*
X354400D03*
X358400D03*
X376467Y88546D03*
X377237Y373772D03*
X366486Y379665D03*
X370486D03*
X368587Y403558D03*
X364326Y481975D03*
X361748Y1137221D03*
X366157Y1147029D03*
X366133Y1165309D03*
X366400Y1195511D03*
X366402Y1203535D03*
X362402D03*
X362400Y1195511D03*
X386112Y30710D03*
X380467Y88546D03*
X388476D03*
X384467D03*
X384797Y173090D03*
X380797D03*
X385024Y184347D03*
X383963Y216699D03*
X387852Y259627D03*
X382905Y285000D03*
X386905D03*
X390905D03*
X379800Y772117D03*
X378472Y790286D03*
X391614Y933168D03*
X408680Y40035D03*
X396680D03*
X396931Y275318D03*
X398237Y373573D03*
X394553Y392919D03*
X401165Y445554D03*
X395390Y872787D03*
X399052Y881290D03*
X402966Y881391D03*
X403159Y1119914D03*
X409461Y1563526D03*
X405461D03*
X415677Y312778D03*
X423551D03*
X419277D03*
X424479Y362174D03*
X416318Y362166D03*
X421459Y625843D03*
X420400Y795631D03*
X412100D03*
X413461Y1563526D03*
X435025Y312778D03*
X431425D03*
X427151D03*
X435574Y439056D03*
X429673Y456118D03*
X433673D03*
X438157Y503126D03*
X431285Y1120913D03*
X435287Y1119914D03*
X444779Y633973D03*
X455619Y1252512D03*
X472332Y127840D03*
X464332D03*
X461521Y147846D03*
X461091Y1024783D03*
X463413Y1120913D03*
X468746Y1119914D03*
X460574Y1252513D03*
X476386Y127845D03*
X476565Y142954D03*
X481178Y233063D03*
X475651Y232951D03*
X485053Y233051D03*
X488485Y412434D03*
X481485Y434434D03*
X488745Y677434D03*
X488091Y992283D03*
X493288Y233076D03*
X493485Y434434D03*
X503729Y442436D03*
X496729Y464436D03*
X503278Y636328D03*
X499278D03*
X507278D03*
X493778D03*
X491373Y654714D03*
X493914Y677452D03*
X505464Y670170D03*
X492091Y992283D03*
X500874Y1119914D03*
X496872Y1120913D03*
X521310Y464576D03*
X513310D03*
X508729Y464436D03*
X511278Y636328D03*
X521074Y625184D03*
X517464Y670170D03*
X513464D03*
X509464D03*
X517412Y758924D03*
X514576Y786320D03*
X519763Y786247D03*
X538477Y88546D03*
X530468D03*
X534468D03*
X526468D03*
X534798Y173090D03*
X530798D03*
X535025Y184347D03*
X533964Y216699D03*
X537853Y259627D03*
X532906Y285000D03*
X536906D03*
X528770Y599742D03*
X532770D03*
X536770D03*
X524770D03*
X537964Y670170D03*
X533964D03*
X529964D03*
X525964D03*
X529000Y1120913D03*
X546932Y275318D03*
X540906Y285000D03*
X544770Y599742D03*
X540770D03*
X542400Y844831D03*
X548144Y1025319D03*
X569114Y88916D03*
X565207Y88821D03*
X561258Y88893D03*
X564694Y127840D03*
X563883Y147846D03*
X567958Y1532332D03*
X574694Y127840D03*
X578748Y127845D03*
X578927Y142954D03*
X578013Y232951D03*
X583540Y233063D03*
X587415Y233051D03*
X584321Y452598D03*
X574504Y750401D03*
X587858Y1520832D03*
X579758Y1520732D03*
X575809Y1535518D03*
X583809D03*
X595650Y233076D03*
X603486Y452317D03*
X592103Y942324D03*
Y949738D03*
X591858Y1526932D03*
X595809Y1535518D03*
X632830Y88546D03*
X636830D03*
X628830D03*
X637160Y173090D03*
X633160D03*
X637387Y184347D03*
X636326Y216699D03*
X635268Y285000D03*
X640839Y88546D03*
X640215Y259627D03*
X649294Y275318D03*
X639268Y285000D03*
X643268D03*
X663620Y88893D03*
X667569Y88821D03*
X669056Y127840D03*
X666245Y147846D03*
X658064Y653253D03*
X662064D03*
X671476Y88916D03*
X677056Y127840D03*
X681110Y127845D03*
X681289Y142954D03*
X680375Y232951D03*
X685902Y233063D03*
X698012Y233076D03*
X689777Y233051D03*
X700364Y620880D03*
X693163Y697165D03*
X704364Y620880D03*
X708364D03*
X731192Y88546D03*
X720260Y696639D03*
X732170Y1622107D03*
X743201Y88546D03*
X739192D03*
X735192D03*
X739522Y173090D03*
X735522D03*
X739749Y184347D03*
X738688Y216699D03*
X742577Y259627D03*
X737630Y285000D03*
X741630D03*
X745630D03*
X751140Y1583827D03*
X735392Y1599282D03*
X744924Y1611885D03*
X743331Y1630736D03*
X765982Y88893D03*
X751656Y275318D03*
X761629Y328959D03*
X755187Y1583841D03*
X759452Y1613859D03*
X773838Y88916D03*
X769931Y88821D03*
X769418Y127840D03*
X779418D03*
X783472Y127845D03*
X783651Y142954D03*
X768607Y147846D03*
X782737Y232951D03*
X769349Y311832D03*
X774844Y1619487D03*
X778358Y1630218D03*
X788264Y233063D03*
X792139Y233051D03*
X799371Y562229D03*
X798835Y1137221D03*
X798542Y1182062D03*
X795159Y1188708D03*
X795418Y1203435D03*
X796972Y1394695D03*
X800374Y233076D03*
X813821Y735388D03*
X816027Y867772D03*
X806835Y1137221D03*
X814835D03*
X810835D03*
X802558Y1181992D03*
X815487Y1195511D03*
X811487D03*
X807487D03*
X815489Y1203535D03*
X811489D03*
X807489D03*
X803604Y1203492D03*
X802333Y1195028D03*
X806148Y1377700D03*
X810148D03*
X805009Y1469602D03*
X821412Y476975D03*
X830484Y741243D03*
X826484D03*
X822831Y836758D03*
X818831D03*
X820027Y867772D03*
X819629Y892647D03*
X828909Y908560D03*
X830913Y926694D03*
X818835Y1137221D03*
X823244Y1147029D03*
X823220Y1165309D03*
X823489Y1203535D03*
X819487Y1195511D03*
X823487D03*
X819489Y1203535D03*
X833554Y88546D03*
X837554D03*
X845563D03*
X841554D03*
X841884Y173090D03*
X837884D03*
X842111Y184347D03*
X841050Y216699D03*
X844939Y259627D03*
X839992Y285000D03*
X843992D03*
X847992D03*
X846098Y411754D03*
X834484Y741243D03*
X846484D03*
X838484D03*
X842484D03*
X833112Y826730D03*
X832726Y840571D03*
X836311Y874105D03*
X844946Y908560D03*
X840909D03*
X836909D03*
X832909D03*
X838829Y926694D03*
X834829D03*
X845395D03*
X836423Y959211D03*
X832423D03*
X854018Y275318D03*
X863086Y377017D03*
X849680Y689131D03*
X854484Y741243D03*
X850484D03*
X852628Y909606D03*
X860628D03*
X849544Y1451276D03*
X872293Y88821D03*
X876200Y88916D03*
X868344Y88893D03*
X878500Y197442D03*
X879740Y257226D03*
X868086Y377017D03*
X876736Y385797D03*
X867586Y387517D03*
X869342Y411559D03*
X875916Y803407D03*
X879916Y813557D03*
X876628Y909606D03*
X868628D03*
X872817Y1207719D03*
X889879Y409260D03*
X896491Y461895D03*
X896431Y536585D03*
X891933Y612685D03*
X884045Y747252D03*
X887916Y803407D03*
X883916D03*
Y813557D03*
X887916D03*
X891916Y803407D03*
X884628Y909606D03*
X887390Y1095666D03*
X896746Y1215884D03*
X891844Y1452176D03*
X897736Y385797D03*
X903431Y536585D03*
X911416Y803407D03*
X910900Y909517D03*
X906128Y956107D03*
X901243Y1211755D03*
X908852Y1225025D03*
X912726D03*
X929418Y127840D03*
X921418D03*
X918607Y147846D03*
X927072Y381424D03*
X923072D03*
X919072D03*
X924999Y472459D03*
X928999D03*
X917250Y551637D03*
X927916Y803407D03*
X923790D03*
X919664D03*
X915716D03*
X914500Y909517D03*
X918100D03*
X924628Y909606D03*
X928628D03*
X925697Y1454343D03*
X921868Y1454373D03*
X933472Y127845D03*
X933651Y142954D03*
X938930Y218234D03*
X942805Y218222D03*
X938657Y364728D03*
X930900Y455397D03*
X931916Y811557D03*
X943916D03*
X945035Y830274D03*
X943735Y844674D03*
X936616Y895121D03*
X932716D03*
X936628Y909606D03*
X944628D03*
X940628D03*
X932628D03*
X936794Y1207719D03*
X951040Y218247D03*
X955816Y467436D03*
X960365Y636328D03*
X956365D03*
X950865D03*
X947556Y702142D03*
X955950Y728555D03*
X948935Y830274D03*
X950335Y823374D03*
X958682Y831445D03*
X958200Y838617D03*
X950100Y850517D03*
X954000D03*
X954124Y880087D03*
X954567Y930336D03*
X957671Y985760D03*
X951367Y1095666D03*
X960723Y1215884D03*
X962816Y445436D03*
X972397Y467496D03*
X967816Y467436D03*
X968365Y636328D03*
X978161Y625184D03*
X964365Y636328D03*
X973712Y716606D03*
X965220Y1211755D03*
X983554Y88546D03*
X987554D03*
X991554D03*
X991884Y173090D03*
X987884D03*
X992111Y184347D03*
X991050Y216699D03*
X989992Y285000D03*
X993992D03*
X990405Y318267D03*
X984045Y361101D03*
X980045D03*
X980397Y467576D03*
X981857Y599742D03*
X989857D03*
X993857D03*
X985857D03*
X991990Y768491D03*
X987990D03*
X990051Y813860D03*
X995563Y88546D03*
X994939Y259627D03*
X1004018Y275318D03*
X997992Y285000D03*
X1004635Y302768D03*
X1008635D03*
X997857Y599742D03*
X1001857D03*
X1003990Y768491D03*
X999990D03*
X1005230Y1025319D03*
X1018344Y88893D03*
X1022293Y88821D03*
X1026200Y88916D03*
X1021780Y127840D03*
X1020969Y147846D03*
X1021259Y1313539D03*
X1024115Y1330906D03*
X1031780Y127840D03*
X1035834Y127845D03*
X1036013Y142954D03*
X1035099Y232951D03*
X1040626Y233063D03*
X1033786Y302768D03*
X1037386D03*
X1041496D03*
X1041408Y452598D03*
X1033719Y939339D03*
Y946753D03*
X1052736Y233076D03*
X1044501Y233051D03*
X1060573Y452317D03*
X1066260Y1442483D03*
X1085916Y88546D03*
X1089916D03*
X1090246Y173090D03*
X1086904Y1593298D03*
X1090469Y1582502D03*
X1083735Y1603715D03*
Y1611651D03*
X1085474Y1631942D03*
X1093916Y88546D03*
X1097925D03*
X1094246Y173090D03*
X1094473Y184347D03*
X1093412Y216699D03*
X1097301Y259627D03*
X1106380Y275318D03*
X1092354Y285000D03*
X1096354D03*
X1100354D03*
X1098376Y1554275D03*
X1093376D03*
X1098904Y1593298D03*
X1094904D03*
X1100233Y1582525D03*
X1104612Y1603694D03*
X1097474Y1631942D03*
X1124655Y88821D03*
X1120706Y88893D03*
X1123331Y147846D03*
X1115151Y653253D03*
X1119151D03*
X1128562Y88916D03*
X1134142Y127840D03*
X1126142D03*
X1138196Y127845D03*
X1138375Y142954D03*
X1137461Y232951D03*
X1142988Y233063D03*
X1155098Y233076D03*
X1146863Y233051D03*
X1152485Y767659D03*
X1157451Y620880D03*
X1161451D03*
X1165451D03*
X1168485Y767527D03*
X1160485Y767659D03*
X1164485D03*
X1188278Y88546D03*
X1180715Y778985D03*
X1196278Y88546D03*
X1200287D03*
X1192278D03*
X1196608Y173090D03*
X1192608D03*
X1196835Y184347D03*
X1195774Y216699D03*
X1199663Y259627D03*
X1194716Y285000D03*
X1198716D03*
X1202716D03*
X1208742Y275318D03*
X1218716Y328959D03*
X1227017Y88821D03*
X1230924Y88916D03*
X1223068Y88893D03*
X1236504Y127840D03*
X1226504D03*
X1225693Y147846D03*
X1226436Y311832D03*
X1240558Y127845D03*
X1240737Y142954D03*
X1239823Y232951D03*
X1245350Y233063D03*
X1249225Y233051D03*
X1251302Y1198942D03*
X1257460Y233076D03*
X1261764Y394025D03*
X1256458Y562229D03*
X1263921Y1137221D03*
X1267921D03*
X1255921D03*
X1255628Y1182062D03*
X1259644Y1181992D03*
X1264575Y1203535D03*
X1268575D03*
X1264573Y1195511D03*
X1268573D03*
X1260535Y1203540D03*
X1260771Y1193837D03*
X1280659Y379665D03*
X1284659D03*
X1282760Y403558D03*
X1278499Y481975D03*
X1284655Y895017D03*
X1275493Y924010D03*
X1279493D03*
X1283493D03*
X1271493D03*
X1275921Y1137221D03*
X1271921D03*
X1280330Y1147029D03*
X1280306Y1165309D03*
X1276575Y1203535D03*
X1280573Y1195511D03*
X1276573D03*
X1280575Y1203535D03*
X1272575D03*
X1272573Y1195511D03*
X1300285Y30710D03*
X1298640Y88546D03*
X1294640D03*
X1302649D03*
X1290640D03*
X1298970Y173090D03*
X1294970D03*
X1299197Y184347D03*
X1298136Y216699D03*
X1302025Y259627D03*
X1297078Y285000D03*
X1301078D03*
X1291500Y321517D03*
X1291410Y373772D03*
X1292000Y895017D03*
X1289500Y944017D03*
X1296500Y964017D03*
X1310853Y40035D03*
X1311104Y275318D03*
X1305078Y285000D03*
X1318262Y315870D03*
X1312410Y373573D03*
X1308726Y392919D03*
X1315338Y445554D03*
X1318500Y920017D03*
X1314500D03*
X1317000Y931017D03*
X1318500Y962017D03*
X1311000Y964017D03*
X1315000D03*
X1317333Y1119914D03*
X1322853Y40035D03*
X1329736Y315870D03*
X1334010D03*
X1321862D03*
X1326136D03*
X1320903Y365258D03*
X1329064Y365266D03*
X1327584Y779122D03*
X1330500Y920017D03*
X1334500D03*
X1326500Y931017D03*
X1337610Y315870D03*
X1349747Y439056D03*
X1343846Y456118D03*
X1347846D03*
X1345000Y790517D03*
X1348917D03*
X1342500Y920017D03*
X1338500D03*
X1345948Y946120D03*
X1349948D03*
X1336000Y931017D03*
X1345459Y1120913D03*
X1349461Y1119914D03*
X1352817Y790517D03*
X1365000Y806517D03*
X1361000D03*
X1357000D03*
X1365948Y946120D03*
X1357948D03*
X1353948D03*
X1378505Y127840D03*
X1375694Y147846D03*
X1380500Y590517D03*
Y637017D03*
Y681517D03*
Y728517D03*
X1373000Y806517D03*
X1381000D03*
X1369000D03*
X1377017Y806515D03*
X1369948Y946120D03*
X1382560Y934338D03*
X1378503Y934337D03*
X1375265Y1024783D03*
X1377587Y1120913D03*
X1382920Y1119914D03*
X1386505Y127840D03*
X1390559Y127845D03*
X1390738Y142954D03*
X1389824Y232951D03*
X1395351Y233063D03*
X1399226Y233051D03*
X1394537Y806196D03*
X1398517Y806234D03*
X1407461Y233076D03*
X1410903Y464436D03*
X1413452Y636328D03*
X1407952D03*
X1402517Y806234D03*
X1406483D03*
X1402265Y992283D03*
X1406265D03*
X1411046Y1120913D03*
X1415048Y1119914D03*
X1407747Y1543477D03*
X1407255Y1566155D03*
X1417903Y442436D03*
X1427484Y464576D03*
X1422903Y464436D03*
X1425452Y636328D03*
X1417452D03*
X1421452D03*
X1432258Y1407832D03*
X1444641Y88546D03*
X1440641D03*
X1448641D03*
X1448971Y173090D03*
X1444971D03*
X1449198Y184347D03*
X1448137Y216699D03*
X1447079Y285000D03*
X1435484Y464576D03*
X1442944Y599742D03*
X1438944D03*
X1446944D03*
X1435248Y625184D03*
X1437980Y1028464D03*
X1443174Y1120913D03*
X1436258Y1407832D03*
X1437293Y1540507D03*
X1436801Y1563185D03*
X1452650Y88546D03*
X1452026Y259627D03*
X1461105Y275318D03*
X1451079Y285000D03*
X1455079D03*
X1454944Y599742D03*
X1458944D03*
X1450944D03*
X1462317Y1025319D03*
X1479380Y88821D03*
X1475431Y88893D03*
X1478867Y127840D03*
X1478056Y147846D03*
X1471500Y713017D03*
Y757017D03*
X1483287Y88916D03*
X1488867Y127840D03*
X1492921Y127845D03*
X1493100Y142954D03*
X1492186Y232951D03*
X1497713Y233063D03*
X1488500Y798517D03*
Y842517D03*
X1509823Y233076D03*
X1501588Y233051D03*
X1498495Y452598D03*
X1517660Y452317D03*
X1547003Y88546D03*
X1543003D03*
X1555012D03*
X1551003D03*
X1551333Y173090D03*
X1547333D03*
X1551560Y184347D03*
X1550499Y216699D03*
X1554388Y259627D03*
X1549441Y285000D03*
X1553441D03*
X1557441D03*
X1577793Y88893D03*
X1563467Y275318D03*
X1572238Y653253D03*
X1576238D03*
X1585649Y88916D03*
X1581742Y88821D03*
X1591229Y127840D03*
X1583229D03*
X1595283Y127845D03*
X1595462Y142954D03*
X1580418Y147846D03*
X1594548Y232951D03*
X1587746Y1457649D03*
X1594264Y1470032D03*
X1600075Y233063D03*
X1603950Y233051D03*
X1601500Y1509017D03*
X1598000D03*
X1608500D03*
X1610858Y1520332D03*
X1612185Y233076D03*
X1614538Y620880D03*
X1618538D03*
X1622538D03*
X1653365Y88546D03*
X1657374D03*
X1645365D03*
X1649365D03*
X1653695Y173090D03*
X1649695D03*
X1653922Y184347D03*
X1652861Y216699D03*
X1656750Y259627D03*
X1651803Y285000D03*
X1655803D03*
X1659803D03*
X1665829Y275318D03*
X1675803Y328959D03*
X1680155Y88893D03*
X1684104Y88821D03*
X1688011Y88916D03*
X1683591Y127840D03*
X1682780Y147846D03*
X1683523Y311832D03*
X1693591Y127840D03*
X1697645Y127845D03*
X1697824Y142954D03*
X1702437Y233063D03*
X1696910Y232951D03*
X1706312Y233051D03*
X1714547Y233076D03*
X1718851Y394025D03*
X1713545Y562229D03*
X1721008Y1137221D03*
X1725008D03*
X1713008D03*
X1712715Y1182062D03*
X1716731Y1181992D03*
X1721662Y1203535D03*
X1725662D03*
X1721660Y1195511D03*
X1725660D03*
X1709820Y1196607D03*
X1717568Y1203335D03*
X1741746Y379665D03*
X1737746D03*
X1739847Y403558D03*
X1735586Y481975D03*
X1733008Y1137221D03*
X1729008D03*
X1737417Y1147029D03*
X1737393Y1165309D03*
X1729662Y1203535D03*
X1733662D03*
X1737660Y1195511D03*
X1729660D03*
X1733660D03*
X1737662Y1203535D03*
X1751727Y88546D03*
X1755727D03*
X1747727D03*
X1756057Y173090D03*
X1752057D03*
X1756284Y184347D03*
X1755223Y216699D03*
X1754165Y285000D03*
X1758165D03*
X1748497Y373772D03*
X1750900Y904917D03*
X1756422Y1634821D03*
X1759736Y88546D03*
X1759112Y259627D03*
X1768191Y275318D03*
X1762165Y285000D03*
X1769497Y373573D03*
X1765813Y392919D03*
X1772425Y445554D03*
X1761072Y1593284D03*
X1765072D03*
X1772422Y1634821D03*
X1768422D03*
X1760422D03*
X1764422D03*
X1782517Y88893D03*
X1786466Y88821D03*
X1790373Y88916D03*
X1776071Y833411D03*
X1789537Y924594D03*
X1780774Y1208205D03*
X1778227Y1440625D03*
X1778104Y1472815D03*
X1776422Y1634821D03*
X1806834Y439056D03*
X1800933Y456118D03*
X1804933D03*
X1797374Y924466D03*
X1795347Y1096152D03*
X1804703Y1216370D03*
X1800046Y1437663D03*
X1799923Y1469853D03*
X1809700Y907117D03*
X1808363Y970177D03*
Y977591D03*
X1809200Y1212241D03*
G54D133*
X419839Y350114D03*
X421413D03*
X422988D03*
X424563D03*
X430862D03*
X437161D03*
X426138D03*
X429287D03*
X435587D03*
X427713D03*
X432437D03*
X434012D03*
X1322424Y353206D03*
X1323998D03*
X1333447D03*
X1328723D03*
X1331872D03*
X1325573D03*
X1327148D03*
X1330298D03*
X1335022D03*
X1339746D03*
X1338172D03*
X1336597D03*
G54D124*
X417211Y1133067D03*
X449339D03*
X482798D03*
X514926D03*
X1331385D03*
X1363513D03*
X1396972D03*
X1429100D03*
G54D14*
X8786Y82444D03*
X6298Y96682D03*
X18298D03*
X6499Y135880D03*
X15184Y147319D03*
X19184D03*
X8264Y156046D03*
X16709Y170318D03*
X17822Y209922D03*
X6811Y1002637D03*
X10701D03*
X14645D03*
X11768Y1522289D03*
X14375Y1547589D03*
X10367Y1547596D03*
X31971Y103502D03*
X23184Y147319D03*
X32201Y233075D03*
X26192Y613827D03*
X30192D03*
X33992D03*
X27556Y1002637D03*
X33659D03*
X21506D03*
X25674Y1488807D03*
X35850Y1550246D03*
X26231Y1548675D03*
X22381Y1548693D03*
X45643Y467435D03*
X49643D03*
X39549Y1002637D03*
X45858D03*
X51946D03*
X40951Y1550246D03*
X47074Y1550237D03*
X52048Y1550212D03*
X65759Y440010D03*
X61759D03*
X57759D03*
X54936Y451854D03*
X62224Y467575D03*
X66345Y487180D03*
X56514Y533924D03*
X64408Y575848D03*
X63684Y599741D03*
X61192Y636327D03*
X57692D03*
X64692D03*
X56149Y821324D03*
X65774Y1002637D03*
X61779D03*
X57834D03*
X57702Y1195761D03*
X61380Y1202487D03*
X53737Y1196921D03*
X54351Y1480899D03*
X56114Y1550211D03*
X64747Y1550204D03*
X63090Y1612093D03*
X70577Y98642D03*
X84808Y100544D03*
X80660Y98289D03*
X76660D03*
X76766Y259626D03*
X84766D03*
X78106Y659507D03*
X74910Y684528D03*
X84699Y1001482D03*
X87652Y575653D03*
X93456Y652341D03*
X95836Y983047D03*
X99836Y992047D03*
X95836D03*
X99836Y983047D03*
X97609Y1010913D03*
X104662Y113567D03*
X115582Y104840D03*
X111582D03*
X113607Y127839D03*
X106796Y154956D03*
X111836Y983047D03*
X103836D03*
X115836D03*
X107836D03*
X111836Y992047D03*
X103836D03*
X115836D03*
X107836D03*
X109601Y1223542D03*
X105601D03*
X119582Y104840D03*
X128251Y143853D03*
X120184Y209922D03*
X127235Y445597D03*
X119836Y983047D03*
X123836D03*
X127836D03*
X119836Y992047D03*
X123836D03*
X127836D03*
X131836Y983047D03*
Y992047D03*
X127604Y1102624D03*
Y1115224D03*
Y1140424D03*
Y1127824D03*
Y1153024D03*
Y1165624D03*
Y1178224D03*
X134333Y103502D03*
X134563Y233075D03*
X138971Y538907D03*
X142961Y538866D03*
X143836Y983047D03*
X147836D03*
X139836D03*
X143836Y992047D03*
X147836D03*
X139836D03*
X135836Y983047D03*
Y992047D03*
X139250Y1009887D03*
Y1022487D03*
X159836Y983047D03*
Y992047D03*
X155836D03*
X151836Y983047D03*
Y992047D03*
X172939Y98642D03*
X179022Y98289D03*
X179128Y259626D03*
X183022Y98289D03*
X188526Y97566D03*
Y105178D03*
X187128Y259626D03*
X201033Y88892D03*
X207024Y113567D03*
X213944Y104840D03*
X209158Y154956D03*
X221944Y104840D03*
X217944D03*
X215969Y127839D03*
X230613Y143853D03*
X222546Y209922D03*
X229942Y1546401D03*
X221942Y1534401D03*
X225753Y1534231D03*
X236695Y103502D03*
X236925Y233075D03*
X242102Y650762D03*
X246102D03*
X240842Y1527401D03*
X237942Y1546401D03*
X244942D03*
X233942D03*
X233753Y1534231D03*
X250102Y650762D03*
X248042Y1527401D03*
X275301Y98642D03*
X281384Y98289D03*
X290888Y97566D03*
X285384Y98289D03*
X290888Y105178D03*
X289490Y259626D03*
X281490D03*
X303395Y88892D03*
X309386Y113567D03*
X311520Y154956D03*
X312263Y318831D03*
X324306Y104840D03*
X320306D03*
X316306D03*
X318222Y127730D03*
X324908Y209922D03*
X317416Y342410D03*
X321416D03*
X323285Y550228D03*
X339057Y103502D03*
X332975Y143853D03*
X339287Y233075D03*
X342486Y379664D03*
X342285Y555228D03*
X336755Y1137220D03*
X337629Y1175841D03*
X342298Y1190932D03*
X346486Y379664D03*
X358486D03*
X350486D03*
X354486D03*
X353202Y409018D03*
X345748Y1137220D03*
X350414Y1175181D03*
X358443Y1174202D03*
X354414Y1175181D03*
X359761Y1182142D03*
X354442Y1182146D03*
X350442D03*
X346136Y1191067D03*
X370931Y364380D03*
X362486Y379664D03*
X374714Y790285D03*
X365748Y1137220D03*
X362282Y1174865D03*
X363729Y1182179D03*
X377663Y98642D03*
X393250Y97566D03*
X387746Y98289D03*
X383746D03*
X393250Y105178D03*
X383852Y259626D03*
X391852D03*
X389237Y373570D03*
X381237D03*
X385237D03*
X404686Y39989D03*
X400686D03*
X394237Y373572D03*
X403478Y872784D03*
X399369D03*
X399816Y953163D03*
X400043Y964420D03*
X404043D03*
X403263Y1155275D03*
X397461Y1563525D03*
X401461D03*
X420422Y362173D03*
X412318Y362165D03*
X411847Y429353D03*
X425673Y456117D03*
X426000Y786316D03*
X416200Y795616D03*
X417682Y1054729D03*
X410668Y1102646D03*
X414455D03*
X422532Y1098858D03*
X421461Y1563525D03*
X417461D03*
X431424Y362034D03*
X435024D03*
X427566Y880949D03*
X427913Y1098858D03*
X431285Y1110412D03*
X449745Y625576D03*
X445745D03*
X442796Y1102646D03*
X446583D03*
X454660Y1098858D03*
X456025Y1218004D03*
X459387Y113567D03*
X474307Y104840D03*
X470307D03*
X466307D03*
X468332Y127839D03*
X461521Y154956D03*
X474909Y209922D03*
X468836Y540113D03*
X460041Y1098858D03*
X463413Y1110412D03*
X468850Y1155275D03*
X462687D03*
X461319Y1218004D03*
X489058Y103502D03*
X482976Y143853D03*
X489288Y233075D03*
X485485Y434433D03*
X489485D03*
X491078Y613827D03*
X483278D03*
X487278D03*
X476255Y1102646D03*
X480042D03*
X488119Y1098858D03*
X500729Y464435D03*
X504729D03*
X501082Y989697D03*
X505958Y1055022D03*
X493500Y1098858D03*
X496872Y1110412D03*
X520845Y437010D03*
X516845D03*
X512845D03*
X510022Y448854D03*
X517310Y464575D03*
X523431Y487180D03*
X513600Y533924D03*
X521494Y575848D03*
X520770Y599741D03*
X516770D03*
X518278Y636327D03*
X514778D03*
X521778D03*
X519285Y725512D03*
X515285D03*
X511285D03*
X523285D03*
X509096Y755806D03*
X513504Y758923D03*
X508383Y1102646D03*
X512170D03*
X520247Y1098858D03*
X527664Y98642D03*
X537747Y98289D03*
X533747D03*
X533853Y259626D03*
X539285Y725512D03*
X535285D03*
X531285D03*
X527285D03*
X524319Y758897D03*
X536715Y1006337D03*
X529000Y1110412D03*
X528274Y1155275D03*
X555758Y88892D03*
X543251Y97566D03*
Y105178D03*
X541853Y259626D03*
X544738Y575653D03*
X552923Y983047D03*
Y992047D03*
X554696Y1010913D03*
X561749Y113567D03*
X568669Y104840D03*
X570694Y127839D03*
X563883Y154956D03*
X568464Y754990D03*
X560256Y776190D03*
X556923Y983047D03*
Y992047D03*
X568923Y983047D03*
X560923D03*
X564923D03*
X568923Y992047D03*
X560923D03*
X564923D03*
X562688Y1223542D03*
X566688D03*
X564242Y1525201D03*
X571942Y1544301D03*
X571809Y1535517D03*
X562786Y1534625D03*
X558786D03*
X576669Y104840D03*
X572669D03*
X585338Y143853D03*
X577271Y209922D03*
X584321Y445597D03*
X573203Y935413D03*
X576923Y983047D03*
X580923D03*
X584923D03*
X576923Y992047D03*
X580923D03*
X584923D03*
X572923Y983047D03*
Y992047D03*
X584691Y1102624D03*
Y1115224D03*
Y1140424D03*
Y1127824D03*
Y1153024D03*
Y1165624D03*
Y1178224D03*
X583742Y1544801D03*
X587809Y1535517D03*
X579809D03*
X591420Y103502D03*
X591650Y233075D03*
X600047Y538866D03*
X596057Y538907D03*
X600923Y983047D03*
X604923D03*
X592923D03*
X596923D03*
X600923Y992047D03*
X604923D03*
X592923D03*
X596923D03*
X588923Y983047D03*
Y992047D03*
X596337Y1009887D03*
Y1022487D03*
X600242Y1538601D03*
X591809Y1535517D03*
X608923Y992047D03*
X616923D03*
X612923D03*
X608923Y983047D03*
X616923D03*
X630026Y98642D03*
X636109Y98289D03*
X636215Y259626D03*
X645613Y97566D03*
X640109Y98289D03*
X645613Y105178D03*
X644215Y259626D03*
X658120Y88892D03*
X664111Y113567D03*
X666245Y154956D03*
X679031Y104840D03*
X671031D03*
X675031D03*
X673056Y127839D03*
X679633Y209922D03*
X693782Y103502D03*
X687700Y143853D03*
X694012Y233075D03*
X699188Y650762D03*
X688728Y700450D03*
X703188Y650762D03*
X707188D03*
X713382Y702253D03*
X732388Y98642D03*
X723811Y739072D03*
X742471Y98289D03*
X747975Y97566D03*
X738471Y98289D03*
X747975Y105178D03*
X738577Y259626D03*
X746577D03*
X747140Y1583826D03*
X748924Y1611884D03*
X748997Y1621426D03*
X747590Y1630725D03*
X760482Y88892D03*
X766473Y113567D03*
X763145Y1583804D03*
X759169Y1583851D03*
X763452Y1613858D03*
X752150Y1630750D03*
X781393Y104840D03*
X773393D03*
X777393D03*
X775418Y127839D03*
X768607Y154956D03*
X781995Y209922D03*
X769349Y318831D03*
X774502Y342410D03*
X778502D03*
X780371Y550228D03*
X767512Y1446718D03*
X783215Y1449666D03*
X777033Y1589513D03*
X781110D03*
X767452Y1613858D03*
X773822Y1630241D03*
X796144Y103502D03*
X790062Y143853D03*
X796374Y233075D03*
X799371Y555228D03*
X793842Y1137220D03*
X794716Y1175841D03*
X799230Y1203547D03*
X798324Y1195125D03*
X799901Y1469617D03*
X791610Y1596529D03*
X787447Y1596552D03*
X802835Y1137220D03*
X811529Y1182146D03*
X811501Y1175181D03*
X807501D03*
X807529Y1182146D03*
X814148Y1377699D03*
X832284Y713530D03*
X827284Y706580D03*
Y713530D03*
X828880Y867380D03*
X828643Y893105D03*
X826987Y926721D03*
X831409Y919309D03*
X827409D03*
X828423Y959210D03*
X822835Y1137220D03*
X816848Y1182142D03*
X820826Y1175229D03*
X820816Y1182179D03*
X816826Y1175229D03*
X834750Y98642D03*
X840833Y98289D03*
X844833D03*
X840939Y259626D03*
X848284Y713530D03*
X839290Y706560D03*
X843284Y706580D03*
X839290Y713510D03*
X843284Y713530D03*
X833112Y833606D03*
X836405Y860508D03*
X832880Y867380D03*
X832643Y893105D03*
X842000Y898516D03*
X848628Y909605D03*
X846000Y898516D03*
X841064Y919109D03*
X837235D03*
X840423Y959210D03*
X862844Y88892D03*
X850337Y97566D03*
Y105178D03*
X848939Y259626D03*
X858586Y377016D03*
X854086D03*
X858586Y387516D03*
X854086D03*
X863086D03*
X852284Y706580D03*
Y713530D03*
X856628Y909605D03*
X864628D03*
X849205Y926725D03*
X852488Y1014169D03*
X857884D03*
X864007D03*
X874531Y197441D03*
X880736Y385796D03*
X875916Y813556D03*
X872628Y909605D03*
X880628D03*
X879740Y941217D03*
X870401Y1014169D03*
X875954D03*
X893736Y385796D03*
X888736D03*
X884736D03*
X892931Y536584D03*
X885931D03*
X889431D03*
X895933Y612684D03*
X892728Y789792D03*
X895916Y813556D03*
X888628Y909605D03*
X892628D03*
X896628D03*
X881454Y1014169D03*
X885210D03*
X889089D03*
X893613Y1014312D03*
X904614Y340380D03*
X908114D03*
X911072Y381423D03*
X907173Y445694D03*
X899931Y536584D03*
X913208Y612535D03*
X909208D03*
X904376Y612455D03*
X900376D03*
X903916Y803406D03*
X899916Y813556D03*
Y803406D03*
X903916Y813556D03*
X909416D03*
X900200Y909616D03*
X907300D03*
X903700D03*
X912628Y922642D03*
X904057Y937629D03*
X906255Y1015797D03*
X898046Y1014256D03*
X902225Y1015744D03*
X901392Y1204764D03*
X897427Y1205924D03*
X905070Y1211490D03*
X916473Y113567D03*
X927393Y104840D03*
X923393D03*
X925418Y127839D03*
X918607Y154956D03*
X915072Y381423D03*
X920999Y472458D03*
X925418Y677886D03*
X921418D03*
X921061Y709861D03*
X925061D03*
X927916Y811556D03*
X921790Y813556D03*
X920628Y922642D03*
X924628D03*
X928628D03*
X916628D03*
X927984Y1014169D03*
X916465D03*
X921861D03*
X931393Y104840D03*
X940062Y143853D03*
X932661Y195093D03*
X938125Y233760D03*
X942757Y254705D03*
X941685Y357769D03*
X942437Y364721D03*
X931072Y381423D03*
X940365Y613827D03*
X944365D03*
X932412Y677886D03*
X938526Y727541D03*
X935916Y811556D03*
X939916D03*
X941535Y823573D03*
X937635D03*
X940516Y895121D03*
X944628Y922642D03*
X936628D03*
X940628D03*
X932628D03*
X945671Y985759D03*
X939931Y1014169D03*
X945431D03*
X934378D03*
X946144Y103502D03*
X947040Y218246D03*
X951278Y238064D03*
Y245043D03*
X959816Y467435D03*
X948165Y613827D03*
X961503Y701348D03*
X953551D03*
X957551D03*
X959950Y728554D03*
X952783Y830299D03*
X951100Y838616D03*
X947200D03*
X957900Y850516D03*
X958567Y930335D03*
X950567D03*
X953671Y985759D03*
X961671D03*
X949671D03*
X950987Y1014169D03*
X954866D03*
X961404Y1205924D03*
X975932Y440010D03*
X971932D03*
X969109Y451854D03*
X963816Y467435D03*
X976397Y467575D03*
X970687Y533924D03*
X978581Y575848D03*
X977857Y599741D03*
X973857D03*
X975365Y636327D03*
X971865D03*
X963950Y728554D03*
X966746Y930308D03*
X962567Y930335D03*
X965671Y985759D03*
X967625Y1014400D03*
X971760Y1014420D03*
X963823Y1014256D03*
X975659Y1014441D03*
X965369Y1204764D03*
X969047Y1211490D03*
X984750Y98642D03*
X990833Y98289D03*
X994833D03*
X990939Y259626D03*
X990405Y311033D03*
X988045Y361100D03*
X992045D03*
X979932Y440010D03*
X980518Y487180D03*
X978865Y636327D03*
X983712Y716605D03*
X994051Y813859D03*
X1000337Y97566D03*
Y105178D03*
X998939Y259626D03*
X1000698Y302767D03*
X996045Y361100D03*
X1001825Y575653D03*
X1007990Y768490D03*
X995990D03*
X1006699Y813916D03*
X1002699D03*
X1010699D03*
X1010009Y983047D03*
Y992047D03*
X998872Y1001482D03*
X1000248Y1021427D03*
X1012844Y88892D03*
X1018835Y113567D03*
X1025755Y104840D03*
X1020969Y154956D03*
X1016635Y302767D03*
X1020635D03*
X1025749D03*
X1012635D03*
X1018922Y802831D03*
X1014819Y932428D03*
X1026009Y983047D03*
X1018009D03*
X1022009D03*
X1014009D03*
X1026009Y992047D03*
X1018009D03*
X1022009D03*
X1014009D03*
X1011782Y1010913D03*
X1019774Y1223542D03*
X1023774D03*
X1017329Y1313528D03*
X1020049Y1330852D03*
X1019671Y1345015D03*
X1019257Y1363489D03*
X1033755Y104840D03*
X1029755D03*
X1027780Y127839D03*
X1042424Y143853D03*
X1034357Y209922D03*
X1029639Y302767D03*
X1041408Y445597D03*
X1030009Y983047D03*
X1038009D03*
X1042009D03*
X1034009Y992047D03*
X1030009D03*
X1038009D03*
X1042009D03*
X1034009Y983047D03*
X1041777Y1102624D03*
Y1115224D03*
Y1140424D03*
Y1127824D03*
Y1153024D03*
Y1165624D03*
Y1178224D03*
X1038996Y1368583D03*
X1048506Y103502D03*
X1048736Y233075D03*
X1045650Y302767D03*
X1057134Y538866D03*
X1053144Y538907D03*
X1046009Y983047D03*
X1050009D03*
X1054009D03*
X1046009Y992047D03*
X1050009D03*
X1054009D03*
X1058009D03*
Y983047D03*
X1053423Y1009887D03*
Y1022487D03*
X1074009Y992047D03*
Y983047D03*
X1066009Y992047D03*
X1062009D03*
X1070009D03*
X1066009Y983047D03*
X1062009D03*
X1087112Y98642D03*
X1086108Y1523524D03*
X1090904Y1593297D03*
X1086469Y1582501D03*
X1089474Y1631941D03*
X1093195Y98289D03*
X1097195D03*
X1102699Y97566D03*
Y105178D03*
X1093301Y259626D03*
X1101301D03*
X1096233Y1582524D03*
X1102904Y1593297D03*
X1104233Y1582524D03*
X1093474Y1631941D03*
X1101474D03*
X1105474D03*
X1115206Y88892D03*
X1121197Y113567D03*
X1123331Y154956D03*
X1136117Y104840D03*
X1132117D03*
X1128117D03*
X1130142Y127839D03*
X1136719Y209922D03*
X1150868Y103502D03*
X1144786Y143853D03*
X1151098Y233075D03*
X1156275Y650762D03*
X1156485Y767658D03*
X1155485Y839158D03*
X1160275Y650762D03*
X1164275D03*
X1167485Y825658D03*
X1159485D03*
X1171485Y839158D03*
X1163485D03*
X1167485D03*
X1159485D03*
X1189474Y98642D03*
X1183485Y825658D03*
X1175485D03*
X1183485Y839158D03*
X1179485D03*
X1175485D03*
X1195557Y98289D03*
X1199557D03*
X1205061Y97566D03*
Y105178D03*
X1195663Y259626D03*
X1203663D03*
X1217568Y88892D03*
X1238479Y104840D03*
X1223559Y113567D03*
X1234479Y104840D03*
X1230479D03*
X1232504Y127839D03*
X1225693Y154956D03*
X1226436Y318831D03*
X1231589Y342410D03*
X1235589D03*
X1237458Y550228D03*
X1253230Y103502D03*
X1247148Y143853D03*
X1239081Y209922D03*
X1253460Y233075D03*
X1250928Y1137220D03*
X1251802Y1175841D03*
X1249230Y1189437D03*
X1256659Y379664D03*
X1268659D03*
X1260659D03*
X1264659D03*
X1267375Y409018D03*
X1256458Y555228D03*
X1261622Y898533D03*
X1259921Y1137220D03*
X1264587Y1175181D03*
X1268587D03*
X1268615Y1182146D03*
X1264615D03*
X1255485Y1198941D03*
X1275660Y342726D03*
X1279655Y342667D03*
X1276659Y379664D03*
X1272659D03*
X1280042Y902164D03*
X1279921Y1137220D03*
X1277912Y1175229D03*
X1273912D03*
X1273934Y1182142D03*
X1277902Y1182179D03*
X1291836Y98642D03*
X1297919Y98289D03*
X1301919D03*
X1298025Y259626D03*
X1303410Y373570D03*
X1287437Y372695D03*
X1295410Y373570D03*
X1299410D03*
X1292566Y804337D03*
X1298909Y815608D03*
X1288155Y895016D03*
X1302000Y920016D03*
X1298000D03*
X1300882Y931080D03*
X1300500Y964016D03*
X1314859Y39989D03*
X1318859D03*
X1307423Y97566D03*
Y105178D03*
X1306025Y259626D03*
X1308410Y373572D03*
X1316903Y365257D03*
X1317000Y790516D03*
X1313000D03*
Y806516D03*
X1317000D03*
X1313152Y931080D03*
X1309103D03*
X1317000Y938016D03*
X1304949Y931080D03*
X1307000Y964016D03*
X1317437Y1155275D03*
X1325007Y365265D03*
X1334009Y365126D03*
X1326020Y429353D03*
X1333000Y790516D03*
X1329000D03*
X1325000D03*
X1321000D03*
X1333000Y806516D03*
X1325000D03*
X1329000D03*
X1321000D03*
X1322500Y920016D03*
X1326500D03*
Y938016D03*
X1327000Y964016D03*
X1332000D03*
X1331856Y1054729D03*
X1324842Y1102646D03*
X1328629D03*
X1337609Y365126D03*
X1339846Y456117D03*
X1341000Y790516D03*
X1337000D03*
X1341000Y806516D03*
X1345000D03*
X1349000D03*
X1337000D03*
X1350500Y920016D03*
X1336000Y938016D03*
X1337691Y948659D03*
X1342087Y1098858D03*
X1336706D03*
X1345459Y1110412D03*
X1353000Y806516D03*
X1354500Y920016D03*
X1358500D03*
X1362500D03*
X1366500D03*
X1361948Y946119D03*
X1356970Y1102646D03*
X1360757D03*
X1373560Y113567D03*
X1384480Y104840D03*
X1380480D03*
X1382505Y127839D03*
X1375694Y154956D03*
X1370500Y920016D03*
X1378500D03*
X1374500D03*
X1382500D03*
X1373948Y946119D03*
X1374215Y1098858D03*
X1368834D03*
X1377587Y1110412D03*
X1376861Y1155275D03*
X1383024D03*
X1388480Y104840D03*
X1397149Y143853D03*
X1389082Y209922D03*
X1397452Y613827D03*
X1390537Y806195D03*
X1386335Y806220D03*
X1388346Y924161D03*
X1390429Y1102646D03*
X1394216D03*
X1403231Y103502D03*
X1403461Y233075D03*
X1414903Y464435D03*
X1405252Y613827D03*
X1401452D03*
X1401000Y920016D03*
X1407674Y1098858D03*
X1402293D03*
X1411046Y1110412D03*
X1416684Y1511665D03*
X1411586Y1543470D03*
X1411094Y1566148D03*
X1431019Y437010D03*
X1427019D03*
X1424196Y448854D03*
X1431484Y464575D03*
X1418903Y464435D03*
X1427774Y533924D03*
X1430944Y599741D03*
X1432452Y636327D03*
X1428952D03*
X1420132Y1055022D03*
X1422557Y1102646D03*
X1426344D03*
X1426253Y1407793D03*
X1430374Y1495586D03*
X1433405Y1540508D03*
X1432913Y1563186D03*
X1441837Y98642D03*
X1447920Y98289D03*
X1448026Y259626D03*
X1435019Y437010D03*
X1437605Y487180D03*
X1435668Y575848D03*
X1434944Y599741D03*
X1435952Y636327D03*
X1443459Y1034427D03*
X1434421Y1098858D03*
X1443174Y1110412D03*
X1442448Y1155275D03*
X1436792Y1555457D03*
X1457424Y97566D03*
X1451920Y98289D03*
X1457424Y105178D03*
X1456026Y259626D03*
X1458912Y575653D03*
X1455959Y1001482D03*
X1469931Y88892D03*
X1475922Y113567D03*
X1478056Y154956D03*
X1475096Y983047D03*
X1479096D03*
X1471096D03*
X1475096Y992047D03*
X1479096D03*
X1471096D03*
X1467096Y983047D03*
Y992047D03*
X1468869Y1010913D03*
X1480861Y1223542D03*
X1476861D03*
X1490842Y104840D03*
X1482842D03*
X1486842D03*
X1484867Y127839D03*
X1491444Y209922D03*
X1491096Y983047D03*
X1487096D03*
X1495096D03*
X1491096Y992047D03*
X1487096D03*
X1495096D03*
X1483096Y983047D03*
Y992047D03*
X1505593Y103502D03*
X1499511Y143853D03*
X1505823Y233075D03*
X1498495Y445597D03*
X1514221Y538866D03*
X1510231Y538907D03*
X1503096Y983047D03*
X1507096D03*
X1511096D03*
X1503096Y992047D03*
X1507096D03*
X1511096D03*
X1499096D03*
Y983047D03*
X1510510Y1009887D03*
Y1022487D03*
X1498864Y1102624D03*
Y1115224D03*
Y1127824D03*
Y1140424D03*
Y1153024D03*
Y1165624D03*
Y1178224D03*
X1525015Y903541D03*
X1523096Y983047D03*
X1519096D03*
X1523096Y992047D03*
X1519096D03*
X1527096D03*
X1515096Y983047D03*
Y992047D03*
X1544199Y98642D03*
X1531096Y983047D03*
Y992047D03*
X1554282Y98289D03*
X1559786Y97566D03*
X1550282Y98289D03*
X1559786Y105178D03*
X1550388Y259626D03*
X1558388D03*
X1572293Y88892D03*
X1578284Y113567D03*
X1593204Y104840D03*
X1589204D03*
X1585204D03*
X1587229Y127839D03*
X1580418Y154956D03*
X1593806Y209922D03*
X1594307Y1502071D03*
X1594500Y1509016D03*
X1607955Y103502D03*
X1601873Y143853D03*
X1608185Y233075D03*
X1608483Y780418D03*
X1608383Y795218D03*
X1608283Y809218D03*
X1600333Y1443501D03*
X1605000Y1509016D03*
X1598142Y1527401D03*
X1613362Y650762D03*
X1617362D03*
X1621362D03*
X1616683Y747518D03*
X1616583Y761518D03*
X1634083Y774718D03*
X1632583Y787418D03*
X1631383Y801518D03*
X1646561Y98642D03*
X1652644Y98289D03*
X1656644D03*
X1652750Y259626D03*
X1660750D03*
X1674655Y88892D03*
X1662148Y97566D03*
Y105178D03*
X1680646Y113567D03*
X1691566Y104840D03*
X1687566D03*
X1689591Y127839D03*
X1682780Y154956D03*
X1683523Y318831D03*
X1688676Y342410D03*
X1692676D03*
X1695566Y104840D03*
X1704235Y143853D03*
X1696168Y209922D03*
X1694545Y550228D03*
X1708015Y1137220D03*
X1708889Y1175841D03*
X1708745Y1224216D03*
X1710317Y103502D03*
X1710547Y233075D03*
X1713746Y379664D03*
X1717746D03*
X1725746D03*
X1721746D03*
X1724462Y409018D03*
X1713545Y555228D03*
X1717008Y1137220D03*
X1725674Y1175181D03*
X1721674D03*
X1725702Y1182146D03*
X1721702D03*
X1713721Y1203402D03*
X1709827Y1203356D03*
X1712966Y1224207D03*
X1733746Y379664D03*
X1729746D03*
X1737008Y1137220D03*
X1734999Y1175229D03*
X1730999D03*
X1731021Y1182142D03*
X1734989Y1182179D03*
X1748923Y98642D03*
X1755006Y98289D03*
X1755112Y259626D03*
X1752497Y373570D03*
X1756497D03*
X1756297Y1015568D03*
X1753221Y1618595D03*
X1764510Y97566D03*
X1759006Y98289D03*
X1764510Y105178D03*
X1763112Y259626D03*
X1765497Y373572D03*
X1760497Y373570D03*
X1765131Y1015568D03*
X1760487D03*
X1771992D03*
X1774339Y1440626D03*
X1774216Y1472816D03*
X1763000Y1582016D03*
X1777017Y88892D03*
X1783107Y429353D03*
X1789463Y963266D03*
X1784145Y1015568D03*
X1790035D03*
X1778042D03*
X1796933Y456117D03*
X1793474Y924502D03*
X1796344Y1015568D03*
X1802432D03*
X1805384Y1206410D03*
X1803885Y1437656D03*
X1803762Y1469846D03*
X1808320Y1015568D03*
X1812265D03*
X1816260D03*
X1809349Y1205250D03*
X1813027Y1211976D03*
X1828272Y1106087D03*
Y1099048D03*
G54D143*
X414519Y1250868D03*
Y1264254D03*
X512830Y1250868D03*
Y1264254D03*
X1328693Y1250868D03*
Y1264254D03*
X1427004Y1250868D03*
Y1264254D03*
G54D224*
X1091661Y1521648D03*
Y1540152D03*
X1099339Y1521648D03*
X1096780D03*
X1094220D03*
Y1540152D03*
X1096780D03*
X1099339D03*
G54D233*
X1803917Y823898D03*
G54D170*
X801057Y1448158D03*
Y1457016D03*
G54D32*
X8788Y992319D03*
Y986519D03*
X14513Y992319D03*
Y986519D03*
X20006Y992319D03*
Y986519D03*
X30903Y992319D03*
Y986519D03*
X36293Y992319D03*
Y986519D03*
X25462Y992319D03*
Y986519D03*
X41792Y992319D03*
Y986519D03*
X47234Y992319D03*
Y986519D03*
X47425Y1242619D03*
Y1248419D03*
X117670Y1011465D03*
X110258Y1014862D03*
Y1020662D03*
X117670Y1017265D03*
Y1024065D03*
Y1029865D03*
X106024Y1104202D03*
Y1110002D03*
Y1116802D03*
Y1122602D03*
Y1129402D03*
Y1135202D03*
Y1142002D03*
Y1147802D03*
Y1154602D03*
Y1160402D03*
Y1167202D03*
Y1173002D03*
Y1179802D03*
Y1185602D03*
X374800Y770700D03*
Y776500D03*
X406173Y455001D03*
Y449201D03*
X400711Y1217592D03*
Y1211792D03*
X411673Y449201D03*
Y455001D03*
X412040Y840629D03*
Y834829D03*
X426822Y1217735D03*
Y1211935D03*
X455968Y1206277D03*
Y1212077D03*
X455592Y1260171D03*
Y1265971D03*
X461319Y1206276D03*
Y1212076D03*
X461101Y1260171D03*
Y1265971D03*
X499598Y1217351D03*
Y1211551D03*
X526120Y1218053D03*
Y1212253D03*
X567345Y1014862D03*
Y1020662D03*
X563111Y1104202D03*
Y1110002D03*
Y1116802D03*
Y1122602D03*
Y1129402D03*
Y1135202D03*
Y1142002D03*
Y1147802D03*
Y1154602D03*
Y1160402D03*
Y1167202D03*
Y1173002D03*
Y1179802D03*
Y1185602D03*
X574757Y1011465D03*
Y1024065D03*
Y1017265D03*
Y1029865D03*
X866448Y1003630D03*
Y997830D03*
X871389Y1003630D03*
Y997830D03*
X876279Y1003630D03*
Y997830D03*
X881278Y1003630D03*
Y997830D03*
X886220Y1003630D03*
Y997830D03*
X891068Y1003630D03*
Y997830D03*
X895989Y1003630D03*
Y997830D03*
X891115Y1251622D03*
Y1257422D03*
X901499Y471342D03*
Y465542D03*
X906999D03*
Y471342D03*
X900721Y1003630D03*
Y997830D03*
X913751Y1004630D03*
Y998830D03*
X925969Y1003630D03*
Y997830D03*
X920476Y1003630D03*
Y997830D03*
X936866Y1003630D03*
Y997830D03*
X942256Y1003630D03*
Y997830D03*
X931425Y1003630D03*
Y997830D03*
X961110Y1003283D03*
Y997483D03*
X955092Y1251622D03*
Y1257422D03*
X973080Y1003456D03*
Y997656D03*
X1002052Y1397662D03*
Y1403462D03*
X1024431Y1014862D03*
Y1020662D03*
X1020197Y1104202D03*
Y1116802D03*
Y1122602D03*
Y1110002D03*
Y1129402D03*
Y1135202D03*
Y1142002D03*
Y1147802D03*
Y1154602D03*
Y1160402D03*
Y1167202D03*
Y1173002D03*
Y1179802D03*
Y1185602D03*
X1031843Y1011465D03*
Y1017265D03*
Y1024065D03*
Y1029865D03*
X1053227Y811659D03*
Y817459D03*
X1314823Y1217928D03*
Y1212128D03*
X1320346Y455001D03*
Y449201D03*
X1325846D03*
Y455001D03*
X1341454Y1217562D03*
Y1211762D03*
X1414947Y1217224D03*
Y1211424D03*
X1440660Y1217062D03*
Y1211262D03*
X1481518Y1014862D03*
Y1020662D03*
X1477284Y1104202D03*
Y1116802D03*
Y1122602D03*
Y1110002D03*
Y1129402D03*
Y1135202D03*
Y1142002D03*
Y1147802D03*
Y1154602D03*
Y1167202D03*
Y1173002D03*
Y1160402D03*
Y1179802D03*
Y1185602D03*
X1488930Y1011465D03*
Y1024065D03*
Y1017265D03*
Y1029865D03*
X1746267Y903414D03*
Y909214D03*
X1770492Y1005250D03*
Y999450D03*
X1759274Y1005250D03*
Y999450D03*
X1764999Y1005250D03*
Y999450D03*
X1777433Y455001D03*
Y449201D03*
X1782933D03*
Y455001D03*
X1786779Y1005250D03*
Y999450D03*
X1775948Y1005250D03*
Y999450D03*
X1781389Y1005250D03*
Y999450D03*
X1792278Y1005250D03*
Y999450D03*
X1797720Y1005250D03*
Y999450D03*
X1799072Y1252108D03*
Y1257908D03*
G54D161*
X656650Y694797D03*
X659209D03*
X656650Y702277D03*
X661768D03*
X659209D03*
X661768Y694797D03*
X781059Y1605740D03*
X778500D03*
X781059Y1598260D03*
X775941D03*
X778500D03*
X775941Y1605740D03*
X1113737Y694797D03*
X1116296D03*
X1113737Y702277D03*
X1118855D03*
X1116296D03*
X1118855Y694797D03*
X1570824D03*
X1573383D03*
X1570824Y702277D03*
X1575942D03*
X1573383D03*
X1575942Y694797D03*
G54D152*
X488765Y663326D03*
Y671200D03*
X493883Y663326D03*
X491324D03*
Y671200D03*
X493883D03*
X519753Y769259D03*
X517194D03*
X514635D03*
Y777133D03*
X517194D03*
X519753D03*
X829725Y727177D03*
Y735051D03*
X848284Y727177D03*
Y735051D03*
X845725Y727177D03*
Y735051D03*
X832284Y727177D03*
Y735051D03*
X834843Y727177D03*
Y735051D03*
X850843Y727177D03*
Y735051D03*
X1096264Y1574807D03*
Y1566933D03*
X1098823Y1574807D03*
Y1566933D03*
X1093705Y1574807D03*
Y1566933D03*
X1301348Y948224D03*
Y956098D03*
X1318000Y955937D03*
Y948063D03*
X1315441Y955937D03*
Y948063D03*
X1303907Y948224D03*
Y956098D03*
X1306466Y948224D03*
Y956098D03*
X1329500Y948063D03*
Y955937D03*
X1326941Y948063D03*
Y955937D03*
X1332059Y948063D03*
Y955937D03*
X1320559D03*
Y948063D03*
G54D107*
X343826Y1153242D03*
X341266D03*
X338707D03*
Y1167808D03*
X341266D03*
X343826D03*
X346385Y1153242D03*
Y1167808D03*
X798353Y1153242D03*
X795794D03*
Y1167808D03*
X798353D03*
X803472Y1153242D03*
X800913D03*
Y1167808D03*
X803472D03*
X874909Y761332D03*
X872350D03*
X880028D03*
X877469D03*
Y775898D03*
X874909D03*
X872350D03*
X880028D03*
X1091168Y1606949D03*
Y1621515D03*
X1093727Y1606949D03*
X1098846D03*
X1096287D03*
Y1621515D03*
X1093727D03*
X1098846D03*
X1252880Y1153242D03*
Y1167808D03*
X1260558Y1153242D03*
X1257999D03*
X1255439D03*
Y1167808D03*
X1257999D03*
X1260558D03*
X1717645Y1153242D03*
X1715086D03*
X1712526D03*
X1709967D03*
Y1167808D03*
X1712526D03*
X1715086D03*
X1717645D03*
G54D23*
X18887Y156163D03*
X16919D03*
X14951D03*
X18887Y164037D03*
X16919D03*
X14951D03*
X65122Y451557D03*
X63154D03*
X61186D03*
X65122Y459431D03*
X63154D03*
X61186D03*
X79038Y277477D03*
X81006D03*
X82974D03*
X79038Y269603D03*
X81006D03*
X82974D03*
X115285Y113684D03*
X113317D03*
X111349D03*
Y121558D03*
X113317D03*
X115285D03*
X181400Y277477D03*
Y269603D03*
X183368Y277477D03*
X185336D03*
X183368Y269603D03*
X185336D03*
X213711Y113684D03*
Y121558D03*
X217647Y113684D03*
X215679D03*
X217647Y121558D03*
X215679D03*
X283762Y277477D03*
X285730D03*
X287698D03*
X283762Y269603D03*
X285730D03*
X287698D03*
X320009Y113684D03*
X318041D03*
X316073D03*
X320009Y121558D03*
X318041D03*
X316073D03*
X386124Y277477D03*
X388092D03*
X390060D03*
X386124Y269603D03*
X388092D03*
X390060D03*
X470010Y113684D03*
X468042D03*
X466074D03*
X470010Y121558D03*
X468042D03*
X466074D03*
X520208Y448557D03*
X518240D03*
X516272D03*
X520208Y456431D03*
X518240D03*
X516272D03*
X536125Y277477D03*
X538093D03*
X536125Y269603D03*
X538093D03*
X540061Y277477D03*
Y269603D03*
X570404Y113684D03*
X568436D03*
X570404Y121558D03*
X568436D03*
X572372Y113684D03*
Y121558D03*
X638487Y277477D03*
X640455D03*
X642423D03*
X638487Y269603D03*
X640455D03*
X642423D03*
X674734Y113684D03*
X672766D03*
X670798D03*
X674734Y121558D03*
X672766D03*
X670798D03*
X740849Y277477D03*
X742817D03*
X744785D03*
X740849Y269603D03*
X742817D03*
X744785D03*
X777096Y113684D03*
X775128D03*
X773160D03*
X777096Y121558D03*
X775128D03*
X773160D03*
X843211Y277477D03*
X845179D03*
X847147D03*
X843211Y269603D03*
X845179D03*
X847147D03*
X927096Y113684D03*
X925128D03*
X923160D03*
X927096Y121558D03*
X925128D03*
X923160D03*
X977327Y451557D03*
X975359D03*
X977327Y459431D03*
X975359D03*
X993211Y277477D03*
Y269603D03*
X979295Y451557D03*
Y459431D03*
X995179Y277477D03*
X997147D03*
X995179Y269603D03*
X997147D03*
X1025522Y113684D03*
Y121558D03*
X1029458Y113684D03*
X1027490D03*
X1029458Y121558D03*
X1027490D03*
X1095573Y277477D03*
X1097541D03*
X1099509D03*
X1095573Y269603D03*
X1097541D03*
X1099509D03*
X1131820Y113684D03*
X1129852D03*
X1127884D03*
X1131820Y121558D03*
X1129852D03*
X1127884D03*
X1197935Y277477D03*
X1199903D03*
X1201871D03*
X1197935Y269603D03*
X1199903D03*
X1201871D03*
X1234182Y113684D03*
X1232214D03*
X1230246D03*
X1234182Y121558D03*
X1232214D03*
X1230246D03*
X1300297Y277477D03*
X1302265D03*
X1300297Y269603D03*
X1302265D03*
X1304233Y277477D03*
Y269603D03*
X1384183Y113684D03*
X1382215D03*
X1380247D03*
X1384183Y121558D03*
X1382215D03*
X1380247D03*
X1432414Y448557D03*
X1430446D03*
X1432414Y456431D03*
X1430446D03*
X1434382Y448557D03*
Y456431D03*
X1450298Y277477D03*
X1452266D03*
X1454234D03*
X1450298Y269603D03*
X1452266D03*
X1454234D03*
X1486545Y113684D03*
X1484577D03*
X1482609D03*
X1486545Y121558D03*
X1484577D03*
X1482609D03*
X1552660Y277477D03*
X1554628D03*
X1556596D03*
X1552660Y269603D03*
X1554628D03*
X1556596D03*
X1588907Y113684D03*
X1586939D03*
X1584971D03*
X1588907Y121558D03*
X1586939D03*
X1584971D03*
X1655022Y277477D03*
X1656990D03*
X1658958D03*
X1655022Y269603D03*
X1656990D03*
X1658958D03*
X1691269Y113684D03*
X1689301D03*
X1687333D03*
X1691269Y121558D03*
X1689301D03*
X1687333D03*
X1757384Y277477D03*
Y269603D03*
X1759352Y277477D03*
X1761320D03*
X1759352Y269603D03*
X1761320D03*
G54D41*
X32051Y213243D03*
X30083D03*
X28114D03*
X26146D03*
X24177D03*
X22209D03*
Y225055D03*
X24177D03*
X26146D03*
X28114D03*
X30083D03*
X32051D03*
X132445Y213243D03*
X130476D03*
X128508D03*
X126539D03*
X124571D03*
Y225055D03*
X126539D03*
X128508D03*
X130476D03*
X132445D03*
X134413Y213243D03*
Y225055D03*
X230870Y213243D03*
X228901D03*
X226933D03*
Y225055D03*
X228901D03*
X230870D03*
X236775Y213243D03*
X234807D03*
X232838D03*
Y225055D03*
X234807D03*
X236775D03*
X339137Y213243D03*
X337169D03*
X335200D03*
X333232D03*
X331263D03*
X329295D03*
Y225055D03*
X331263D03*
X333232D03*
X335200D03*
X337169D03*
X339137D03*
X389303Y383732D03*
X387335D03*
X385366D03*
X383398D03*
X381429D03*
X379461D03*
Y395544D03*
X381429D03*
X383398D03*
X385366D03*
X387335D03*
X389303D03*
X489138Y213243D03*
X487170D03*
X485201D03*
X483233D03*
X481264D03*
X479296D03*
Y225055D03*
X481264D03*
X483233D03*
X485201D03*
X487170D03*
X489138D03*
X587563Y213243D03*
X585595D03*
X583626D03*
X581658D03*
Y225055D03*
X583626D03*
X585595D03*
X587563D03*
X591500Y213243D03*
X589532D03*
Y225055D03*
X591500D03*
X684020Y213243D03*
Y225055D03*
X693862Y213243D03*
X691894D03*
X689925D03*
X687957D03*
X685988D03*
Y225055D03*
X687957D03*
X689925D03*
X691894D03*
X693862D03*
X796224Y213243D03*
X794256D03*
X792287D03*
X790319D03*
X788350D03*
X786382D03*
Y225055D03*
X788350D03*
X790319D03*
X792287D03*
X794256D03*
X796224D03*
X880692Y397073D03*
X878724D03*
X876755D03*
X874787D03*
Y408885D03*
X876755D03*
X878724D03*
X880692D03*
X884629Y397073D03*
X882661D03*
Y408885D03*
X884629D03*
X944922Y198414D03*
X942953D03*
X940985D03*
X939016D03*
X937048D03*
Y210226D03*
X939016D03*
X940985D03*
X942953D03*
X944922D03*
X946890Y198414D03*
Y210226D03*
X1042681Y213243D03*
X1040712D03*
X1038744D03*
Y225055D03*
X1040712D03*
X1042681D03*
X1048586Y213243D03*
X1046618D03*
X1044649D03*
Y225055D03*
X1046618D03*
X1048586D03*
X1150948Y213243D03*
X1148980D03*
X1147011D03*
X1145043D03*
X1143074D03*
X1141106D03*
Y225055D03*
X1143074D03*
X1145043D03*
X1147011D03*
X1148980D03*
X1150948D03*
X1253310Y213243D03*
X1251342D03*
X1249373D03*
X1247405D03*
X1245436D03*
X1243468D03*
Y225055D03*
X1245436D03*
X1247405D03*
X1249373D03*
X1251342D03*
X1253310D03*
X1301508Y383732D03*
X1299539D03*
X1297571D03*
X1295602D03*
X1293634D03*
Y395544D03*
X1295602D03*
X1297571D03*
X1299539D03*
X1301508D03*
X1303476Y383732D03*
Y395544D03*
X1399374Y213243D03*
X1397406D03*
X1395437D03*
X1393469D03*
Y225055D03*
X1395437D03*
X1397406D03*
X1399374D03*
X1403311Y213243D03*
X1401343D03*
Y225055D03*
X1403311D03*
X1497799Y213243D03*
X1495831D03*
Y225055D03*
X1497799D03*
X1505673Y213243D03*
X1503705D03*
X1501736D03*
X1499768D03*
Y225055D03*
X1501736D03*
X1503705D03*
X1505673D03*
X1608035Y213243D03*
X1606067D03*
X1604098D03*
X1602130D03*
X1600161D03*
X1598193D03*
Y225055D03*
X1600161D03*
X1602130D03*
X1604098D03*
X1606067D03*
X1608035D03*
X1708429Y213243D03*
X1706460D03*
X1704492D03*
X1702523D03*
X1700555D03*
Y225055D03*
X1702523D03*
X1704492D03*
X1706460D03*
X1708429D03*
X1710397Y213243D03*
Y225055D03*
X1756626Y383732D03*
X1754658D03*
X1752689D03*
X1750721D03*
Y395544D03*
X1752689D03*
X1754658D03*
X1756626D03*
X1760563Y383732D03*
X1758595D03*
Y395544D03*
X1760563D03*
G36*
G01X935311Y1451521D02*
Y1460576D01*
X937673D01*
Y1464907D01*
X932929D01*
Y1468450D01*
X935291D01*
Y1465407D01*
X937929D01*
Y1468450D01*
X940291D01*
Y1465407D01*
X942929D01*
Y1468450D01*
X945291D01*
Y1465407D01*
X947929D01*
Y1468450D01*
X950291D01*
Y1464907D01*
X946047D01*
Y1460576D01*
X947909D01*
Y1458214D01*
X944866D01*
Y1457230D01*
X947909D01*
Y1454868D01*
X944866D01*
Y1453883D01*
X947909D01*
Y1451521D01*
X944366D01*
Y1460576D01*
X945547D01*
Y1464907D01*
X942110D01*
Y1460576D01*
X943382D01*
Y1458214D01*
X940338D01*
Y1457230D01*
X943382D01*
Y1454868D01*
X940338D01*
Y1453883D01*
X943382D01*
Y1451521D01*
X939838D01*
Y1460576D01*
X941610D01*
Y1464907D01*
X938173D01*
Y1460576D01*
X938854D01*
Y1458214D01*
X935811D01*
Y1457230D01*
X938854D01*
Y1454868D01*
X935811D01*
Y1453883D01*
X938854D01*
Y1451521D01*
X935311D01*
G37*
G36*
G01X961469Y1451774D02*
Y1460829D01*
X963831D01*
Y1465160D01*
X959087D01*
Y1468703D01*
X961449D01*
Y1465660D01*
X964087D01*
Y1468703D01*
X966449D01*
Y1465660D01*
X969087D01*
Y1468703D01*
X971449D01*
Y1465660D01*
X974087D01*
Y1468703D01*
X976449D01*
Y1465160D01*
X972205D01*
Y1460829D01*
X974067D01*
Y1458467D01*
X971024D01*
Y1457483D01*
X974067D01*
Y1455121D01*
X971024D01*
Y1454136D01*
X974067D01*
Y1451774D01*
X970524D01*
Y1460829D01*
X971705D01*
Y1465160D01*
X968268D01*
Y1460829D01*
X969540D01*
Y1458467D01*
X966496D01*
Y1457483D01*
X969540D01*
Y1455121D01*
X966496D01*
Y1454136D01*
X969540D01*
Y1451774D01*
X965996D01*
Y1460829D01*
X967768D01*
Y1465160D01*
X964331D01*
Y1460829D01*
X965012D01*
Y1458467D01*
X961969D01*
Y1457483D01*
X965012D01*
Y1455121D01*
X961969D01*
Y1454136D01*
X965012D01*
Y1451774D01*
X961469D01*
G37*
G36*
G01X984535D02*
Y1460829D01*
X986897D01*
Y1465160D01*
X982153D01*
Y1468703D01*
X984515D01*
Y1465660D01*
X987153D01*
Y1468703D01*
X989515D01*
Y1465660D01*
X992153D01*
Y1468703D01*
X994515D01*
Y1465660D01*
X997153D01*
Y1468703D01*
X999515D01*
Y1465160D01*
X995271D01*
Y1460829D01*
X997133D01*
Y1458467D01*
X994090D01*
Y1457483D01*
X997133D01*
Y1455121D01*
X994090D01*
Y1454136D01*
X997133D01*
Y1451774D01*
X993590D01*
Y1460829D01*
X994771D01*
Y1465160D01*
X991334D01*
Y1460829D01*
X992606D01*
Y1458467D01*
X989562D01*
Y1457483D01*
X992606D01*
Y1455121D01*
X989562D01*
Y1454136D01*
X992606D01*
Y1451774D01*
X989062D01*
Y1460829D01*
X990834D01*
Y1465160D01*
X987397D01*
Y1460829D01*
X988078D01*
Y1458467D01*
X985035D01*
Y1457483D01*
X988078D01*
Y1455121D01*
X985035D01*
Y1454136D01*
X988078D01*
Y1451774D01*
X984535D01*
G37*
G36*
G01X1007567Y1451874D02*
Y1460929D01*
X1009929D01*
Y1465260D01*
X1005185D01*
Y1468803D01*
X1007547D01*
Y1465760D01*
X1010185D01*
Y1468803D01*
X1012547D01*
Y1465760D01*
X1015185D01*
Y1468803D01*
X1017547D01*
Y1465760D01*
X1020185D01*
Y1468803D01*
X1022547D01*
Y1465260D01*
X1018303D01*
Y1460929D01*
X1020165D01*
Y1458567D01*
X1017122D01*
Y1457583D01*
X1020165D01*
Y1455221D01*
X1017122D01*
Y1454236D01*
X1020165D01*
Y1451874D01*
X1016622D01*
Y1460929D01*
X1017803D01*
Y1465260D01*
X1014366D01*
Y1460929D01*
X1015638D01*
Y1458567D01*
X1012594D01*
Y1457583D01*
X1015638D01*
Y1455221D01*
X1012594D01*
Y1454236D01*
X1015638D01*
Y1451874D01*
X1012094D01*
Y1460929D01*
X1013866D01*
Y1465260D01*
X1010429D01*
Y1460929D01*
X1011110D01*
Y1458567D01*
X1008067D01*
Y1457583D01*
X1011110D01*
Y1455221D01*
X1008067D01*
Y1454236D01*
X1011110D01*
Y1451874D01*
X1007567D01*
G37*
G36*
G01X1030453Y1451990D02*
Y1461045D01*
X1032815D01*
Y1465376D01*
X1028071D01*
Y1468919D01*
X1030433D01*
Y1465876D01*
X1033071D01*
Y1468919D01*
X1035433D01*
Y1465876D01*
X1038071D01*
Y1468919D01*
X1040433D01*
Y1465876D01*
X1043071D01*
Y1468919D01*
X1045433D01*
Y1465376D01*
X1041189D01*
Y1461045D01*
X1043051D01*
Y1458683D01*
X1040008D01*
Y1457699D01*
X1043051D01*
Y1455337D01*
X1040008D01*
Y1454352D01*
X1043051D01*
Y1451990D01*
X1039508D01*
Y1461045D01*
X1040689D01*
Y1465376D01*
X1037252D01*
Y1461045D01*
X1038524D01*
Y1458683D01*
X1035480D01*
Y1457699D01*
X1038524D01*
Y1455337D01*
X1035480D01*
Y1454352D01*
X1038524D01*
Y1451990D01*
X1034980D01*
Y1461045D01*
X1036752D01*
Y1465376D01*
X1033315D01*
Y1461045D01*
X1033996D01*
Y1458683D01*
X1030953D01*
Y1457699D01*
X1033996D01*
Y1455337D01*
X1030953D01*
Y1454352D01*
X1033996D01*
Y1451990D01*
X1030453D01*
G37*
G54D134*
X423673Y439314D03*
Y435770D03*
Y446400D03*
Y442857D03*
X918999Y455655D03*
Y452111D03*
Y462741D03*
Y459198D03*
X1337846Y439314D03*
Y435770D03*
Y446400D03*
Y442857D03*
X1794933Y439314D03*
Y435770D03*
Y446400D03*
Y442857D03*
G54D50*
X35158Y1504318D03*
X33189D03*
X31221D03*
X29252D03*
X27284D03*
X25315D03*
Y1538964D03*
X27284D03*
X29252D03*
X31221D03*
X33189D03*
X35158D03*
X50906Y1504318D03*
X48937D03*
X46969D03*
X45000D03*
X43032D03*
X41063D03*
X39095D03*
X37126D03*
Y1538964D03*
X39095D03*
X41063D03*
X43032D03*
X45000D03*
X46969D03*
X48937D03*
X50906D03*
X54843Y1504318D03*
X52874D03*
Y1538964D03*
X54843D03*
G54D116*
X405466Y673038D03*
X426726D03*
X443226D03*
X464486D03*
G54D215*
X989651Y1556274D03*
X1015635D03*
G54D125*
X413469Y1183065D03*
Y1208261D03*
X439639Y896653D03*
Y921849D03*
X440399Y1183065D03*
Y1208261D03*
X486671Y1183065D03*
Y1208261D03*
X513601Y1183065D03*
Y1208261D03*
X1327643Y1183065D03*
Y1208261D03*
X1354573Y1183065D03*
Y1208261D03*
X1400845Y1183065D03*
Y1208261D03*
X1427775Y1183065D03*
Y1208261D03*
G54D234*
G01X-20602Y-468335D02*
Y-543335D01*
X479398D01*
Y-468335D01*
X-20602D01*
G01X-8602Y-533335D02*
Y-538335D01*
G01X-10059Y-533335D02*
X-7145D01*
G01X-2235Y-538335D02*
X-4769D01*
Y-533335D01*
X-2235D01*
G01X-3249Y-535752D02*
X-4769D01*
G01X331Y-533335D02*
Y-538335D01*
X2865D01*
G01X6698Y-538502D02*
X6571Y-538418D01*
Y-538252D01*
X6698Y-538168D01*
X6825Y-538252D01*
Y-538418D01*
X6698Y-538502D01*
G01Y-536252D02*
X6571Y-536168D01*
Y-536002D01*
X6698Y-535918D01*
X6825Y-536002D01*
Y-536168D01*
X6698Y-536252D01*
G01X11481Y-540002D02*
X10848Y-539168D01*
X10531Y-538335D01*
Y-535002D01*
X10848Y-534168D01*
X11481Y-533335D01*
G01X16898D02*
X16391Y-533502D01*
X16011Y-533918D01*
X15758Y-534418D01*
X15568Y-535085D01*
X15505Y-535835D01*
X15568Y-536585D01*
X15758Y-537252D01*
X16011Y-537752D01*
X16391Y-538168D01*
X16898Y-538335D01*
X17405Y-538168D01*
X17785Y-537752D01*
X18038Y-537252D01*
X18228Y-536585D01*
X18291Y-535835D01*
X18228Y-535085D01*
X18038Y-534418D01*
X17785Y-533918D01*
X17405Y-533502D01*
X16898Y-533335D01*
G01X20605Y-537335D02*
X20985Y-537918D01*
X21491Y-538252D01*
X22061Y-538335D01*
X22568Y-538252D01*
X23075Y-537835D01*
X23391Y-537335D01*
X23455Y-536835D01*
X23328Y-536252D01*
X22885Y-535835D01*
X22441Y-535668D01*
X21871D01*
G01X22441D02*
X22821Y-535418D01*
X23138Y-535002D01*
X23265Y-534502D01*
X23138Y-534002D01*
X22821Y-533585D01*
X22251Y-533335D01*
X21681Y-533418D01*
X21111Y-533752D01*
G01X27415Y-540002D02*
X28048Y-539168D01*
X28365Y-538335D01*
Y-535002D01*
X28048Y-534168D01*
X27415Y-533335D01*
G01X30805Y-537335D02*
X31185Y-537918D01*
X31691Y-538252D01*
X32261Y-538335D01*
X32768Y-538252D01*
X33275Y-537835D01*
X33591Y-537335D01*
X33655Y-536835D01*
X33528Y-536252D01*
X33085Y-535835D01*
X32641Y-535668D01*
X32071D01*
G01X32641D02*
X33021Y-535418D01*
X33338Y-535002D01*
X33465Y-534502D01*
X33338Y-534002D01*
X33021Y-533585D01*
X32451Y-533335D01*
X31881Y-533418D01*
X31311Y-533752D01*
G01X36095Y-534168D02*
X36475Y-533668D01*
X36918Y-533418D01*
X37425Y-533335D01*
X38058Y-533502D01*
X38501Y-533918D01*
X38628Y-534418D01*
X38565Y-534918D01*
X38311Y-535335D01*
X37045Y-536168D01*
X36475Y-536752D01*
X36095Y-537585D01*
X35968Y-538335D01*
X38628D01*
G01X42271D02*
X42398Y-537252D01*
X42588Y-536335D01*
X42841Y-535502D01*
X43158Y-534585D01*
X43665Y-533335D01*
X41131D01*
G01X46675Y-536668D02*
X48321D01*
G01X51395Y-534168D02*
X51775Y-533668D01*
X52218Y-533418D01*
X52725Y-533335D01*
X53358Y-533502D01*
X53801Y-533918D01*
X53928Y-534418D01*
X53865Y-534918D01*
X53611Y-535335D01*
X52345Y-536168D01*
X51775Y-536752D01*
X51395Y-537585D01*
X51268Y-538335D01*
X53928D01*
G01X56305Y-537335D02*
X56685Y-537918D01*
X57191Y-538252D01*
X57761Y-538335D01*
X58268Y-538252D01*
X58775Y-537835D01*
X59091Y-537335D01*
X59155Y-536835D01*
X59028Y-536252D01*
X58585Y-535835D01*
X58141Y-535668D01*
X57571D01*
G01X58141D02*
X58521Y-535418D01*
X58838Y-535002D01*
X58965Y-534502D01*
X58838Y-534002D01*
X58521Y-533585D01*
X57951Y-533335D01*
X57381Y-533418D01*
X56811Y-533752D01*
G01X63558Y-538335D02*
Y-533335D01*
X61215Y-536918D01*
X64381D01*
G01X66505Y-537585D02*
X66885Y-538002D01*
X67328Y-538252D01*
X67898Y-538335D01*
X68468Y-538168D01*
X68911Y-537835D01*
X69228Y-537252D01*
X69291Y-536585D01*
X69165Y-535918D01*
X68848Y-535502D01*
X68405Y-535168D01*
X67961Y-535085D01*
X67518Y-535168D01*
X66948Y-535502D01*
X67138Y-533335D01*
X68848D01*
G01X76895Y-538335D02*
Y-533335D01*
X79301D01*
G01X78415Y-535752D02*
X76895D01*
G01X81615Y-538335D02*
X83198Y-533335D01*
X84781Y-538335D01*
G01X84211Y-536585D02*
X82185D01*
G01X86968Y-538335D02*
X89628Y-533335D01*
G01X86968D02*
X89628Y-538335D01*
G01X93398Y-538502D02*
X93271Y-538418D01*
Y-538252D01*
X93398Y-538168D01*
X93525Y-538252D01*
Y-538418D01*
X93398Y-538502D01*
G01Y-536252D02*
X93271Y-536168D01*
Y-536002D01*
X93398Y-535918D01*
X93525Y-536002D01*
Y-536168D01*
X93398Y-536252D01*
G01X98181Y-540002D02*
X97548Y-539168D01*
X97231Y-538335D01*
Y-535002D01*
X97548Y-534168D01*
X98181Y-533335D01*
G01X103598D02*
X103091Y-533502D01*
X102711Y-533918D01*
X102458Y-534418D01*
X102268Y-535085D01*
X102205Y-535835D01*
X102268Y-536585D01*
X102458Y-537252D01*
X102711Y-537752D01*
X103091Y-538168D01*
X103598Y-538335D01*
X104105Y-538168D01*
X104485Y-537752D01*
X104738Y-537252D01*
X104928Y-536585D01*
X104991Y-535835D01*
X104928Y-535085D01*
X104738Y-534418D01*
X104485Y-533918D01*
X104105Y-533502D01*
X103598Y-533335D01*
G01X107305Y-537335D02*
X107685Y-537918D01*
X108191Y-538252D01*
X108761Y-538335D01*
X109268Y-538252D01*
X109775Y-537835D01*
X110091Y-537335D01*
X110155Y-536835D01*
X110028Y-536252D01*
X109585Y-535835D01*
X109141Y-535668D01*
X108571D01*
G01X109141D02*
X109521Y-535418D01*
X109838Y-535002D01*
X109965Y-534502D01*
X109838Y-534002D01*
X109521Y-533585D01*
X108951Y-533335D01*
X108381Y-533418D01*
X107811Y-533752D01*
G01X114115Y-540002D02*
X114748Y-539168D01*
X115065Y-538335D01*
Y-535002D01*
X114748Y-534168D01*
X114115Y-533335D01*
G01X117505Y-537335D02*
X117885Y-537918D01*
X118391Y-538252D01*
X118961Y-538335D01*
X119468Y-538252D01*
X119975Y-537835D01*
X120291Y-537335D01*
X120355Y-536835D01*
X120228Y-536252D01*
X119785Y-535835D01*
X119341Y-535668D01*
X118771D01*
G01X119341D02*
X119721Y-535418D01*
X120038Y-535002D01*
X120165Y-534502D01*
X120038Y-534002D01*
X119721Y-533585D01*
X119151Y-533335D01*
X118581Y-533418D01*
X118011Y-533752D01*
G01X122921Y-537752D02*
X123365Y-538168D01*
X123871Y-538335D01*
X124378Y-538168D01*
X124821Y-537668D01*
X125138Y-536918D01*
X125265Y-536168D01*
Y-535252D01*
X125138Y-534502D01*
X124821Y-533835D01*
X124441Y-533502D01*
X123998Y-533335D01*
X123491Y-533502D01*
X123111Y-533835D01*
X122858Y-534335D01*
X122731Y-535002D01*
X122858Y-535585D01*
X123175Y-536168D01*
X123555Y-536502D01*
X123998Y-536585D01*
X124505Y-536418D01*
X124885Y-536002D01*
X125265Y-535252D01*
G01X128971Y-538335D02*
X129098Y-537252D01*
X129288Y-536335D01*
X129541Y-535502D01*
X129858Y-534585D01*
X130365Y-533335D01*
X127831D01*
G01X133375Y-536668D02*
X135021D01*
G01X137905Y-537335D02*
X138285Y-537918D01*
X138791Y-538252D01*
X139361Y-538335D01*
X139868Y-538252D01*
X140375Y-537835D01*
X140691Y-537335D01*
X140755Y-536835D01*
X140628Y-536252D01*
X140185Y-535835D01*
X139741Y-535668D01*
X139171D01*
G01X139741D02*
X140121Y-535418D01*
X140438Y-535002D01*
X140565Y-534502D01*
X140438Y-534002D01*
X140121Y-533585D01*
X139551Y-533335D01*
X138981Y-533418D01*
X138411Y-533752D01*
G01X143195Y-536252D02*
X143638Y-535668D01*
X144018Y-535335D01*
X144525Y-535168D01*
X144968Y-535335D01*
X145285Y-535668D01*
X145538Y-536168D01*
X145601Y-536752D01*
X145538Y-537252D01*
X145285Y-537752D01*
X144905Y-538168D01*
X144461Y-538335D01*
X143955Y-538168D01*
X143511Y-537668D01*
X143258Y-536918D01*
X143195Y-536085D01*
X143321Y-535002D01*
X143511Y-534418D01*
X143828Y-533835D01*
X144271Y-533418D01*
X144715Y-533335D01*
X145158Y-533502D01*
X145475Y-533918D01*
G01X149498Y-538335D02*
Y-533335D01*
X148738Y-534335D01*
G01Y-538335D02*
X150258D01*
G01X155358D02*
Y-533335D01*
X153015Y-536918D01*
X156181D01*
G01X174398Y-468335D02*
Y-543335D01*
G01Y-518335D02*
X277398D01*
Y-493335D01*
G01X174398D02*
X277398D01*
G01Y-468335D02*
Y-543335D01*
G01X279398Y-468335D02*
Y-543335D01*
G01X284905Y-528335D02*
Y-523335D01*
X286171D01*
X286678Y-523585D01*
X287058Y-523918D01*
X287375Y-524418D01*
X287628Y-525002D01*
X287691Y-525835D01*
X287628Y-526668D01*
X287375Y-527252D01*
X287058Y-527752D01*
X286678Y-528085D01*
X286171Y-528335D01*
X284905D01*
G01X289815D02*
X291398Y-523335D01*
X292981Y-528335D01*
G01X292411Y-526585D02*
X290385D01*
G01X296498Y-523335D02*
Y-528335D01*
G01X295041Y-523335D02*
X297955D01*
G01X302865Y-528335D02*
X300331D01*
Y-523335D01*
X302865D01*
G01X301851Y-525752D02*
X300331D01*
G01X306698Y-528502D02*
X306571Y-528418D01*
Y-528252D01*
X306698Y-528168D01*
X306825Y-528252D01*
Y-528418D01*
X306698Y-528502D01*
G01Y-526252D02*
X306571Y-526168D01*
Y-526002D01*
X306698Y-525918D01*
X306825Y-526002D01*
Y-526168D01*
X306698Y-526252D01*
G01X279398Y-518335D02*
X479398D01*
G01X285031Y-503335D02*
Y-498335D01*
X286551D01*
X287058Y-498585D01*
X287438Y-499168D01*
X287565Y-499835D01*
X287438Y-500502D01*
X287121Y-501002D01*
X286551Y-501252D01*
X285031D01*
G01X290258Y-503502D02*
X292538Y-498335D01*
G01X295041Y-503335D02*
Y-498335D01*
X297955Y-503335D01*
Y-498335D01*
G01X301598Y-503502D02*
X301471Y-503418D01*
Y-503252D01*
X301598Y-503168D01*
X301725Y-503252D01*
Y-503418D01*
X301598Y-503502D01*
G01Y-501252D02*
X301471Y-501168D01*
Y-501002D01*
X301598Y-500918D01*
X301725Y-501002D01*
Y-501168D01*
X301598Y-501252D01*
G01X279398Y-493335D02*
X479398D01*
G01X285031Y-478335D02*
Y-473335D01*
X286551D01*
X287058Y-473585D01*
X287438Y-474168D01*
X287565Y-474835D01*
X287438Y-475502D01*
X287121Y-476002D01*
X286551Y-476252D01*
X285031D01*
G01X290131Y-478335D02*
Y-473335D01*
X291715D01*
X292221Y-473585D01*
X292538Y-473918D01*
X292665Y-474585D01*
X292538Y-475252D01*
X292158Y-475668D01*
X291715Y-475918D01*
X290131D01*
G01X291715D02*
X292665Y-478335D01*
G01X296498D02*
X295991Y-478252D01*
X295548Y-477918D01*
X295168Y-477418D01*
X294915Y-476835D01*
X294788Y-476168D01*
Y-475502D01*
X294915Y-474835D01*
X295168Y-474252D01*
X295548Y-473752D01*
X295991Y-473418D01*
X296498Y-473335D01*
X297005Y-473418D01*
X297448Y-473752D01*
X297828Y-474252D01*
X298081Y-474835D01*
X298208Y-475502D01*
Y-476168D01*
X298081Y-476835D01*
X297828Y-477418D01*
X297448Y-477918D01*
X297005Y-478252D01*
X296498Y-478335D01*
G01X300331Y-477335D02*
X300648Y-477835D01*
X301028Y-478168D01*
X301471Y-478335D01*
X301978Y-478168D01*
X302358Y-477835D01*
X302738Y-477335D01*
X302865Y-476668D01*
Y-473335D01*
G01X307965Y-478335D02*
X305431D01*
Y-473335D01*
X307965D01*
G01X306951Y-475752D02*
X305431D01*
G01X313191Y-473752D02*
X312811Y-473502D01*
X312368Y-473335D01*
X311861D01*
X311291Y-473585D01*
X310848Y-474002D01*
X310531Y-474502D01*
X310278Y-475335D01*
X310215Y-476085D01*
X310341Y-476835D01*
X310531Y-477335D01*
X310911Y-477835D01*
X311355Y-478168D01*
X311798Y-478335D01*
X312241D01*
X312685Y-478168D01*
X313065Y-477918D01*
X313381Y-477585D01*
G01X316898Y-473335D02*
Y-478335D01*
G01X315441Y-473335D02*
X318355D01*
G01X321998Y-478502D02*
X321871Y-478418D01*
Y-478252D01*
X321998Y-478168D01*
X322125Y-478252D01*
Y-478418D01*
X321998Y-478502D01*
G01Y-476252D02*
X321871Y-476168D01*
Y-476002D01*
X321998Y-475918D01*
X322125Y-476002D01*
Y-476168D01*
X321998Y-476252D01*
G01X394258Y-543563D02*
Y-518563D01*
G01X397031Y-520835D02*
Y-525835D01*
X399565D01*
G01X402638Y-520835D02*
X404158D01*
G01X403398D02*
Y-525835D01*
G01X402638D02*
X404158D01*
G01X409005Y-523168D02*
X409258Y-522918D01*
X409448Y-522502D01*
X409575Y-521918D01*
X409448Y-521418D01*
X409195Y-521085D01*
X408751Y-520835D01*
X407041D01*
Y-525835D01*
X409131D01*
X409575Y-525502D01*
X409828Y-525002D01*
X409955Y-524418D01*
X409828Y-523835D01*
X409448Y-523335D01*
X409005Y-523168D01*
X407041D01*
G01X413598Y-526002D02*
X413471Y-525918D01*
Y-525752D01*
X413598Y-525668D01*
X413725Y-525752D01*
Y-525918D01*
X413598Y-526002D01*
G01Y-523752D02*
X413471Y-523668D01*
Y-523502D01*
X413598Y-523418D01*
X413725Y-523502D01*
Y-523668D01*
X413598Y-523752D01*
G01X437258Y-518563D02*
Y-543563D01*
G01X437398Y-518335D02*
Y-543335D01*
G01X441298Y-520835D02*
Y-525835D01*
G01X439841Y-520835D02*
X442755D01*
G01X446398Y-525835D02*
X446018Y-525752D01*
X445638Y-525418D01*
X445385Y-524835D01*
X445258Y-524168D01*
X445385Y-523502D01*
X445638Y-522918D01*
X446018Y-522585D01*
X446398Y-522502D01*
X446778Y-522585D01*
X447158Y-522918D01*
X447411Y-523502D01*
X447475Y-524168D01*
X447411Y-524835D01*
X447158Y-525418D01*
X446778Y-525752D01*
X446398Y-525835D01*
G01X451498D02*
X451118Y-525752D01*
X450738Y-525418D01*
X450485Y-524835D01*
X450358Y-524168D01*
X450485Y-523502D01*
X450738Y-522918D01*
X451118Y-522585D01*
X451498Y-522502D01*
X451878Y-522585D01*
X452258Y-522918D01*
X452511Y-523502D01*
X452575Y-524168D01*
X452511Y-524835D01*
X452258Y-525418D01*
X451878Y-525752D01*
X451498Y-525835D01*
G01X456598D02*
Y-520835D01*
G01X461698Y-526002D02*
X461571Y-525918D01*
Y-525752D01*
X461698Y-525668D01*
X461825Y-525752D01*
Y-525918D01*
X461698Y-526002D01*
G01Y-523752D02*
X461571Y-523668D01*
Y-523502D01*
X461698Y-523418D01*
X461825Y-523502D01*
Y-523668D01*
X461698Y-523752D01*
G01X437398Y-493335D02*
Y-518335D01*
G01X440031Y-500835D02*
Y-495835D01*
X441615D01*
X442121Y-496085D01*
X442438Y-496418D01*
X442565Y-497085D01*
X442438Y-497752D01*
X442058Y-498168D01*
X441615Y-498418D01*
X440031D01*
G01X441615D02*
X442565Y-500835D01*
G01X447665D02*
X445131D01*
Y-495835D01*
X447665D01*
G01X446651Y-498252D02*
X445131D01*
G01X449915Y-495835D02*
X451498Y-500835D01*
X453081Y-495835D01*
G01X456598Y-501002D02*
X456471Y-500918D01*
Y-500752D01*
X456598Y-500668D01*
X456725Y-500752D01*
Y-500918D01*
X456598Y-501002D01*
G01Y-498752D02*
X456471Y-498668D01*
Y-498502D01*
X456598Y-498418D01*
X456725Y-498502D01*
Y-498668D01*
X456598Y-498752D01*
G01X445411Y-546502D02*
X445518Y-546377D01*
X445598Y-546168D01*
X445651Y-545877D01*
X445598Y-545627D01*
X445491Y-545460D01*
X445305Y-545335D01*
X444585D01*
Y-547835D01*
X445465D01*
X445651Y-547668D01*
X445758Y-547418D01*
X445811Y-547127D01*
X445758Y-546835D01*
X445598Y-546585D01*
X445411Y-546502D01*
X444585D01*
G01X447878Y-547835D02*
Y-546168D01*
G01Y-546460D02*
X447771Y-546293D01*
X447611Y-546210D01*
X447425Y-546168D01*
X447238Y-546252D01*
X447078Y-546418D01*
X446971Y-546668D01*
X446918Y-547002D01*
X446971Y-547335D01*
X447078Y-547585D01*
X447238Y-547752D01*
X447425Y-547835D01*
X447611Y-547793D01*
X447771Y-547668D01*
X447878Y-547502D01*
G01X449198Y-547543D02*
X449331Y-547710D01*
X449518Y-547835D01*
X449678D01*
X449838Y-547752D01*
X449945Y-547627D01*
X449998Y-547460D01*
X449971Y-547210D01*
X449865Y-547085D01*
X449385Y-546835D01*
X449278Y-546543D01*
X449331Y-546335D01*
X449438Y-546210D01*
X449598Y-546168D01*
X449758Y-546210D01*
X449918Y-546335D01*
G01X451398Y-546710D02*
X452251D01*
X452171Y-546418D01*
X452038Y-546252D01*
X451851Y-546168D01*
X451665Y-546210D01*
X451505Y-546335D01*
X451398Y-546627D01*
X451345Y-546877D01*
Y-547127D01*
X451398Y-547377D01*
X451531Y-547627D01*
X451691Y-547793D01*
X451878Y-547835D01*
X452065Y-547752D01*
X452251Y-547502D01*
G01X453518Y-547835D02*
Y-545335D01*
G01Y-546585D02*
X453651Y-546335D01*
X453811Y-546210D01*
X453971Y-546168D01*
X454211Y-546252D01*
X454371Y-546418D01*
X454478Y-546710D01*
Y-547043D01*
X454425Y-547377D01*
X454318Y-547627D01*
X454131Y-547793D01*
X453971Y-547835D01*
X453811Y-547793D01*
X453651Y-547668D01*
X453518Y-547460D01*
G01X456198Y-547835D02*
X456038Y-547793D01*
X455878Y-547627D01*
X455771Y-547335D01*
X455718Y-547002D01*
X455771Y-546668D01*
X455878Y-546377D01*
X456038Y-546210D01*
X456198Y-546168D01*
X456358Y-546210D01*
X456518Y-546377D01*
X456625Y-546668D01*
X456651Y-547002D01*
X456625Y-547335D01*
X456518Y-547627D01*
X456358Y-547793D01*
X456198Y-547835D01*
G01X458878D02*
Y-546168D01*
G01Y-546460D02*
X458771Y-546293D01*
X458611Y-546210D01*
X458425Y-546168D01*
X458238Y-546252D01*
X458078Y-546418D01*
X457971Y-546668D01*
X457918Y-547002D01*
X457971Y-547335D01*
X458078Y-547585D01*
X458238Y-547752D01*
X458425Y-547835D01*
X458611Y-547793D01*
X458771Y-547668D01*
X458878Y-547502D01*
G01X460225Y-547835D02*
Y-546168D01*
G01Y-546502D02*
X460358Y-546335D01*
X460491Y-546210D01*
X460678Y-546168D01*
X460811Y-546210D01*
X460971Y-546335D01*
G01X463278Y-545335D02*
Y-547835D01*
G01Y-547460D02*
X463171Y-547668D01*
X463011Y-547793D01*
X462825Y-547835D01*
X462611Y-547752D01*
X462451Y-547543D01*
X462345Y-547293D01*
X462318Y-547002D01*
X462345Y-546710D01*
X462451Y-546460D01*
X462611Y-546252D01*
X462825Y-546168D01*
X463011Y-546210D01*
X463145Y-546293D01*
X463278Y-546460D01*
G01X466665Y-547835D02*
Y-545335D01*
X467331D01*
X467545Y-545460D01*
X467678Y-545627D01*
X467731Y-545960D01*
X467678Y-546293D01*
X467518Y-546502D01*
X467331Y-546627D01*
X466665D01*
G01X467331D02*
X467731Y-547835D01*
G01X468998Y-546710D02*
X469851D01*
X469771Y-546418D01*
X469638Y-546252D01*
X469451Y-546168D01*
X469265Y-546210D01*
X469105Y-546335D01*
X468998Y-546627D01*
X468945Y-546877D01*
Y-547127D01*
X468998Y-547377D01*
X469131Y-547627D01*
X469291Y-547793D01*
X469478Y-547835D01*
X469665Y-547752D01*
X469851Y-547502D01*
G01X471118Y-546168D02*
X471598Y-547835D01*
X472078Y-546168D01*
G01X473798Y-547918D02*
X473745Y-547877D01*
Y-547793D01*
X473798Y-547752D01*
X473851Y-547793D01*
Y-547877D01*
X473798Y-547918D01*
G01X475545Y-547543D02*
X475731Y-547752D01*
X475945Y-547835D01*
X476158Y-547752D01*
X476345Y-547502D01*
X476478Y-547127D01*
X476531Y-546752D01*
Y-546293D01*
X476478Y-545918D01*
X476345Y-545585D01*
X476185Y-545418D01*
X475998Y-545335D01*
X475785Y-545418D01*
X475625Y-545585D01*
X475518Y-545835D01*
X475465Y-546168D01*
X475518Y-546460D01*
X475651Y-546752D01*
X475811Y-546918D01*
X475998Y-546960D01*
X476211Y-546877D01*
X476371Y-546668D01*
X476531Y-546293D01*
G01X478411Y-546502D02*
X478518Y-546377D01*
X478598Y-546168D01*
X478651Y-545877D01*
X478598Y-545627D01*
X478491Y-545460D01*
X478305Y-545335D01*
X477585D01*
Y-547835D01*
X478465D01*
X478651Y-547668D01*
X478758Y-547418D01*
X478811Y-547127D01*
X478758Y-546835D01*
X478598Y-546585D01*
X478411Y-546502D01*
X477585D01*
G01X-1490433Y-1677216D02*
Y3837819D01*
X4496476D01*
Y-1677216D01*
X-1490433D01*
G01X-7782Y-515685D02*
X-6215D01*
Y-517575D01*
X-6685Y-518205D01*
X-7234Y-518625D01*
X-8017Y-518835D01*
X-8800Y-518625D01*
X-9349Y-518205D01*
X-9819Y-517575D01*
X-10132Y-516840D01*
X-10289Y-516000D01*
Y-515265D01*
X-10132Y-514635D01*
X-9819Y-513900D01*
X-9349Y-513270D01*
X-8879Y-512850D01*
X-8252Y-512535D01*
X-7704D01*
X-7077Y-512745D01*
X-6607Y-513165D01*
G01X-3675Y-512535D02*
Y-517050D01*
X-3362Y-517995D01*
X-2735Y-518625D01*
X-1952Y-518835D01*
X-1169Y-518625D01*
X-542Y-517995D01*
X-229Y-517050D01*
Y-512535D01*
G01X3408D02*
X5288D01*
G01X4348D02*
Y-518835D01*
G01X3408D02*
X5288D01*
G01X9003Y-517995D02*
X9630Y-518520D01*
X10335Y-518835D01*
X10961D01*
X11588Y-518520D01*
X12058Y-517995D01*
X12293Y-517260D01*
X12136Y-516525D01*
X11745Y-515895D01*
X11040Y-515475D01*
X10100Y-515265D01*
X9551Y-514845D01*
X9316Y-514110D01*
X9473Y-513375D01*
X9865Y-512850D01*
X10413Y-512535D01*
X10961D01*
X11510Y-512745D01*
X11980Y-513270D01*
G01X15303Y-518835D02*
Y-512535D01*
G01X18593D02*
Y-518835D01*
G01Y-515685D02*
X15303D01*
G01X21290Y-518835D02*
X23248Y-512535D01*
X25206Y-518835D01*
G01X24501Y-516630D02*
X21995D01*
G01X27746Y-518835D02*
Y-512535D01*
X31350Y-518835D01*
Y-512535D01*
G01X40425Y-518835D02*
Y-512535D01*
X41991D01*
X42618Y-512850D01*
X43088Y-513270D01*
X43480Y-513900D01*
X43793Y-514635D01*
X43871Y-515685D01*
X43793Y-516735D01*
X43480Y-517470D01*
X43088Y-518100D01*
X42618Y-518520D01*
X41991Y-518835D01*
X40425D01*
G01X47508Y-512535D02*
X49388D01*
G01X48448D02*
Y-518835D01*
G01X47508D02*
X49388D01*
G01X53103Y-517995D02*
X53730Y-518520D01*
X54435Y-518835D01*
X55061D01*
X55688Y-518520D01*
X56158Y-517995D01*
X56393Y-517260D01*
X56236Y-516525D01*
X55845Y-515895D01*
X55140Y-515475D01*
X54200Y-515265D01*
X53651Y-514845D01*
X53416Y-514110D01*
X53573Y-513375D01*
X53965Y-512850D01*
X54513Y-512535D01*
X55061D01*
X55610Y-512745D01*
X56080Y-513270D01*
G01X61048Y-512535D02*
Y-518835D01*
G01X59246Y-512535D02*
X62850D01*
G01X67348Y-519045D02*
X67191Y-518940D01*
Y-518730D01*
X67348Y-518625D01*
X67505Y-518730D01*
Y-518940D01*
X67348Y-519045D01*
G01X73491Y-519990D02*
X73805Y-518625D01*
G01X79948Y-512535D02*
Y-518835D01*
G01X78146Y-512535D02*
X81750D01*
G01X84290Y-518835D02*
X86248Y-512535D01*
X88206Y-518835D01*
G01X87501Y-516630D02*
X84995D01*
G01X92548Y-518835D02*
X91921Y-518730D01*
X91373Y-518310D01*
X90903Y-517680D01*
X90590Y-516945D01*
X90433Y-516105D01*
Y-515265D01*
X90590Y-514425D01*
X90903Y-513690D01*
X91373Y-513060D01*
X91921Y-512640D01*
X92548Y-512535D01*
X93175Y-512640D01*
X93723Y-513060D01*
X94193Y-513690D01*
X94506Y-514425D01*
X94663Y-515265D01*
Y-516105D01*
X94506Y-516945D01*
X94193Y-517680D01*
X93723Y-518310D01*
X93175Y-518730D01*
X92548Y-518835D01*
G01X98848D02*
Y-516000D01*
X97281Y-512535D01*
G01X100415D02*
X98848Y-516000D01*
G01X103425Y-512535D02*
Y-517050D01*
X103738Y-517995D01*
X104365Y-518625D01*
X105148Y-518835D01*
X105931Y-518625D01*
X106558Y-517995D01*
X106871Y-517050D01*
Y-512535D01*
G01X109490Y-518835D02*
X111448Y-512535D01*
X113406Y-518835D01*
G01X112701Y-516630D02*
X110195D01*
G01X115946Y-518835D02*
Y-512535D01*
X119550Y-518835D01*
Y-512535D01*
G01X-6529Y-523060D02*
X-6999Y-522745D01*
X-7547Y-522535D01*
X-8174D01*
X-8879Y-522850D01*
X-9427Y-523375D01*
X-9819Y-524005D01*
X-10132Y-525055D01*
X-10210Y-526000D01*
X-10054Y-526945D01*
X-9819Y-527575D01*
X-9349Y-528205D01*
X-8800Y-528625D01*
X-8252Y-528835D01*
X-7704D01*
X-7155Y-528625D01*
X-6685Y-528310D01*
X-6294Y-527890D01*
G01X-2892Y-522535D02*
X-1012D01*
G01X-1952D02*
Y-528835D01*
G01X-2892D02*
X-1012D01*
G01X4348Y-522535D02*
Y-528835D01*
G01X2546Y-522535D02*
X6150D01*
G01X10648Y-528835D02*
Y-526000D01*
X9081Y-522535D01*
G01X12215D02*
X10648Y-526000D01*
G01X21525Y-527575D02*
X21995Y-528310D01*
X22621Y-528730D01*
X23326Y-528835D01*
X23953Y-528730D01*
X24580Y-528205D01*
X24971Y-527575D01*
X25050Y-526945D01*
X24893Y-526210D01*
X24345Y-525685D01*
X23796Y-525475D01*
X23091D01*
G01X23796D02*
X24266Y-525160D01*
X24658Y-524635D01*
X24815Y-524005D01*
X24658Y-523375D01*
X24266Y-522850D01*
X23561Y-522535D01*
X22856Y-522640D01*
X22151Y-523060D01*
G01X27825Y-527575D02*
X28295Y-528310D01*
X28921Y-528730D01*
X29626Y-528835D01*
X30253Y-528730D01*
X30880Y-528205D01*
X31271Y-527575D01*
X31350Y-526945D01*
X31193Y-526210D01*
X30645Y-525685D01*
X30096Y-525475D01*
X29391D01*
G01X30096D02*
X30566Y-525160D01*
X30958Y-524635D01*
X31115Y-524005D01*
X30958Y-523375D01*
X30566Y-522850D01*
X29861Y-522535D01*
X29156Y-522640D01*
X28451Y-523060D01*
G01X34125Y-527575D02*
X34595Y-528310D01*
X35221Y-528730D01*
X35926Y-528835D01*
X36553Y-528730D01*
X37180Y-528205D01*
X37571Y-527575D01*
X37650Y-526945D01*
X37493Y-526210D01*
X36945Y-525685D01*
X36396Y-525475D01*
X35691D01*
G01X36396D02*
X36866Y-525160D01*
X37258Y-524635D01*
X37415Y-524005D01*
X37258Y-523375D01*
X36866Y-522850D01*
X36161Y-522535D01*
X35456Y-522640D01*
X34751Y-523060D01*
G01X41991Y-528835D02*
X42148Y-527470D01*
X42383Y-526315D01*
X42696Y-525265D01*
X43088Y-524110D01*
X43715Y-522535D01*
X40581D01*
G01X48291Y-528835D02*
X48448Y-527470D01*
X48683Y-526315D01*
X48996Y-525265D01*
X49388Y-524110D01*
X50015Y-522535D01*
X46881D01*
G01X54591Y-529990D02*
X54905Y-528625D01*
G01X61048Y-522535D02*
Y-528835D01*
G01X59246Y-522535D02*
X62850D01*
G01X65390Y-528835D02*
X67348Y-522535D01*
X69306Y-528835D01*
G01X68601Y-526630D02*
X66095D01*
G01X72708Y-522535D02*
X74588D01*
G01X73648D02*
Y-528835D01*
G01X72708D02*
X74588D01*
G01X77598Y-522535D02*
X78695Y-528835D01*
X79948Y-522535D01*
X81201Y-528835D01*
X82298Y-522535D01*
G01X84290Y-528835D02*
X86248Y-522535D01*
X88206Y-528835D01*
G01X87501Y-526630D02*
X84995D01*
G01X90746Y-528835D02*
Y-522535D01*
X94350Y-528835D01*
Y-522535D01*
G01X104756Y-530935D02*
X103973Y-529885D01*
X103581Y-528835D01*
Y-524635D01*
X103973Y-523585D01*
X104756Y-522535D01*
G01X116181Y-528835D02*
Y-522535D01*
X118140D01*
X118766Y-522850D01*
X119158Y-523270D01*
X119315Y-524110D01*
X119158Y-524950D01*
X118688Y-525475D01*
X118140Y-525790D01*
X116181D01*
G01X118140D02*
X119315Y-528835D01*
G01X124048Y-529045D02*
X123891Y-528940D01*
Y-528730D01*
X124048Y-528625D01*
X124205Y-528730D01*
Y-528940D01*
X124048Y-529045D01*
G01X130348Y-528835D02*
X129721Y-528730D01*
X129173Y-528310D01*
X128703Y-527680D01*
X128390Y-526945D01*
X128233Y-526105D01*
Y-525265D01*
X128390Y-524425D01*
X128703Y-523690D01*
X129173Y-523060D01*
X129721Y-522640D01*
X130348Y-522535D01*
X130975Y-522640D01*
X131523Y-523060D01*
X131993Y-523690D01*
X132306Y-524425D01*
X132463Y-525265D01*
Y-526105D01*
X132306Y-526945D01*
X131993Y-527680D01*
X131523Y-528310D01*
X130975Y-528730D01*
X130348Y-528835D01*
G01X136648Y-529045D02*
X136491Y-528940D01*
Y-528730D01*
X136648Y-528625D01*
X136805Y-528730D01*
Y-528940D01*
X136648Y-529045D01*
G01X144671Y-523060D02*
X144201Y-522745D01*
X143653Y-522535D01*
X143026D01*
X142321Y-522850D01*
X141773Y-523375D01*
X141381Y-524005D01*
X141068Y-525055D01*
X140990Y-526000D01*
X141146Y-526945D01*
X141381Y-527575D01*
X141851Y-528205D01*
X142400Y-528625D01*
X142948Y-528835D01*
X143496D01*
X144045Y-528625D01*
X144515Y-528310D01*
X144906Y-527890D01*
G01X149248Y-529045D02*
X149091Y-528940D01*
Y-528730D01*
X149248Y-528625D01*
X149405Y-528730D01*
Y-528940D01*
X149248Y-529045D01*
G01X155940Y-530935D02*
X156723Y-529885D01*
X157115Y-528835D01*
Y-524635D01*
X156723Y-523585D01*
X155940Y-522535D01*
G01X-10054Y-508835D02*
Y-502535D01*
X-6450Y-508835D01*
Y-502535D01*
G01X-1952Y-508835D02*
X-2579Y-508730D01*
X-3127Y-508310D01*
X-3597Y-507680D01*
X-3910Y-506945D01*
X-4067Y-506105D01*
Y-505265D01*
X-3910Y-504425D01*
X-3597Y-503690D01*
X-3127Y-503060D01*
X-2579Y-502640D01*
X-1952Y-502535D01*
X-1325Y-502640D01*
X-777Y-503060D01*
X-307Y-503690D01*
X6Y-504425D01*
X163Y-505265D01*
Y-506105D01*
X6Y-506945D01*
X-307Y-507680D01*
X-777Y-508310D01*
X-1325Y-508730D01*
X-1952Y-508835D01*
G01X4348Y-509045D02*
X4191Y-508940D01*
Y-508730D01*
X4348Y-508625D01*
X4505Y-508730D01*
Y-508940D01*
X4348Y-509045D01*
G01X9160Y-503585D02*
X9630Y-502955D01*
X10178Y-502640D01*
X10805Y-502535D01*
X11588Y-502745D01*
X12136Y-503270D01*
X12293Y-503900D01*
X12215Y-504530D01*
X11901Y-505055D01*
X10335Y-506105D01*
X9630Y-506840D01*
X9160Y-507890D01*
X9003Y-508835D01*
X12293D01*
G01X16948D02*
Y-502535D01*
X16008Y-503795D01*
G01Y-508835D02*
X17888D01*
G01X23248D02*
Y-502535D01*
X22308Y-503795D01*
G01Y-508835D02*
X24188D01*
G01X29391Y-509990D02*
X29705Y-508625D01*
G01X33498Y-502535D02*
X34595Y-508835D01*
X35848Y-502535D01*
X37101Y-508835D01*
X38198Y-502535D01*
G01X43715Y-508835D02*
X40581D01*
Y-502535D01*
X43715D01*
G01X42461Y-505580D02*
X40581D01*
G01X46646Y-508835D02*
Y-502535D01*
X50250Y-508835D01*
Y-502535D01*
G01X53103Y-508835D02*
Y-502535D01*
G01X56393D02*
Y-508835D01*
G01Y-505685D02*
X53103D01*
G01X59325Y-502535D02*
Y-507050D01*
X59638Y-507995D01*
X60265Y-508625D01*
X61048Y-508835D01*
X61831Y-508625D01*
X62458Y-507995D01*
X62771Y-507050D01*
Y-502535D01*
G01X65390Y-508835D02*
X67348Y-502535D01*
X69306Y-508835D01*
G01X68601Y-506630D02*
X66095D01*
G01X78460Y-503585D02*
X78930Y-502955D01*
X79478Y-502640D01*
X80105Y-502535D01*
X80888Y-502745D01*
X81436Y-503270D01*
X81593Y-503900D01*
X81515Y-504530D01*
X81201Y-505055D01*
X79635Y-506105D01*
X78930Y-506840D01*
X78460Y-507890D01*
X78303Y-508835D01*
X81593D01*
G01X84446D02*
Y-502535D01*
X88050Y-508835D01*
Y-502535D01*
G01X90825Y-508835D02*
Y-502535D01*
X92391D01*
X93018Y-502850D01*
X93488Y-503270D01*
X93880Y-503900D01*
X94193Y-504635D01*
X94271Y-505685D01*
X94193Y-506735D01*
X93880Y-507470D01*
X93488Y-508100D01*
X93018Y-508520D01*
X92391Y-508835D01*
X90825D01*
G01X103581D02*
Y-502535D01*
X105540D01*
X106166Y-502850D01*
X106558Y-503270D01*
X106715Y-504110D01*
X106558Y-504950D01*
X106088Y-505475D01*
X105540Y-505790D01*
X103581D01*
G01X105540D02*
X106715Y-508835D01*
G01X109725D02*
Y-502535D01*
X111291D01*
X111918Y-502850D01*
X112388Y-503270D01*
X112780Y-503900D01*
X113093Y-504635D01*
X113171Y-505685D01*
X113093Y-506735D01*
X112780Y-507470D01*
X112388Y-508100D01*
X111918Y-508520D01*
X111291Y-508835D01*
X109725D01*
G01X117748Y-509045D02*
X117591Y-508940D01*
Y-508730D01*
X117748Y-508625D01*
X117905Y-508730D01*
Y-508940D01*
X117748Y-509045D01*
G01X14048Y-498135D02*
X11528Y-497718D01*
X9323Y-496052D01*
X7433Y-493552D01*
X6173Y-490635D01*
X5543Y-487302D01*
Y-483968D01*
X6173Y-480635D01*
X7433Y-477718D01*
X9323Y-475219D01*
X11528Y-473552D01*
X14048Y-473135D01*
X16568Y-473552D01*
X18773Y-475219D01*
X20663Y-477718D01*
X21923Y-480635D01*
X22553Y-483968D01*
Y-487302D01*
X21923Y-490635D01*
X20663Y-493552D01*
X18773Y-496052D01*
X16568Y-497718D01*
X14048Y-498135D01*
G01X16568Y-491468D02*
X20348Y-498135D01*
G01X33893Y-481469D02*
Y-493135D01*
X35153Y-496052D01*
X37043Y-497718D01*
X39248Y-498135D01*
X41453Y-497718D01*
X43343Y-496052D01*
X44603Y-493135D01*
G01Y-498135D02*
Y-481469D01*
G01X70118Y-498135D02*
Y-481469D01*
G01Y-484385D02*
X68858Y-482719D01*
X66968Y-481885D01*
X64763Y-481469D01*
X62558Y-482302D01*
X60668Y-483968D01*
X59408Y-486469D01*
X58778Y-489802D01*
X59408Y-493135D01*
X60668Y-495636D01*
X62558Y-497302D01*
X64763Y-498135D01*
X66968Y-497718D01*
X68858Y-496469D01*
X70118Y-494802D01*
G01X84293Y-498135D02*
Y-481469D01*
G01Y-485635D02*
X85553Y-483552D01*
X87443Y-481885D01*
X89963Y-481469D01*
X92168Y-481885D01*
X94058Y-483552D01*
X95003Y-486469D01*
Y-498135D01*
G01X114848Y-473135D02*
Y-498135D01*
G01X110438Y-481469D02*
X119258D01*
G01X145718Y-498135D02*
Y-481469D01*
G01Y-484385D02*
X144458Y-482719D01*
X142568Y-481885D01*
X140363Y-481469D01*
X138158Y-482302D01*
X136268Y-483968D01*
X135008Y-486469D01*
X134378Y-489802D01*
X135008Y-493135D01*
X136268Y-495636D01*
X138158Y-497302D01*
X140363Y-498135D01*
X142568Y-497718D01*
X144458Y-496469D01*
X145718Y-494802D01*
G01X196898Y-510835D02*
Y-502835D01*
X199298D01*
X200098Y-503235D01*
X200698Y-504168D01*
X200898Y-505235D01*
X200698Y-506302D01*
X200198Y-507102D01*
X199298Y-507502D01*
X196898D01*
G01X204398Y-510835D02*
X206898Y-502835D01*
X209398Y-510835D01*
G01X208498Y-508035D02*
X205298D01*
G01X212798Y-509769D02*
X213598Y-510435D01*
X214498Y-510835D01*
X215298D01*
X216098Y-510435D01*
X216698Y-509769D01*
X216998Y-508835D01*
X216798Y-507902D01*
X216298Y-507102D01*
X215398Y-506568D01*
X214198Y-506302D01*
X213498Y-505768D01*
X213198Y-504835D01*
X213398Y-503902D01*
X213898Y-503235D01*
X214598Y-502835D01*
X215298D01*
X215998Y-503102D01*
X216598Y-503768D01*
G01X222898Y-502835D02*
Y-510835D01*
G01X220598Y-502835D02*
X225198D01*
G01X229598Y-508168D02*
X232198D01*
G01X238898Y-502835D02*
Y-510835D01*
G01X236598Y-502835D02*
X241198D01*
G01X246898Y-510835D02*
X246098Y-510702D01*
X245398Y-510168D01*
X244798Y-509368D01*
X244398Y-508435D01*
X244198Y-507368D01*
Y-506302D01*
X244398Y-505235D01*
X244798Y-504302D01*
X245398Y-503502D01*
X246098Y-502968D01*
X246898Y-502835D01*
X247698Y-502968D01*
X248398Y-503502D01*
X248998Y-504302D01*
X249398Y-505235D01*
X249598Y-506302D01*
Y-507368D01*
X249398Y-508435D01*
X248998Y-509368D01*
X248398Y-510168D01*
X247698Y-510702D01*
X246898Y-510835D01*
G01X252898D02*
Y-502835D01*
X255298D01*
X256098Y-503235D01*
X256698Y-504168D01*
X256898Y-505235D01*
X256698Y-506302D01*
X256198Y-507102D01*
X255298Y-507502D01*
X252898D01*
G01X185398Y-477835D02*
Y-485835D01*
X189398D01*
G01X197198D02*
Y-480502D01*
G01Y-481435D02*
X196798Y-480902D01*
X196198Y-480635D01*
X195498Y-480502D01*
X194798Y-480768D01*
X194198Y-481302D01*
X193798Y-482102D01*
X193598Y-483168D01*
X193798Y-484235D01*
X194198Y-485035D01*
X194798Y-485568D01*
X195498Y-485835D01*
X196198Y-485702D01*
X196798Y-485302D01*
X197198Y-484769D01*
G01X201298Y-488235D02*
X201898Y-488502D01*
X202698Y-488235D01*
X203198Y-487702D01*
X203598Y-487035D01*
X204198Y-484902D01*
X205498Y-480502D01*
G01X202298D02*
X204198Y-484902D01*
G01X209898Y-482235D02*
X213098D01*
X212798Y-481302D01*
X212298Y-480768D01*
X211598Y-480502D01*
X210898Y-480635D01*
X210298Y-481035D01*
X209898Y-481968D01*
X209698Y-482769D01*
Y-483568D01*
X209898Y-484368D01*
X210398Y-485168D01*
X210998Y-485702D01*
X211698Y-485835D01*
X212398Y-485568D01*
X213098Y-484769D01*
G01X217998Y-485835D02*
Y-480502D01*
G01Y-481568D02*
X218498Y-481035D01*
X218998Y-480635D01*
X219698Y-480502D01*
X220198Y-480635D01*
X220798Y-481035D01*
G01X211398Y-535835D02*
Y-532235D01*
X209398Y-527835D01*
G01X213398D02*
X211398Y-532235D01*
G01X217698Y-530502D02*
Y-534235D01*
X218098Y-535168D01*
X218698Y-535702D01*
X219398Y-535835D01*
X220098Y-535702D01*
X220698Y-535168D01*
X221098Y-534235D01*
G01Y-535835D02*
Y-530502D01*
G01X225698Y-535835D02*
Y-530502D01*
G01Y-531835D02*
X226098Y-531168D01*
X226698Y-530635D01*
X227498Y-530502D01*
X228198Y-530635D01*
X228798Y-531168D01*
X229098Y-532102D01*
Y-535835D01*
G01X237198D02*
Y-530502D01*
G01Y-531435D02*
X236798Y-530902D01*
X236198Y-530635D01*
X235498Y-530502D01*
X234798Y-530768D01*
X234198Y-531302D01*
X233798Y-532102D01*
X233598Y-533168D01*
X233798Y-534235D01*
X234198Y-535035D01*
X234798Y-535568D01*
X235498Y-535835D01*
X236198Y-535702D01*
X236798Y-535302D01*
X237198Y-534769D01*
G01X311998Y-529168D02*
X312598Y-528368D01*
X313298Y-527968D01*
X314098Y-527835D01*
X315098Y-528102D01*
X315798Y-528768D01*
X315998Y-529568D01*
X315898Y-530369D01*
X315498Y-531035D01*
X313498Y-532368D01*
X312598Y-533302D01*
X311998Y-534635D01*
X311798Y-535835D01*
X315998D01*
G01X321898Y-527835D02*
X321098Y-528102D01*
X320498Y-528768D01*
X320098Y-529568D01*
X319798Y-530635D01*
X319698Y-531835D01*
X319798Y-533035D01*
X320098Y-534102D01*
X320498Y-534902D01*
X321098Y-535568D01*
X321898Y-535835D01*
X322698Y-535568D01*
X323298Y-534902D01*
X323698Y-534102D01*
X323998Y-533035D01*
X324098Y-531835D01*
X323998Y-530635D01*
X323698Y-529568D01*
X323298Y-528768D01*
X322698Y-528102D01*
X321898Y-527835D01*
G01X327998Y-529168D02*
X328598Y-528368D01*
X329298Y-527968D01*
X330098Y-527835D01*
X331098Y-528102D01*
X331798Y-528768D01*
X331998Y-529568D01*
X331898Y-530369D01*
X331498Y-531035D01*
X329498Y-532368D01*
X328598Y-533302D01*
X327998Y-534635D01*
X327798Y-535835D01*
X331998D01*
G01X335698Y-534235D02*
X336298Y-535168D01*
X337098Y-535702D01*
X337998Y-535835D01*
X338798Y-535702D01*
X339598Y-535035D01*
X340098Y-534235D01*
X340198Y-533435D01*
X339998Y-532502D01*
X339298Y-531835D01*
X338598Y-531568D01*
X337698D01*
G01X338598D02*
X339198Y-531168D01*
X339698Y-530502D01*
X339898Y-529702D01*
X339698Y-528902D01*
X339198Y-528235D01*
X338298Y-527835D01*
X337398Y-527968D01*
X336498Y-528502D01*
G01X344098Y-536102D02*
X347698Y-527835D01*
G01X353898D02*
X353098Y-528102D01*
X352498Y-528768D01*
X352098Y-529568D01*
X351798Y-530635D01*
X351698Y-531835D01*
X351798Y-533035D01*
X352098Y-534102D01*
X352498Y-534902D01*
X353098Y-535568D01*
X353898Y-535835D01*
X354698Y-535568D01*
X355298Y-534902D01*
X355698Y-534102D01*
X355998Y-533035D01*
X356098Y-531835D01*
X355998Y-530635D01*
X355698Y-529568D01*
X355298Y-528768D01*
X354698Y-528102D01*
X353898Y-527835D01*
G01X361898Y-535835D02*
Y-527835D01*
X360698Y-529435D01*
G01Y-535835D02*
X363098D01*
G01X368098Y-536102D02*
X371698Y-527835D01*
G01X377898D02*
X377098Y-528102D01*
X376498Y-528768D01*
X376098Y-529568D01*
X375798Y-530635D01*
X375698Y-531835D01*
X375798Y-533035D01*
X376098Y-534102D01*
X376498Y-534902D01*
X377098Y-535568D01*
X377898Y-535835D01*
X378698Y-535568D01*
X379298Y-534902D01*
X379698Y-534102D01*
X379998Y-533035D01*
X380098Y-531835D01*
X379998Y-530635D01*
X379698Y-529568D01*
X379298Y-528768D01*
X378698Y-528102D01*
X377898Y-527835D01*
G01X384198Y-534902D02*
X384898Y-535568D01*
X385698Y-535835D01*
X386498Y-535568D01*
X387198Y-534769D01*
X387698Y-533568D01*
X387898Y-532368D01*
Y-530902D01*
X387698Y-529702D01*
X387198Y-528635D01*
X386598Y-528102D01*
X385898Y-527835D01*
X385098Y-528102D01*
X384498Y-528635D01*
X384098Y-529435D01*
X383898Y-530502D01*
X384098Y-531435D01*
X384598Y-532368D01*
X385198Y-532902D01*
X385898Y-533035D01*
X386698Y-532769D01*
X387298Y-532102D01*
X387898Y-530902D01*
G01X311698Y-510835D02*
Y-502835D01*
X313698D01*
X314498Y-503235D01*
X315098Y-503768D01*
X315598Y-504568D01*
X315998Y-505502D01*
X316098Y-506835D01*
X315998Y-508168D01*
X315598Y-509102D01*
X315098Y-509902D01*
X314498Y-510435D01*
X313698Y-510835D01*
X311698D01*
G01X319398D02*
X321898Y-502835D01*
X324398Y-510835D01*
G01X323498Y-508035D02*
X320298D01*
G01X329898Y-502835D02*
X329098Y-503102D01*
X328498Y-503768D01*
X328098Y-504568D01*
X327798Y-505635D01*
X327698Y-506835D01*
X327798Y-508035D01*
X328098Y-509102D01*
X328498Y-509902D01*
X329098Y-510568D01*
X329898Y-510835D01*
X330698Y-510568D01*
X331298Y-509902D01*
X331698Y-509102D01*
X331998Y-508035D01*
X332098Y-506835D01*
X331998Y-505635D01*
X331698Y-504568D01*
X331298Y-503768D01*
X330698Y-503102D01*
X329898Y-502835D01*
G01X335998Y-510835D02*
Y-502835D01*
X339798D01*
G01X338398Y-506702D02*
X335998D01*
G01X345898Y-502835D02*
X345098Y-503102D01*
X344498Y-503768D01*
X344098Y-504568D01*
X343798Y-505635D01*
X343698Y-506835D01*
X343798Y-508035D01*
X344098Y-509102D01*
X344498Y-509902D01*
X345098Y-510568D01*
X345898Y-510835D01*
X346698Y-510568D01*
X347298Y-509902D01*
X347698Y-509102D01*
X347998Y-508035D01*
X348098Y-506835D01*
X347998Y-505635D01*
X347698Y-504568D01*
X347298Y-503768D01*
X346698Y-503102D01*
X345898Y-502835D01*
G01X353898D02*
Y-510835D01*
G01X351598Y-502835D02*
X356198D01*
G01X363898Y-510835D02*
X359898D01*
Y-502835D01*
X363898D01*
G01X362298Y-506702D02*
X359898D01*
G01X370698Y-506568D02*
X371098Y-506168D01*
X371398Y-505502D01*
X371598Y-504568D01*
X371398Y-503768D01*
X370998Y-503235D01*
X370298Y-502835D01*
X367598D01*
Y-510835D01*
X370898D01*
X371598Y-510302D01*
X371998Y-509502D01*
X372198Y-508568D01*
X371998Y-507635D01*
X371398Y-506835D01*
X370698Y-506568D01*
X367598D01*
G01X376698Y-502835D02*
X379098D01*
G01X377898D02*
Y-510835D01*
G01X376698D02*
X379098D01*
G01X383998D02*
Y-502835D01*
X387798D01*
G01X386398Y-506702D02*
X383998D01*
G01X393898Y-502835D02*
X393098Y-503102D01*
X392498Y-503768D01*
X392098Y-504568D01*
X391798Y-505635D01*
X391698Y-506835D01*
X391798Y-508035D01*
X392098Y-509102D01*
X392498Y-509902D01*
X393098Y-510568D01*
X393898Y-510835D01*
X394698Y-510568D01*
X395298Y-509902D01*
X395698Y-509102D01*
X395998Y-508035D01*
X396098Y-506835D01*
X395998Y-505635D01*
X395698Y-504568D01*
X395298Y-503768D01*
X394698Y-503102D01*
X393898Y-502835D01*
G01X329498Y-485835D02*
Y-477835D01*
X333298D01*
G01X331898Y-481702D02*
X329498D01*
G01X339398Y-477835D02*
X338598Y-478102D01*
X337998Y-478768D01*
X337598Y-479568D01*
X337298Y-480635D01*
X337198Y-481835D01*
X337298Y-483035D01*
X337598Y-484102D01*
X337998Y-484902D01*
X338598Y-485568D01*
X339398Y-485835D01*
X340198Y-485568D01*
X340798Y-484902D01*
X341198Y-484102D01*
X341498Y-483035D01*
X341598Y-481835D01*
X341498Y-480635D01*
X341198Y-479568D01*
X340798Y-478768D01*
X340198Y-478102D01*
X339398Y-477835D01*
G01X347398D02*
Y-485835D01*
G01X345098Y-477835D02*
X349698D01*
G01X352398Y-488502D02*
X358398D01*
G01X361898Y-482235D02*
X365098D01*
X364798Y-481302D01*
X364298Y-480768D01*
X363598Y-480502D01*
X362898Y-480635D01*
X362298Y-481035D01*
X361898Y-481968D01*
X361698Y-482769D01*
Y-483568D01*
X361898Y-484368D01*
X362398Y-485168D01*
X362998Y-485702D01*
X363698Y-485835D01*
X364398Y-485568D01*
X365098Y-484769D01*
G01X369898Y-480502D02*
X372898Y-485835D01*
G01Y-480502D02*
X369898Y-485835D01*
G01X377598Y-488502D02*
Y-480502D01*
G01Y-481702D02*
X378098Y-481035D01*
X378598Y-480635D01*
X379398Y-480502D01*
X380098Y-480635D01*
X380798Y-481302D01*
X381098Y-482235D01*
X381198Y-483168D01*
X381098Y-484102D01*
X380798Y-485035D01*
X380198Y-485568D01*
X379398Y-485835D01*
X378698Y-485702D01*
X377998Y-485302D01*
X377598Y-484769D01*
G01X389198Y-485835D02*
Y-480502D01*
G01Y-481435D02*
X388798Y-480902D01*
X388198Y-480635D01*
X387498Y-480502D01*
X386798Y-480768D01*
X386198Y-481302D01*
X385798Y-482102D01*
X385598Y-483168D01*
X385798Y-484235D01*
X386198Y-485035D01*
X386798Y-485568D01*
X387498Y-485835D01*
X388198Y-485702D01*
X388798Y-485302D01*
X389198Y-484769D01*
G01X393698Y-485835D02*
Y-480502D01*
G01Y-481835D02*
X394098Y-481168D01*
X394698Y-480635D01*
X395498Y-480502D01*
X396198Y-480635D01*
X396798Y-481168D01*
X397098Y-482102D01*
Y-485835D01*
G01X405198Y-477835D02*
Y-485835D01*
G01Y-484635D02*
X404798Y-485302D01*
X404198Y-485702D01*
X403498Y-485835D01*
X402698Y-485568D01*
X402098Y-484902D01*
X401698Y-484102D01*
X401598Y-483168D01*
X401698Y-482235D01*
X402098Y-481435D01*
X402698Y-480768D01*
X403498Y-480502D01*
X404198Y-480635D01*
X404698Y-480902D01*
X405198Y-481435D01*
G01X409898Y-482235D02*
X413098D01*
X412798Y-481302D01*
X412298Y-480768D01*
X411598Y-480502D01*
X410898Y-480635D01*
X410298Y-481035D01*
X409898Y-481968D01*
X409698Y-482769D01*
Y-483568D01*
X409898Y-484368D01*
X410398Y-485168D01*
X410998Y-485702D01*
X411698Y-485835D01*
X412398Y-485568D01*
X413098Y-484769D01*
G01X417998Y-485835D02*
Y-480502D01*
G01Y-481568D02*
X418498Y-481035D01*
X418998Y-480635D01*
X419698Y-480502D01*
X420198Y-480635D01*
X420798Y-481035D01*
G01X424398Y-488502D02*
X430398D01*
G01X433598Y-485835D02*
Y-477835D01*
G01Y-481835D02*
X434098Y-481035D01*
X434698Y-480635D01*
X435298Y-480502D01*
X436198Y-480768D01*
X436798Y-481302D01*
X437198Y-482235D01*
Y-483302D01*
X436998Y-484368D01*
X436598Y-485168D01*
X435898Y-485702D01*
X435298Y-485835D01*
X434698Y-485702D01*
X434098Y-485302D01*
X433598Y-484635D01*
G01X445198Y-477835D02*
Y-485835D01*
G01Y-484635D02*
X444798Y-485302D01*
X444198Y-485702D01*
X443498Y-485835D01*
X442698Y-485568D01*
X442098Y-484902D01*
X441698Y-484102D01*
X441598Y-483168D01*
X441698Y-482235D01*
X442098Y-481435D01*
X442698Y-480768D01*
X443498Y-480502D01*
X444198Y-480635D01*
X444698Y-480902D01*
X445198Y-481435D01*
G01X400398Y-538835D02*
Y-530835D01*
X399198Y-532435D01*
G01Y-538835D02*
X401598D01*
G01X406498Y-535502D02*
X407198Y-534568D01*
X407798Y-534035D01*
X408598Y-533768D01*
X409298Y-534035D01*
X409798Y-534568D01*
X410198Y-535368D01*
X410298Y-536302D01*
X410198Y-537102D01*
X409798Y-537902D01*
X409198Y-538568D01*
X408498Y-538835D01*
X407698Y-538568D01*
X406998Y-537769D01*
X406598Y-536568D01*
X406498Y-535235D01*
X406698Y-533502D01*
X406998Y-532568D01*
X407498Y-531635D01*
X408198Y-530968D01*
X408898Y-530835D01*
X409598Y-531102D01*
X410098Y-531768D01*
G01X416398Y-539102D02*
X416198Y-538968D01*
Y-538702D01*
X416398Y-538568D01*
X416598Y-538702D01*
Y-538968D01*
X416398Y-539102D01*
G01X422498Y-535502D02*
X423198Y-534568D01*
X423798Y-534035D01*
X424598Y-533768D01*
X425298Y-534035D01*
X425798Y-534568D01*
X426198Y-535368D01*
X426298Y-536302D01*
X426198Y-537102D01*
X425798Y-537902D01*
X425198Y-538568D01*
X424498Y-538835D01*
X423698Y-538568D01*
X422998Y-537769D01*
X422598Y-536568D01*
X422498Y-535235D01*
X422698Y-533502D01*
X422998Y-532568D01*
X423498Y-531635D01*
X424198Y-530968D01*
X424898Y-530835D01*
X425598Y-531102D01*
X426098Y-531768D01*
G01X445398Y-538835D02*
Y-530835D01*
X444198Y-532435D01*
G01Y-538835D02*
X446598D01*
G01X453198D02*
X453398Y-537102D01*
X453698Y-535635D01*
X454098Y-534302D01*
X454598Y-532835D01*
X455398Y-530835D01*
X451398D01*
G01X461398Y-539102D02*
X461198Y-538968D01*
Y-538702D01*
X461398Y-538568D01*
X461598Y-538702D01*
Y-538968D01*
X461398Y-539102D01*
G01X467498Y-532168D02*
X468098Y-531368D01*
X468798Y-530968D01*
X469598Y-530835D01*
X470598Y-531102D01*
X471298Y-531768D01*
X471498Y-532568D01*
X471398Y-533369D01*
X470998Y-534035D01*
X468998Y-535368D01*
X468098Y-536302D01*
X467498Y-537635D01*
X467298Y-538835D01*
X471498D01*
G01X465498Y-513835D02*
Y-505835D01*
X469298D01*
G01X467898Y-509702D02*
X465498D01*
G54D135*
X423674Y430898D03*
X919000Y447239D03*
X1337847Y430898D03*
X1794934D03*
G54D24*
X14781Y189835D03*
X30529D03*
X32086Y586113D03*
X47834D03*
X117143Y189835D03*
X132891D03*
X235253D03*
X219505D03*
X321867D03*
X337615D03*
X381983Y418952D03*
X397731D03*
X471868Y189835D03*
X487616D03*
X489172Y586113D03*
X504920D03*
X574230Y189835D03*
X589978D03*
X676592D03*
X692340D03*
X778954D03*
X794702D03*
X877309Y432293D03*
X893057D03*
X929620Y175006D03*
X945368D03*
X946259Y586113D03*
X962007D03*
X1047064Y189835D03*
X1031316D03*
X1133678D03*
X1149426D03*
X1236040D03*
X1251788D03*
X1296156Y418952D03*
X1311904D03*
X1386041Y189835D03*
X1401789D03*
X1403346Y586113D03*
X1419094D03*
X1488403Y189835D03*
X1504151D03*
X1590765D03*
X1606513D03*
X1693127D03*
X1708875D03*
X1753243Y418952D03*
X1768991D03*
G54D144*
X440114Y339287D03*
Y337713D03*
Y344012D03*
Y332988D03*
Y342437D03*
Y340862D03*
Y336138D03*
Y334563D03*
Y331413D03*
Y329839D03*
Y347161D03*
Y345587D03*
X1342699Y342379D03*
Y340805D03*
Y336080D03*
Y343954D03*
Y339230D03*
Y337655D03*
Y334505D03*
Y332931D03*
Y347104D03*
Y350253D03*
Y348679D03*
Y345529D03*
G54D33*
X15916Y1041679D03*
X28318D03*
X50051Y1041371D03*
X37649D03*
X438119Y1234726D03*
X450521D03*
X476828D03*
X489230D03*
X862606Y1050682D03*
X875008D03*
X896741Y1050374D03*
X884339D03*
X926583Y1050682D03*
X938985D03*
X960718Y1050374D03*
X948316D03*
X1352293Y1234726D03*
X1364695D03*
X1391002D03*
X1403404D03*
X1770563Y1051168D03*
X1782965D03*
X1804698Y1050860D03*
X1792296D03*
G54D126*
X414519Y1251852D03*
Y1264254D03*
X512830Y1251852D03*
Y1264254D03*
X1328693Y1251852D03*
Y1264254D03*
X1427004Y1251852D03*
Y1264254D03*
G54D225*
X1150912Y324148D03*
Y329148D03*
Y334148D03*
Y339148D03*
X1171712Y324148D03*
Y334148D03*
Y339148D03*
Y329148D03*
G54D207*
X942586Y1477022D03*
Y1498282D03*
G54D162*
X687146Y759581D03*
Y762140D03*
Y764699D03*
Y774936D03*
Y777495D03*
Y767258D03*
Y769818D03*
Y772377D03*
X709194Y759581D03*
Y762140D03*
Y764699D03*
Y774936D03*
Y777495D03*
Y767258D03*
Y769818D03*
Y772377D03*
G54D153*
X501821Y359214D03*
Y356655D03*
Y361773D03*
Y366891D03*
Y372010D03*
Y377128D03*
Y364332D03*
Y369450D03*
Y374569D03*
Y379687D03*
Y382246D03*
Y384805D03*
X523869Y356655D03*
Y359214D03*
Y372010D03*
Y366891D03*
Y361773D03*
Y374569D03*
Y369450D03*
Y364332D03*
Y377128D03*
Y384805D03*
Y382246D03*
Y379687D03*
X1404362Y326437D03*
Y331555D03*
Y336673D03*
Y341792D03*
Y328996D03*
Y334114D03*
Y339232D03*
Y344351D03*
Y346910D03*
Y349469D03*
Y352028D03*
Y354587D03*
X1426410Y326437D03*
Y341792D03*
Y336673D03*
Y331555D03*
Y344351D03*
Y339232D03*
Y334114D03*
Y328996D03*
Y354587D03*
Y352028D03*
Y349469D03*
Y346910D03*
X1506457Y326325D03*
Y323766D03*
Y328884D03*
Y334002D03*
Y339121D03*
Y344239D03*
Y331443D03*
Y336561D03*
Y341680D03*
Y346798D03*
Y349357D03*
Y351916D03*
X1528505Y323766D03*
Y326325D03*
Y339121D03*
Y334002D03*
Y328884D03*
Y341680D03*
Y336561D03*
Y331443D03*
Y344239D03*
Y351916D03*
Y349357D03*
Y346798D03*
G54D180*
X857781Y1443730D03*
Y1461448D03*
X871561Y1443730D03*
Y1461448D03*
X899781Y1443730D03*
Y1461448D03*
X913561Y1443730D03*
Y1461448D03*
G54D60*
X39743Y617343D03*
Y621279D03*
X418161Y432227D03*
Y434195D03*
Y436164D03*
Y438133D03*
Y440101D03*
Y442069D03*
Y444038D03*
Y446007D03*
Y447975D03*
X429185Y438133D03*
Y442069D03*
Y434195D03*
Y440101D03*
Y436164D03*
Y446007D03*
Y444038D03*
Y447975D03*
X496829Y617343D03*
Y621279D03*
X913487Y448568D03*
Y450536D03*
Y452505D03*
Y454474D03*
Y456442D03*
Y458410D03*
Y460379D03*
Y462348D03*
Y464316D03*
X924511Y454474D03*
Y450536D03*
Y456442D03*
Y452505D03*
Y458410D03*
Y462348D03*
Y460379D03*
Y464316D03*
X953916Y617343D03*
Y621279D03*
X1332334Y432227D03*
Y434195D03*
Y436164D03*
Y438133D03*
Y440101D03*
Y442069D03*
Y444038D03*
Y446007D03*
Y447975D03*
X1343358Y438133D03*
Y442069D03*
Y434195D03*
Y440101D03*
Y436164D03*
Y446007D03*
Y444038D03*
Y447975D03*
X1411003Y617343D03*
Y621279D03*
X1789421Y432227D03*
Y434195D03*
Y436164D03*
Y438133D03*
Y440101D03*
Y442069D03*
Y444038D03*
Y446007D03*
Y447975D03*
X1800445Y438133D03*
Y442069D03*
Y434195D03*
Y440101D03*
Y436164D03*
Y446007D03*
Y444038D03*
Y447975D03*
G54D15*
X12786Y85412D03*
X10292Y99695D03*
X14292D03*
X15948Y138776D03*
X11999Y138848D03*
X19855Y138871D03*
X12709Y173286D03*
X18826Y235961D03*
X10852Y1541606D03*
X11781Y1532371D03*
X6560Y1550595D03*
X18434Y1551666D03*
X20709Y173286D03*
X36201Y236043D03*
X24091Y236030D03*
X27966Y236018D03*
X29127Y1201683D03*
X27222Y1441611D03*
X48643Y448403D03*
X41643Y470403D03*
X46192Y639295D03*
X42192D03*
X50192D03*
X36692D03*
X40700Y1089630D03*
X58224Y470543D03*
X66224D03*
X53643Y470403D03*
X67684Y602709D03*
X63988Y628151D03*
X54192Y639295D03*
X57553Y1205719D03*
X53056Y1209848D03*
X54339Y1490956D03*
X60013Y1553179D03*
X66291Y1631286D03*
X73381Y91513D03*
X69381D03*
X77711Y176057D03*
X73711D03*
X77938Y187314D03*
X76877Y219666D03*
X80766Y262594D03*
X75819Y287967D03*
X79819D03*
X83819D03*
X83684Y602709D03*
X79684D03*
X71684D03*
X75684D03*
X73968Y665576D03*
X75049Y831202D03*
Y838616D03*
X70941Y1589749D03*
X74291Y1631286D03*
X78291D03*
X82291D03*
X70291D03*
X89845Y278285D03*
X87684Y602709D03*
X91057Y1028286D03*
X86291Y1631286D03*
X107607Y130807D03*
X117607D03*
X106796Y150813D03*
X121661Y130812D03*
X121840Y145921D03*
X120926Y235918D03*
X126453Y236030D03*
X130328Y236018D03*
X127235Y455565D03*
X138563Y236043D03*
X146400Y455284D03*
X175743Y91513D03*
X171743D03*
X179743D03*
X180073Y176057D03*
X176073D03*
X180300Y187314D03*
X179239Y219666D03*
X178181Y287967D03*
X182181D03*
X183752Y91513D03*
X183128Y262594D03*
X192207Y278285D03*
X186181Y287967D03*
X210482Y91788D03*
X214389Y91883D03*
X206533Y91860D03*
X211969Y130807D03*
X209158Y150813D03*
X219969Y130807D03*
X224023Y130812D03*
X224202Y145921D03*
X223288Y235918D03*
X228815Y236030D03*
X217939Y614948D03*
X221809Y614960D03*
X221084Y1482964D03*
X229753Y1537199D03*
X240925Y236043D03*
X232690Y236018D03*
X243278Y623847D03*
X247278D03*
X236498Y1478624D03*
X237753Y1537199D03*
X251278Y623847D03*
X278105Y91513D03*
X274105D03*
X278435Y176057D03*
X282105Y91513D03*
X286114D03*
X282435Y176057D03*
X282662Y187314D03*
X281601Y219666D03*
X285490Y262594D03*
X294569Y278285D03*
X280543Y287967D03*
X284543D03*
X288543D03*
X280500Y858698D03*
Y868798D03*
X286300Y893898D03*
Y904198D03*
X282300Y929398D03*
X282400Y939498D03*
X308895Y91860D03*
X312331Y130807D03*
X311520Y150834D03*
X312263Y314799D03*
X304543Y331926D03*
X316751Y91883D03*
X312844Y91788D03*
X322331Y130807D03*
X326385Y130812D03*
X326564Y145921D03*
X325650Y235918D03*
X331177Y236030D03*
X343287Y236043D03*
X335052Y236018D03*
X342285Y565196D03*
X341748Y1140188D03*
X341455Y1185029D03*
X338322Y1193954D03*
X342152Y1206502D03*
X347591Y396992D03*
X357748Y1140188D03*
X353748D03*
X349748D03*
X345471Y1184959D03*
X350400Y1198478D03*
X354400D03*
X358400D03*
X346387Y1206464D03*
X350402Y1206502D03*
X354402D03*
X358402D03*
X376467Y91513D03*
X377237Y376739D03*
X366486Y382632D03*
X370486D03*
X368587Y406525D03*
X364326Y484942D03*
X361748Y1140188D03*
X366157Y1149996D03*
X366133Y1168276D03*
X366400Y1198478D03*
X362400D03*
X366402Y1206502D03*
X362402D03*
X386112Y33677D03*
X380467Y91513D03*
X388476D03*
X384467D03*
X384797Y176057D03*
X380797D03*
X385024Y187314D03*
X383963Y219666D03*
X387852Y262594D03*
X382905Y287967D03*
X386905D03*
X390905D03*
X379800Y775084D03*
X378472Y793253D03*
X391614Y936135D03*
X408680Y43002D03*
X396680D03*
X396931Y278285D03*
X398237Y376540D03*
X394553Y395886D03*
X401165Y448521D03*
X395390Y875754D03*
X399052Y884257D03*
X402966Y884358D03*
X403159Y1122881D03*
X409461Y1566493D03*
X405461D03*
X415677Y315745D03*
X423551D03*
X419277D03*
X424479Y365141D03*
X416318Y365133D03*
X421459Y628810D03*
X420400Y798598D03*
X412100D03*
X413461Y1566493D03*
X435025Y315745D03*
X431425D03*
X427151D03*
X435574Y442023D03*
X429673Y459085D03*
X433673D03*
X438157Y506093D03*
X431285Y1123880D03*
X435287Y1122881D03*
X444779Y636940D03*
X455619Y1255479D03*
X472332Y130807D03*
X464332D03*
X461521Y150813D03*
X461091Y1027750D03*
X463413Y1123880D03*
X468746Y1122881D03*
X460574Y1255480D03*
X476386Y130812D03*
X476565Y145921D03*
X481178Y236030D03*
X475651Y235918D03*
X485053Y236018D03*
X488485Y415401D03*
X481485Y437401D03*
X488745Y680401D03*
X488091Y995250D03*
X493288Y236043D03*
X493485Y437401D03*
X503729Y445403D03*
X496729Y467403D03*
X503278Y639295D03*
X499278D03*
X507278D03*
X493778D03*
X491373Y657681D03*
X493914Y680419D03*
X505464Y673137D03*
X492091Y995250D03*
X500874Y1122881D03*
X496872Y1123880D03*
X521310Y467543D03*
X513310D03*
X508729Y467403D03*
X521074Y628151D03*
X511278Y639295D03*
X517464Y673137D03*
X513464D03*
X509464D03*
X517412Y761891D03*
X514576Y789287D03*
X519763Y789214D03*
X538477Y91513D03*
X530468D03*
X534468D03*
X526468D03*
X534798Y176057D03*
X530798D03*
X535025Y187314D03*
X533964Y219666D03*
X537853Y262594D03*
X532906Y287967D03*
X536906D03*
X528770Y602709D03*
X532770D03*
X536770D03*
X524770D03*
X537964Y673137D03*
X533964D03*
X529964D03*
X525964D03*
X529000Y1123880D03*
X546932Y278285D03*
X540906Y287967D03*
X544770Y602709D03*
X540770D03*
X542400Y847798D03*
X548144Y1028286D03*
X569114Y91883D03*
X565207Y91788D03*
X561258Y91860D03*
X564694Y130807D03*
X563883Y150813D03*
X567958Y1535299D03*
X574694Y130807D03*
X578748Y130812D03*
X578927Y145921D03*
X578013Y235918D03*
X583540Y236030D03*
X587415Y236018D03*
X584321Y455565D03*
X574504Y753368D03*
X587858Y1523799D03*
X579758Y1523699D03*
X575809Y1538485D03*
X583809D03*
X595650Y236043D03*
X603486Y455284D03*
X592103Y945291D03*
Y952705D03*
X591858Y1529899D03*
X595809Y1538485D03*
X632830Y91513D03*
X636830D03*
X628830D03*
X637160Y176057D03*
X633160D03*
X637387Y187314D03*
X636326Y219666D03*
X635268Y287967D03*
X640839Y91513D03*
X640215Y262594D03*
X649294Y278285D03*
X639268Y287967D03*
X643268D03*
X663620Y91860D03*
X667569Y91788D03*
X669056Y130807D03*
X666245Y150813D03*
X658064Y656220D03*
X662064D03*
X671476Y91883D03*
X677056Y130807D03*
X681110Y130812D03*
X681289Y145921D03*
X680375Y235918D03*
X685902Y236030D03*
X698012Y236043D03*
X689777Y236018D03*
X700364Y623847D03*
X693163Y700132D03*
X704364Y623847D03*
X708364D03*
X731192Y91513D03*
X720260Y699606D03*
X732170Y1625074D03*
X743201Y91513D03*
X739192D03*
X735192D03*
X739522Y176057D03*
X735522D03*
X739749Y187314D03*
X738688Y219666D03*
X742577Y262594D03*
X737630Y287967D03*
X741630D03*
X745630D03*
X751140Y1586794D03*
X735392Y1602249D03*
X744924Y1614852D03*
X743331Y1633703D03*
X765982Y91860D03*
X751656Y278285D03*
X761629Y331926D03*
X755187Y1586808D03*
X759452Y1616826D03*
X773838Y91883D03*
X769931Y91788D03*
X769418Y130807D03*
X779418D03*
X783472Y130812D03*
X783651Y145921D03*
X768607Y150813D03*
X782737Y235918D03*
X769349Y314799D03*
X774844Y1622454D03*
X778358Y1633185D03*
X788264Y236030D03*
X792139Y236018D03*
X799371Y565196D03*
X798835Y1140188D03*
X798542Y1185029D03*
X795159Y1191675D03*
X795418Y1206402D03*
X796972Y1397662D03*
X800374Y236043D03*
X813821Y738355D03*
X816027Y870739D03*
X806835Y1140188D03*
X814835D03*
X810835D03*
X802558Y1184959D03*
X815487Y1198478D03*
X811487D03*
X807487D03*
X802333Y1197995D03*
X815489Y1206502D03*
X811489D03*
X807489D03*
X803604Y1206459D03*
X806148Y1380667D03*
X810148D03*
X805009Y1472569D03*
X821412Y479942D03*
X830484Y744210D03*
X826484D03*
X822831Y839725D03*
X818831D03*
X820027Y870739D03*
X819629Y895614D03*
X828909Y911527D03*
X830913Y929661D03*
X818835Y1140188D03*
X823244Y1149996D03*
X823220Y1168276D03*
X819487Y1198478D03*
X823487D03*
X823489Y1206502D03*
X819489D03*
X833554Y91513D03*
X837554D03*
X845563D03*
X841554D03*
X841884Y176057D03*
X837884D03*
X842111Y187314D03*
X841050Y219666D03*
X844939Y262594D03*
X839992Y287967D03*
X843992D03*
X847992D03*
X846098Y414721D03*
X834484Y744210D03*
X846484D03*
X838484D03*
X842484D03*
X833112Y829697D03*
X832726Y843538D03*
X836311Y877072D03*
X844946Y911527D03*
X840909D03*
X836909D03*
X832909D03*
X838829Y929661D03*
X834829D03*
X845395D03*
X836423Y962178D03*
X832423D03*
X854018Y278285D03*
X863086Y379984D03*
X849680Y692098D03*
X854484Y744210D03*
X850484D03*
X852628Y912573D03*
X860628D03*
X849544Y1454243D03*
X872293Y91788D03*
X876200Y91883D03*
X868344Y91860D03*
X878500Y200409D03*
X879740Y260193D03*
X868086Y379984D03*
X876736Y388764D03*
X867586Y390484D03*
X869342Y414526D03*
X875916Y806374D03*
X879916Y816524D03*
X876628Y912573D03*
X868628D03*
X872817Y1210686D03*
X889879Y412227D03*
X896491Y464862D03*
X896431Y539552D03*
X891933Y615652D03*
X884045Y750219D03*
X887916Y806374D03*
X883916D03*
X891916D03*
X883916Y816524D03*
X887916D03*
X884628Y912573D03*
X887390Y1098633D03*
X896746Y1218851D03*
X891844Y1455143D03*
X897736Y388764D03*
X903431Y539552D03*
X911416Y806374D03*
X910900Y912484D03*
X906128Y959074D03*
X901243Y1214722D03*
X908852Y1227992D03*
X912726D03*
X929418Y130807D03*
X921418D03*
X918607Y150813D03*
X927072Y384391D03*
X923072D03*
X919072D03*
X924999Y475426D03*
X928999D03*
X917250Y554604D03*
X927916Y806374D03*
X923790D03*
X919664D03*
X915716D03*
X914500Y912484D03*
X918100D03*
X924628Y912573D03*
X928628D03*
X925697Y1457310D03*
X921868Y1457340D03*
X933472Y130812D03*
X933651Y145921D03*
X938930Y221201D03*
X942805Y221189D03*
X938657Y367695D03*
X930900Y458364D03*
X931916Y814524D03*
X943916D03*
X943735Y847641D03*
X945035Y833241D03*
X936616Y898088D03*
X936628Y912573D03*
X944628D03*
X940628D03*
X932628D03*
X932716Y898088D03*
X936794Y1210686D03*
X951040Y221214D03*
X955816Y470403D03*
X960365Y639295D03*
X956365D03*
X950865D03*
X947556Y705109D03*
X955950Y731522D03*
X950335Y826341D03*
X948935Y833241D03*
X958682Y834412D03*
X958200Y841584D03*
X950100Y853484D03*
X954000D03*
X954124Y883054D03*
X954567Y933303D03*
X957671Y988727D03*
X951367Y1098633D03*
X960723Y1218851D03*
X962816Y448403D03*
X972397Y470463D03*
X967816Y470403D03*
X978161Y628151D03*
X968365Y639295D03*
X964365D03*
X973712Y719573D03*
X965220Y1214722D03*
X983554Y91513D03*
X987554D03*
X991554D03*
X991884Y176057D03*
X987884D03*
X992111Y187314D03*
X991050Y219666D03*
X989992Y287967D03*
X993992D03*
X990405Y321234D03*
X984045Y364068D03*
X980045D03*
X980397Y470543D03*
X981857Y602709D03*
X989857D03*
X993857D03*
X985857D03*
X991990Y771458D03*
X987990D03*
X990051Y816827D03*
X995563Y91513D03*
X994939Y262594D03*
X1004018Y278285D03*
X997992Y287967D03*
X1004635Y305735D03*
X1008635D03*
X997857Y602709D03*
X1001857D03*
X1003990Y771458D03*
X999990D03*
X1005230Y1028286D03*
X1018344Y91860D03*
X1022293Y91788D03*
X1026200Y91883D03*
X1021780Y130807D03*
X1020969Y150813D03*
X1021259Y1316506D03*
X1024115Y1333873D03*
X1031780Y130807D03*
X1035834Y130812D03*
X1036013Y145921D03*
X1035099Y235918D03*
X1040626Y236030D03*
X1033786Y305735D03*
X1037386D03*
X1041496D03*
X1041408Y455565D03*
X1033719Y942306D03*
Y949720D03*
X1052736Y236043D03*
X1044501Y236018D03*
X1060573Y455284D03*
X1066260Y1445450D03*
X1085916Y91513D03*
X1089916D03*
X1090246Y176057D03*
X1090469Y1585469D03*
X1086904Y1596265D03*
X1083735Y1606682D03*
Y1614618D03*
X1085474Y1634909D03*
X1093916Y91513D03*
X1097925D03*
X1094246Y176057D03*
X1094473Y187314D03*
X1093412Y219666D03*
X1097301Y262594D03*
X1106380Y278285D03*
X1092354Y287967D03*
X1096354D03*
X1100354D03*
X1098376Y1557242D03*
X1093376D03*
X1100233Y1585492D03*
X1104612Y1606661D03*
X1098904Y1596265D03*
X1094904D03*
X1097474Y1634909D03*
X1124655Y91788D03*
X1120706Y91860D03*
X1123331Y150813D03*
X1115151Y656220D03*
X1119151D03*
X1128562Y91883D03*
X1134142Y130807D03*
X1126142D03*
X1138196Y130812D03*
X1138375Y145921D03*
X1137461Y235918D03*
X1142988Y236030D03*
X1155098Y236043D03*
X1146863Y236018D03*
X1152485Y770626D03*
X1157451Y623847D03*
X1161451D03*
X1165451D03*
X1168485Y770494D03*
X1160485Y770626D03*
X1164485D03*
X1188278Y91513D03*
X1180715Y781952D03*
X1196278Y91513D03*
X1200287D03*
X1192278D03*
X1196608Y176057D03*
X1192608D03*
X1196835Y187314D03*
X1195774Y219666D03*
X1199663Y262594D03*
X1194716Y287967D03*
X1198716D03*
X1202716D03*
X1208742Y278285D03*
X1218716Y331926D03*
X1227017Y91788D03*
X1230924Y91883D03*
X1223068Y91860D03*
X1236504Y130807D03*
X1226504D03*
X1225693Y150813D03*
X1226436Y314799D03*
X1240558Y130812D03*
X1240737Y145921D03*
X1239823Y235918D03*
X1245350Y236030D03*
X1249225Y236018D03*
X1251302Y1201909D03*
X1257460Y236043D03*
X1261764Y396992D03*
X1256458Y565196D03*
X1263921Y1140188D03*
X1267921D03*
X1255921D03*
X1255628Y1185029D03*
X1259644Y1184959D03*
X1264573Y1198478D03*
X1268573D03*
X1260771Y1196804D03*
X1264575Y1206502D03*
X1268575D03*
X1260535Y1206507D03*
X1280659Y382632D03*
X1284659D03*
X1282760Y406525D03*
X1278499Y484942D03*
X1284655Y897984D03*
X1275493Y926977D03*
X1279493D03*
X1283493D03*
X1271493D03*
X1275921Y1140188D03*
X1271921D03*
X1280330Y1149996D03*
X1280306Y1168276D03*
X1280573Y1198478D03*
X1276573D03*
X1272573D03*
X1276575Y1206502D03*
X1280575D03*
X1272575D03*
X1300285Y33677D03*
X1298640Y91513D03*
X1294640D03*
X1302649D03*
X1290640D03*
X1298970Y176057D03*
X1294970D03*
X1299197Y187314D03*
X1298136Y219666D03*
X1302025Y262594D03*
X1297078Y287967D03*
X1301078D03*
X1291500Y324484D03*
X1291410Y376739D03*
X1292000Y897984D03*
X1289500Y946984D03*
X1296500Y966984D03*
X1310853Y43002D03*
X1311104Y278285D03*
X1305078Y287967D03*
X1318262Y318837D03*
X1312410Y376540D03*
X1308726Y395886D03*
X1315338Y448521D03*
X1318500Y922984D03*
X1314500D03*
X1317000Y933984D03*
X1318500Y964984D03*
X1311000Y966984D03*
X1315000D03*
X1317333Y1122881D03*
X1322853Y43002D03*
X1329736Y318837D03*
X1334010D03*
X1321862D03*
X1326136D03*
X1320903Y368225D03*
X1329064Y368233D03*
X1327584Y782089D03*
X1330500Y922984D03*
X1334500D03*
X1326500Y933984D03*
X1337610Y318837D03*
X1349747Y442023D03*
X1343846Y459085D03*
X1347846D03*
X1345000Y793484D03*
X1348917D03*
X1342500Y922984D03*
X1338500D03*
X1336000Y933984D03*
X1345948Y949087D03*
X1349948D03*
X1345459Y1123880D03*
X1349461Y1122881D03*
X1352817Y793484D03*
X1365000Y809484D03*
X1361000D03*
X1357000D03*
X1365948Y949087D03*
X1357948D03*
X1353948D03*
X1378505Y130807D03*
X1375694Y150813D03*
X1380500Y593484D03*
Y639984D03*
Y684484D03*
Y731484D03*
X1373000Y809484D03*
X1381000D03*
X1369000D03*
X1377017Y809482D03*
X1382560Y937305D03*
X1378503Y937304D03*
X1369948Y949087D03*
X1375265Y1027750D03*
X1377587Y1123880D03*
X1382920Y1122881D03*
X1386505Y130807D03*
X1390559Y130812D03*
X1390738Y145921D03*
X1389824Y235918D03*
X1395351Y236030D03*
X1399226Y236018D03*
X1394537Y809163D03*
X1398517Y809201D03*
X1407461Y236043D03*
X1410903Y467403D03*
X1413452Y639295D03*
X1407952D03*
X1402517Y809201D03*
X1406483D03*
X1402265Y995250D03*
X1406265D03*
X1411046Y1123880D03*
X1415048Y1122881D03*
X1407747Y1546444D03*
X1407255Y1569122D03*
X1417903Y445403D03*
X1427484Y467543D03*
X1422903Y467403D03*
X1425452Y639295D03*
X1417452D03*
X1421452D03*
X1432258Y1410799D03*
X1444641Y91513D03*
X1440641D03*
X1448641D03*
X1448971Y176057D03*
X1444971D03*
X1449198Y187314D03*
X1448137Y219666D03*
X1447079Y287967D03*
X1435484Y467543D03*
X1442944Y602709D03*
X1438944D03*
X1446944D03*
X1435248Y628151D03*
X1437980Y1031431D03*
X1443174Y1123880D03*
X1436258Y1410799D03*
X1437293Y1543474D03*
X1436801Y1566152D03*
X1452650Y91513D03*
X1452026Y262594D03*
X1461105Y278285D03*
X1451079Y287967D03*
X1455079D03*
X1454944Y602709D03*
X1458944D03*
X1450944D03*
X1462317Y1028286D03*
X1479380Y91788D03*
X1475431Y91860D03*
X1478867Y130807D03*
X1478056Y150813D03*
X1471500Y715984D03*
Y759984D03*
X1483287Y91883D03*
X1488867Y130807D03*
X1492921Y130812D03*
X1493100Y145921D03*
X1492186Y235918D03*
X1497713Y236030D03*
X1488500Y801484D03*
Y845484D03*
X1509823Y236043D03*
X1501588Y236018D03*
X1498495Y455565D03*
X1517660Y455284D03*
X1547003Y91513D03*
X1543003D03*
X1555012D03*
X1551003D03*
X1551333Y176057D03*
X1547333D03*
X1551560Y187314D03*
X1550499Y219666D03*
X1554388Y262594D03*
X1549441Y287967D03*
X1553441D03*
X1557441D03*
X1577793Y91860D03*
X1563467Y278285D03*
X1572238Y656220D03*
X1576238D03*
X1585649Y91883D03*
X1581742Y91788D03*
X1591229Y130807D03*
X1583229D03*
X1595283Y130812D03*
X1595462Y145921D03*
X1580418Y150813D03*
X1594548Y235918D03*
X1587746Y1460616D03*
X1594264Y1472999D03*
X1600075Y236030D03*
X1603950Y236018D03*
X1601500Y1511984D03*
X1598000D03*
X1608500D03*
X1610858Y1523299D03*
X1612185Y236043D03*
X1614538Y623847D03*
X1618538D03*
X1622538D03*
X1653365Y91513D03*
X1657374D03*
X1645365D03*
X1649365D03*
X1653695Y176057D03*
X1649695D03*
X1653922Y187314D03*
X1652861Y219666D03*
X1656750Y262594D03*
X1651803Y287967D03*
X1655803D03*
X1659803D03*
X1665829Y278285D03*
X1675803Y331926D03*
X1680155Y91860D03*
X1684104Y91788D03*
X1688011Y91883D03*
X1683591Y130807D03*
X1682780Y150813D03*
X1683523Y314799D03*
X1693591Y130807D03*
X1697645Y130812D03*
X1697824Y145921D03*
X1702437Y236030D03*
X1696910Y235918D03*
X1706312Y236018D03*
X1714547Y236043D03*
X1718851Y396992D03*
X1713545Y565196D03*
X1721008Y1140188D03*
X1725008D03*
X1713008D03*
X1712715Y1185029D03*
X1716731Y1184959D03*
X1721660Y1198478D03*
X1725660D03*
X1709820Y1199574D03*
X1721662Y1206502D03*
X1725662D03*
X1717568Y1206302D03*
X1741746Y382632D03*
X1737746D03*
X1739847Y406525D03*
X1735586Y484942D03*
X1733008Y1140188D03*
X1729008D03*
X1737417Y1149996D03*
X1737393Y1168276D03*
X1737660Y1198478D03*
X1729660D03*
X1733660D03*
X1729662Y1206502D03*
X1733662D03*
X1737662D03*
X1751727Y91513D03*
X1755727D03*
X1747727D03*
X1756057Y176057D03*
X1752057D03*
X1756284Y187314D03*
X1755223Y219666D03*
X1754165Y287967D03*
X1758165D03*
X1748497Y376739D03*
X1750900Y907884D03*
X1756422Y1637788D03*
X1759736Y91513D03*
X1759112Y262594D03*
X1768191Y278285D03*
X1762165Y287967D03*
X1769497Y376540D03*
X1765813Y395886D03*
X1772425Y448521D03*
X1761072Y1596251D03*
X1765072D03*
X1772422Y1637788D03*
X1768422D03*
X1760422D03*
X1764422D03*
X1782517Y91860D03*
X1786466Y91788D03*
X1790373Y91883D03*
X1776071Y836378D03*
X1789537Y927561D03*
X1780774Y1211172D03*
X1778227Y1443592D03*
X1778104Y1475782D03*
X1776422Y1637788D03*
X1806834Y442023D03*
X1800933Y459085D03*
X1804933D03*
X1797374Y927433D03*
X1795347Y1099119D03*
X1804703Y1219337D03*
X1800046Y1440630D03*
X1799923Y1472820D03*
X1809700Y910084D03*
X1808363Y973144D03*
Y980558D03*
X1809200Y1215208D03*
G54D42*
X27130Y219149D03*
X129492D03*
X231854D03*
X334216D03*
X384382Y389638D03*
X484217Y219149D03*
X586579D03*
X688941D03*
X791303D03*
X879708Y402979D03*
X941969Y204320D03*
X1043665Y219149D03*
X1146027D03*
X1248389D03*
X1298555Y389638D03*
X1398390Y219149D03*
X1500752D03*
X1603114D03*
X1705476D03*
X1755642Y389638D03*
G54D108*
X360727Y458603D03*
X466821Y473078D03*
X817813Y452603D03*
X1274900Y458603D03*
X1731987D03*
G54D171*
X797907Y1443778D03*
Y1461396D03*
X815624Y1443778D03*
X813852D03*
X812080D03*
X810309D03*
X808537D03*
X806765D03*
X801450D03*
X803222D03*
X804994D03*
X799679D03*
X804994Y1461396D03*
X806765D03*
X808537D03*
X810309D03*
X812080D03*
X813852D03*
X815624D03*
X799679D03*
X801450D03*
X803222D03*
X819167Y1443778D03*
X817395D03*
Y1461396D03*
X819167D03*
G54D51*
X51043Y60709D03*
Y150197D03*
X153405Y60709D03*
Y150197D03*
X190325Y455492D03*
Y503760D03*
Y583957D03*
Y636752D03*
X255767Y60709D03*
Y150197D03*
X279360Y368760D03*
Y421555D03*
Y501752D03*
Y550020D03*
X358129Y60709D03*
Y150197D03*
X508130Y60709D03*
Y150197D03*
X610492Y60709D03*
Y150197D03*
X647411Y455492D03*
Y503760D03*
Y583957D03*
Y636752D03*
X712854Y60709D03*
Y150197D03*
X736446Y368760D03*
Y421555D03*
Y501752D03*
Y550020D03*
X815216Y60709D03*
Y150197D03*
X965216Y60709D03*
Y150197D03*
X1067578Y60709D03*
Y150197D03*
X1104498Y455492D03*
Y503760D03*
Y583957D03*
Y636752D03*
X1169940Y60709D03*
Y150197D03*
X1193533Y368760D03*
Y421555D03*
Y501752D03*
Y550020D03*
X1272302Y60709D03*
Y150197D03*
X1422303Y60709D03*
Y150197D03*
X1524665Y60709D03*
Y150197D03*
X1561585Y455492D03*
Y503760D03*
Y583957D03*
Y636752D03*
X1627027Y60709D03*
Y150197D03*
X1650620Y368760D03*
Y421555D03*
Y501752D03*
Y550020D03*
X1729389Y60709D03*
Y150197D03*
G54D117*
X409284Y745280D03*
X407316D03*
X405347D03*
X403379D03*
X401410D03*
X399442D03*
X397473D03*
X395505D03*
X393536D03*
X423064D03*
X421095D03*
X419127D03*
X417158D03*
X415190D03*
X413221D03*
X411253D03*
X1772142Y877880D03*
X1770173D03*
X1768205D03*
X1766236D03*
X1789858D03*
X1787890D03*
X1785921D03*
X1783953D03*
X1781984D03*
X1780016D03*
X1778047D03*
X1776079D03*
X1774110D03*
X1795764D03*
X1793795D03*
X1791827D03*
G54D216*
X1022350Y331915D03*
G54D145*
X429086Y432227D03*
X924412Y448568D03*
X1343259Y432227D03*
X1800346D03*
G54D118*
X408300Y762800D03*
X1781000Y895400D03*
G54D16*
X8786Y85411D03*
X6298Y99649D03*
X18298D03*
X6499Y138847D03*
X8264Y159013D03*
X15184Y150286D03*
X19184D03*
X16709Y173285D03*
X17822Y212889D03*
X6811Y1005604D03*
X10701D03*
X14645D03*
X11768Y1525256D03*
X14375Y1550556D03*
X10367Y1550563D03*
X31971Y106469D03*
X23184Y150286D03*
X32201Y236042D03*
X26192Y616794D03*
X30192D03*
X33992D03*
X27556Y1005604D03*
X33659D03*
X21506D03*
X25674Y1491774D03*
X35850Y1553213D03*
X26231Y1551642D03*
X22381Y1551660D03*
X45643Y470402D03*
X49643D03*
X39549Y1005604D03*
X45858D03*
X51946D03*
X40951Y1553213D03*
X47074Y1553204D03*
X52048Y1553179D03*
X65759Y442977D03*
X54936Y454821D03*
X61759Y442977D03*
X57759D03*
X62224Y470542D03*
X66345Y490147D03*
X56514Y536891D03*
X64408Y578815D03*
X63684Y602708D03*
X61192Y639294D03*
X57692D03*
X64692D03*
X56149Y824291D03*
X65774Y1005604D03*
X61779D03*
X57834D03*
X57702Y1198728D03*
X61380Y1205454D03*
X53737Y1199888D03*
X54351Y1483866D03*
X56114Y1553178D03*
X64747Y1553171D03*
X63090Y1615060D03*
X80660Y101256D03*
X76660D03*
X70577Y101609D03*
X84808Y103511D03*
X76766Y262593D03*
X84766D03*
X78106Y662474D03*
X74910Y687495D03*
X84699Y1004449D03*
X87652Y578620D03*
X93456Y655308D03*
X95836Y986014D03*
X99836D03*
Y995014D03*
X95836D03*
X97609Y1013880D03*
X104662Y116534D03*
X115582Y107807D03*
X111582D03*
X113607Y130806D03*
X106796Y157923D03*
X111836Y986014D03*
X103836D03*
X115836D03*
X107836D03*
X111836Y995014D03*
X103836D03*
X115836D03*
X107836D03*
X109601Y1226509D03*
X105601D03*
X119582Y107807D03*
X128251Y146820D03*
X120184Y212889D03*
X127235Y448564D03*
X119836Y986014D03*
X123836D03*
X127836D03*
X131836D03*
X119836Y995014D03*
X123836D03*
X127836D03*
X131836D03*
X127604Y1105591D03*
Y1118191D03*
Y1130791D03*
Y1143391D03*
Y1155991D03*
Y1168591D03*
Y1181191D03*
X134333Y106469D03*
X134563Y236042D03*
X138971Y541874D03*
X142961Y541833D03*
X143836Y986014D03*
X147836D03*
X139836D03*
X135836D03*
X143836Y995014D03*
X147836D03*
X139836D03*
X135836D03*
X139250Y1012854D03*
Y1025454D03*
X159836Y986014D03*
X151836D03*
X159836Y995014D03*
X155836D03*
X151836D03*
X179022Y101256D03*
X172939Y101609D03*
X179128Y262593D03*
X183022Y101256D03*
X188526Y100533D03*
Y108145D03*
X187128Y262593D03*
X201033Y91859D03*
X207024Y116534D03*
X213944Y107807D03*
X209158Y157923D03*
X221944Y107807D03*
X217944D03*
X215969Y130806D03*
X230613Y146820D03*
X222546Y212889D03*
X221942Y1537368D03*
X225753Y1537198D03*
X229942Y1549368D03*
X236695Y106469D03*
X236925Y236042D03*
X242102Y653729D03*
X246102D03*
X240842Y1530368D03*
X233753Y1537198D03*
X237942Y1549368D03*
X244942D03*
X233942D03*
X250102Y653729D03*
X248042Y1530368D03*
X275301Y101609D03*
X281384Y101256D03*
X290888Y100533D03*
X285384Y101256D03*
X290888Y108145D03*
X289490Y262593D03*
X281490D03*
X303395Y91859D03*
X309386Y116534D03*
X311520Y157923D03*
X312263Y321798D03*
X324306Y107807D03*
X320306D03*
X316306D03*
X318222Y130697D03*
X324908Y212889D03*
X317416Y345377D03*
X321416D03*
X323285Y553195D03*
X339057Y106469D03*
X332975Y146820D03*
X339287Y236042D03*
X342486Y382631D03*
X342285Y558195D03*
X336755Y1140187D03*
X337629Y1178808D03*
X342298Y1193899D03*
X346486Y382631D03*
X358486D03*
X350486D03*
X354486D03*
X353202Y411985D03*
X345748Y1140187D03*
X350414Y1178148D03*
X358443Y1177169D03*
X354414Y1178148D03*
X359761Y1185109D03*
X354442Y1185113D03*
X350442D03*
X346136Y1194034D03*
X370931Y367347D03*
X362486Y382631D03*
X374714Y793252D03*
X365748Y1140187D03*
X362282Y1177832D03*
X363729Y1185146D03*
X393250Y100533D03*
X387746Y101256D03*
X383746D03*
X377663Y101609D03*
X393250Y108145D03*
X383852Y262593D03*
X391852D03*
X389237Y376537D03*
X381237D03*
X385237D03*
X404686Y42956D03*
X400686D03*
X394237Y376539D03*
X403478Y875751D03*
X399369D03*
X399816Y956130D03*
X400043Y967387D03*
X404043D03*
X403263Y1158242D03*
X397461Y1566492D03*
X401461D03*
X420422Y365140D03*
X412318Y365132D03*
X411847Y432320D03*
X425673Y459084D03*
X426000Y789283D03*
X416200Y798583D03*
X417682Y1057696D03*
X410668Y1105613D03*
X414455D03*
X422532Y1101825D03*
X421461Y1566492D03*
X417461D03*
X431424Y365001D03*
X435024D03*
X427566Y883916D03*
X427913Y1101825D03*
X431285Y1113379D03*
X449745Y628543D03*
X445745D03*
X442796Y1105613D03*
X446583D03*
X454660Y1101825D03*
X456025Y1220971D03*
X459387Y116534D03*
X474307Y107807D03*
X470307D03*
X466307D03*
X468332Y130806D03*
X461521Y157923D03*
X474909Y212889D03*
X468836Y543080D03*
X460041Y1101825D03*
X463413Y1113379D03*
X468850Y1158242D03*
X462687D03*
X461319Y1220971D03*
X489058Y106469D03*
X482976Y146820D03*
X489288Y236042D03*
X485485Y437400D03*
X489485D03*
X491078Y616794D03*
X483278D03*
X487278D03*
X476255Y1105613D03*
X480042D03*
X488119Y1101825D03*
X500729Y467402D03*
X504729D03*
X501082Y992664D03*
X505958Y1057989D03*
X493500Y1101825D03*
X496872Y1113379D03*
X520845Y439977D03*
X516845D03*
X512845D03*
X510022Y451821D03*
X517310Y467542D03*
X523431Y490147D03*
X513600Y536891D03*
X521494Y578815D03*
X520770Y602708D03*
X516770D03*
X518278Y639294D03*
X514778D03*
X521778D03*
X519285Y728479D03*
X515285D03*
X511285D03*
X523285D03*
X509096Y758773D03*
X513504Y761890D03*
X508383Y1105613D03*
X512170D03*
X520247Y1101825D03*
X537747Y101256D03*
X533747D03*
X527664Y101609D03*
X533853Y262593D03*
X539285Y728479D03*
X535285D03*
X531285D03*
X527285D03*
X524319Y761864D03*
X536715Y1009304D03*
X529000Y1113379D03*
X528274Y1158242D03*
X555758Y91859D03*
X543251Y100533D03*
Y108145D03*
X541853Y262593D03*
X544738Y578620D03*
X552923Y986014D03*
Y995014D03*
X554696Y1013880D03*
X561749Y116534D03*
X568669Y107807D03*
X570694Y130806D03*
X563883Y157923D03*
X568464Y757957D03*
X560256Y779157D03*
X556923Y986014D03*
X568923D03*
X560923D03*
X564923D03*
X556923Y995014D03*
X568923D03*
X560923D03*
X564923D03*
X562688Y1226509D03*
X566688D03*
X564242Y1528168D03*
X571809Y1538484D03*
X562786Y1537592D03*
X558786D03*
X571942Y1547268D03*
X576669Y107807D03*
X572669D03*
X585338Y146820D03*
X577271Y212889D03*
X584321Y448564D03*
X573203Y938380D03*
X576923Y986014D03*
X580923D03*
X584923D03*
X572923D03*
X576923Y995014D03*
X580923D03*
X584923D03*
X572923D03*
X584691Y1105591D03*
Y1118191D03*
Y1130791D03*
Y1143391D03*
Y1155991D03*
Y1168591D03*
Y1181191D03*
X587809Y1538484D03*
X579809D03*
X583742Y1547768D03*
X591420Y106469D03*
X591650Y236042D03*
X600047Y541833D03*
X596057Y541874D03*
X600923Y986014D03*
X604923D03*
X592923D03*
X596923D03*
X588923D03*
X600923Y995014D03*
X604923D03*
X592923D03*
X596923D03*
X588923D03*
X596337Y1012854D03*
Y1025454D03*
X600242Y1541568D03*
X591809Y1538484D03*
X608923Y986014D03*
X616923D03*
X608923Y995014D03*
X616923D03*
X612923D03*
X636109Y101256D03*
X630026Y101609D03*
X636215Y262593D03*
X645613Y100533D03*
X640109Y101256D03*
X645613Y108145D03*
X644215Y262593D03*
X658120Y91859D03*
X664111Y116534D03*
X666245Y157923D03*
X679031Y107807D03*
X671031D03*
X675031D03*
X673056Y130806D03*
X679633Y212889D03*
X693782Y106469D03*
X687700Y146820D03*
X694012Y236042D03*
X699188Y653729D03*
X688728Y703417D03*
X703188Y653729D03*
X707188D03*
X713382Y705220D03*
X732388Y101609D03*
X723811Y742039D03*
X742471Y101256D03*
X747975Y100533D03*
X738471Y101256D03*
X747975Y108145D03*
X738577Y262593D03*
X746577D03*
X747140Y1586793D03*
X748924Y1614851D03*
X748997Y1624393D03*
X747590Y1633692D03*
X760482Y91859D03*
X766473Y116534D03*
X763145Y1586771D03*
X759169Y1586818D03*
X763452Y1616825D03*
X752150Y1633717D03*
X781393Y107807D03*
X773393D03*
X777393D03*
X775418Y130806D03*
X768607Y157923D03*
X781995Y212889D03*
X769349Y321798D03*
X774502Y345377D03*
X778502D03*
X780371Y553195D03*
X783215Y1452633D03*
X767512Y1449685D03*
X777033Y1592480D03*
X781110D03*
X767452Y1616825D03*
X773822Y1633208D03*
X796144Y106469D03*
X790062Y146820D03*
X796374Y236042D03*
X799371Y558195D03*
X793842Y1140187D03*
X794716Y1178808D03*
X798324Y1198092D03*
X799230Y1206514D03*
X799901Y1472584D03*
X791610Y1599496D03*
X787447Y1599519D03*
X802835Y1140187D03*
X811529Y1185113D03*
X811501Y1178148D03*
X807501D03*
X807529Y1185113D03*
X814148Y1380666D03*
X832284Y716497D03*
X827284Y709547D03*
Y716497D03*
X828880Y870347D03*
X828643Y896072D03*
X826987Y929688D03*
X831409Y922276D03*
X827409D03*
X828423Y962177D03*
X822835Y1140187D03*
X816848Y1185109D03*
X820826Y1178196D03*
X820816Y1185146D03*
X816826Y1178196D03*
X840833Y101256D03*
X844833D03*
X834750Y101609D03*
X840939Y262593D03*
X848284Y716497D03*
X839290Y709527D03*
X843284Y709547D03*
X839290Y716477D03*
X843284Y716497D03*
X833112Y836573D03*
X836405Y863475D03*
X832880Y870347D03*
X832643Y896072D03*
X842000Y901483D03*
X848628Y912572D03*
X846000Y901483D03*
X841064Y922076D03*
X837235D03*
X840423Y962177D03*
X862844Y91859D03*
X850337Y100533D03*
Y108145D03*
X848939Y262593D03*
X858586Y379983D03*
X854086D03*
X858586Y390483D03*
X854086D03*
X863086D03*
X852284Y709547D03*
Y716497D03*
X856628Y912572D03*
X864628D03*
X849205Y929692D03*
X852488Y1017136D03*
X857884D03*
X864007D03*
X874531Y200408D03*
X880736Y388763D03*
X875916Y816523D03*
X872628Y912572D03*
X880628D03*
X879740Y944184D03*
X870401Y1017136D03*
X875954D03*
X893736Y388763D03*
X888736D03*
X884736D03*
X892931Y539551D03*
X885931D03*
X889431D03*
X895933Y615651D03*
X892728Y792759D03*
X895916Y816523D03*
X888628Y912572D03*
X892628D03*
X896628D03*
X881454Y1017136D03*
X885210D03*
X889089D03*
X893613Y1017279D03*
X904614Y343347D03*
X908114D03*
X911072Y384390D03*
X907173Y448661D03*
X899931Y539551D03*
X913208Y615502D03*
X909208D03*
X904376Y615422D03*
X900376D03*
X903916Y806373D03*
X899916D03*
Y816523D03*
X903916D03*
X909416D03*
X900200Y912583D03*
X907300D03*
X903700D03*
X912628Y925609D03*
X904057Y940596D03*
X906255Y1018764D03*
X898046Y1017223D03*
X902225Y1018711D03*
X901392Y1207731D03*
X905070Y1214457D03*
X897427Y1208891D03*
X916473Y116534D03*
X927393Y107807D03*
X923393D03*
X925418Y130806D03*
X918607Y157923D03*
X915072Y384390D03*
X920999Y475425D03*
X925418Y680853D03*
X921418D03*
X921061Y712828D03*
X925061D03*
X927916Y814523D03*
X921790Y816523D03*
X920628Y925609D03*
X924628D03*
X928628D03*
X916628D03*
X927984Y1017136D03*
X916465D03*
X921861D03*
X931393Y107807D03*
X940062Y146820D03*
X932661Y198060D03*
X938125Y236727D03*
X942757Y257672D03*
X941685Y360736D03*
X942437Y367688D03*
X931072Y384390D03*
X940365Y616794D03*
X944365D03*
X932412Y680853D03*
X938526Y730508D03*
X935916Y814523D03*
X939916D03*
X941535Y826540D03*
X937635D03*
X940516Y898088D03*
X944628Y925609D03*
X936628D03*
X940628D03*
X932628D03*
X945671Y988726D03*
X939931Y1017136D03*
X945431D03*
X934378D03*
X946144Y106469D03*
X947040Y221213D03*
X951278Y241031D03*
Y248010D03*
X959816Y470402D03*
X948165Y616794D03*
X961503Y704315D03*
X953551D03*
X957551D03*
X959950Y731521D03*
X951100Y841583D03*
X952783Y833266D03*
X947200Y841583D03*
X957900Y853483D03*
X958567Y933302D03*
X950567D03*
X953671Y988726D03*
X961671D03*
X949671D03*
X950987Y1017136D03*
X954866D03*
X961404Y1208891D03*
X969109Y454821D03*
X975932Y442977D03*
X971932D03*
X963816Y470402D03*
X976397Y470542D03*
X970687Y536891D03*
X978581Y578815D03*
X977857Y602708D03*
X973857D03*
X975365Y639294D03*
X971865D03*
X963950Y731521D03*
X966746Y933275D03*
X962567Y933302D03*
X965671Y988726D03*
X967625Y1017367D03*
X971760Y1017387D03*
X963823Y1017223D03*
X975659Y1017408D03*
X965369Y1207731D03*
X969047Y1214457D03*
X990833Y101256D03*
X994833D03*
X984750Y101609D03*
X990939Y262593D03*
X990405Y314000D03*
X988045Y364067D03*
X992045D03*
X979932Y442977D03*
X980518Y490147D03*
X978865Y639294D03*
X983712Y719572D03*
X994051Y816826D03*
X1000337Y100533D03*
Y108145D03*
X998939Y262593D03*
X1000698Y305734D03*
X996045Y364067D03*
X1001825Y578620D03*
X1007990Y771457D03*
X995990D03*
X1006699Y816883D03*
X1002699D03*
X1010699D03*
X1010009Y986014D03*
Y995014D03*
X998872Y1004449D03*
X1000248Y1024394D03*
X1012844Y91859D03*
X1018835Y116534D03*
X1025755Y107807D03*
X1020969Y157923D03*
X1016635Y305734D03*
X1020635D03*
X1025749D03*
X1012635D03*
X1018922Y805798D03*
X1014819Y935395D03*
X1026009Y986014D03*
X1018009D03*
X1022009D03*
X1014009D03*
X1026009Y995014D03*
X1018009D03*
X1022009D03*
X1014009D03*
X1011782Y1013880D03*
X1019774Y1226509D03*
X1023774D03*
X1017329Y1316495D03*
X1020049Y1333819D03*
X1019671Y1347982D03*
X1019257Y1366456D03*
X1033755Y107807D03*
X1029755D03*
X1027780Y130806D03*
X1042424Y146820D03*
X1034357Y212889D03*
X1029639Y305734D03*
X1041408Y448564D03*
X1030009Y986014D03*
X1038009D03*
X1042009D03*
X1034009D03*
Y995014D03*
X1030009D03*
X1038009D03*
X1042009D03*
X1041777Y1105591D03*
Y1118191D03*
Y1130791D03*
Y1143391D03*
Y1155991D03*
Y1168591D03*
Y1181191D03*
X1038996Y1371550D03*
X1048506Y106469D03*
X1048736Y236042D03*
X1045650Y305734D03*
X1057134Y541833D03*
X1053144Y541874D03*
X1046009Y986014D03*
X1050009D03*
X1054009D03*
X1058009D03*
X1046009Y995014D03*
X1050009D03*
X1054009D03*
X1058009D03*
X1053423Y1012854D03*
Y1025454D03*
X1074009Y986014D03*
X1066009D03*
X1062009D03*
X1074009Y995014D03*
X1066009D03*
X1062009D03*
X1070009D03*
X1087112Y101609D03*
X1086108Y1526491D03*
X1086469Y1585468D03*
X1090904Y1596264D03*
X1089474Y1634908D03*
X1093195Y101256D03*
X1097195D03*
X1102699Y100533D03*
Y108145D03*
X1093301Y262593D03*
X1101301D03*
X1096233Y1585491D03*
X1104233D03*
X1102904Y1596264D03*
X1093474Y1634908D03*
X1101474D03*
X1105474D03*
X1115206Y91859D03*
X1121197Y116534D03*
X1123331Y157923D03*
X1136117Y107807D03*
X1132117D03*
X1128117D03*
X1130142Y130806D03*
X1136719Y212889D03*
X1150868Y106469D03*
X1144786Y146820D03*
X1151098Y236042D03*
X1156275Y653729D03*
X1156485Y770625D03*
X1155485Y842125D03*
X1160275Y653729D03*
X1164275D03*
X1167485Y828625D03*
X1159485D03*
X1171485Y842125D03*
X1163485D03*
X1167485D03*
X1159485D03*
X1189474Y101609D03*
X1183485Y828625D03*
X1175485D03*
X1183485Y842125D03*
X1179485D03*
X1175485D03*
X1195557Y101256D03*
X1199557D03*
X1205061Y100533D03*
Y108145D03*
X1195663Y262593D03*
X1203663D03*
X1217568Y91859D03*
X1238479Y107807D03*
X1223559Y116534D03*
X1234479Y107807D03*
X1230479D03*
X1232504Y130806D03*
X1225693Y157923D03*
X1226436Y321798D03*
X1231589Y345377D03*
X1235589D03*
X1237458Y553195D03*
X1253230Y106469D03*
X1247148Y146820D03*
X1239081Y212889D03*
X1253460Y236042D03*
X1250928Y1140187D03*
X1251802Y1178808D03*
X1249230Y1192404D03*
X1256659Y382631D03*
X1268659D03*
X1260659D03*
X1264659D03*
X1267375Y411985D03*
X1256458Y558195D03*
X1261622Y901500D03*
X1259921Y1140187D03*
X1264587Y1178148D03*
X1268587D03*
X1268615Y1185113D03*
X1264615D03*
X1255485Y1201908D03*
X1275660Y345693D03*
X1279655Y345634D03*
X1276659Y382631D03*
X1272659D03*
X1280042Y905131D03*
X1279921Y1140187D03*
X1277912Y1178196D03*
X1273912D03*
X1273934Y1185109D03*
X1277902Y1185146D03*
X1297919Y101256D03*
X1301919D03*
X1291836Y101609D03*
X1298025Y262593D03*
X1303410Y376537D03*
X1287437Y375662D03*
X1295410Y376537D03*
X1299410D03*
X1292566Y807304D03*
X1298909Y818575D03*
X1288155Y897983D03*
X1302000Y922983D03*
X1298000D03*
X1300882Y934047D03*
X1300500Y966983D03*
X1314859Y42956D03*
X1318859D03*
X1307423Y100533D03*
Y108145D03*
X1306025Y262593D03*
X1308410Y376539D03*
X1316903Y368224D03*
X1317000Y793483D03*
X1313000D03*
Y809483D03*
X1317000D03*
X1313152Y934047D03*
X1309103D03*
X1317000Y940983D03*
X1304949Y934047D03*
X1307000Y966983D03*
X1317437Y1158242D03*
X1325007Y368232D03*
X1334009Y368093D03*
X1326020Y432320D03*
X1333000Y793483D03*
X1329000D03*
X1325000D03*
X1321000D03*
X1333000Y809483D03*
X1325000D03*
X1329000D03*
X1321000D03*
X1322500Y922983D03*
X1326500D03*
Y940983D03*
X1327000Y966983D03*
X1332000D03*
X1331856Y1057696D03*
X1324842Y1105613D03*
X1328629D03*
X1337609Y368093D03*
X1339846Y459084D03*
X1341000Y793483D03*
X1337000D03*
X1341000Y809483D03*
X1345000D03*
X1349000D03*
X1337000D03*
X1350500Y922983D03*
X1336000Y940983D03*
X1337691Y951626D03*
X1342087Y1101825D03*
X1336706D03*
X1345459Y1113379D03*
X1353000Y809483D03*
X1354500Y922983D03*
X1358500D03*
X1362500D03*
X1366500D03*
X1361948Y949086D03*
X1356970Y1105613D03*
X1360757D03*
X1373560Y116534D03*
X1384480Y107807D03*
X1380480D03*
X1382505Y130806D03*
X1375694Y157923D03*
X1370500Y922983D03*
X1378500D03*
X1374500D03*
X1382500D03*
X1373948Y949086D03*
X1374215Y1101825D03*
X1368834D03*
X1377587Y1113379D03*
X1376861Y1158242D03*
X1383024D03*
X1388480Y107807D03*
X1397149Y146820D03*
X1389082Y212889D03*
X1397452Y616794D03*
X1390537Y809162D03*
X1386335Y809187D03*
X1388346Y927128D03*
X1390429Y1105613D03*
X1394216D03*
X1403231Y106469D03*
X1403461Y236042D03*
X1414903Y467402D03*
X1405252Y616794D03*
X1401452D03*
X1401000Y922983D03*
X1407674Y1101825D03*
X1402293D03*
X1411046Y1113379D03*
X1416684Y1514632D03*
X1411586Y1546437D03*
X1411094Y1569115D03*
X1431019Y439977D03*
X1427019D03*
X1424196Y451821D03*
X1431484Y467542D03*
X1418903Y467402D03*
X1427774Y536891D03*
X1430944Y602708D03*
X1432452Y639294D03*
X1428952D03*
X1420132Y1057989D03*
X1422557Y1105613D03*
X1426344D03*
X1426253Y1410760D03*
X1430374Y1498553D03*
X1433405Y1543475D03*
X1432913Y1566153D03*
X1447920Y101256D03*
X1441837Y101609D03*
X1448026Y262593D03*
X1435019Y439977D03*
X1437605Y490147D03*
X1435668Y578815D03*
X1434944Y602708D03*
X1435952Y639294D03*
X1443459Y1037394D03*
X1434421Y1101825D03*
X1443174Y1113379D03*
X1442448Y1158242D03*
X1436792Y1558424D03*
X1457424Y100533D03*
X1451920Y101256D03*
X1457424Y108145D03*
X1456026Y262593D03*
X1458912Y578620D03*
X1455959Y1004449D03*
X1469931Y91859D03*
X1475922Y116534D03*
X1478056Y157923D03*
X1475096Y986014D03*
X1479096D03*
X1471096D03*
X1467096D03*
X1475096Y995014D03*
X1479096D03*
X1471096D03*
X1467096D03*
X1468869Y1013880D03*
X1480861Y1226509D03*
X1476861D03*
X1490842Y107807D03*
X1482842D03*
X1486842D03*
X1484867Y130806D03*
X1491444Y212889D03*
X1491096Y986014D03*
X1487096D03*
X1495096D03*
X1483096D03*
X1491096Y995014D03*
X1487096D03*
X1495096D03*
X1483096D03*
X1505593Y106469D03*
X1499511Y146820D03*
X1505823Y236042D03*
X1498495Y448564D03*
X1514221Y541833D03*
X1510231Y541874D03*
X1503096Y986014D03*
X1507096D03*
X1511096D03*
X1499096D03*
X1503096Y995014D03*
X1507096D03*
X1511096D03*
X1499096D03*
X1510510Y1025454D03*
Y1012854D03*
X1498864Y1105591D03*
Y1118191D03*
Y1130791D03*
Y1143391D03*
Y1155991D03*
Y1168591D03*
Y1181191D03*
X1525015Y906508D03*
X1523096Y986014D03*
X1519096D03*
X1515096D03*
X1523096Y995014D03*
X1519096D03*
X1527096D03*
X1515096D03*
X1544199Y101609D03*
X1531096Y986014D03*
Y995014D03*
X1554282Y101256D03*
X1559786Y100533D03*
X1550282Y101256D03*
X1559786Y108145D03*
X1550388Y262593D03*
X1558388D03*
X1572293Y91859D03*
X1578284Y116534D03*
X1593204Y107807D03*
X1589204D03*
X1585204D03*
X1587229Y130806D03*
X1580418Y157923D03*
X1593806Y212889D03*
X1594307Y1505038D03*
X1594500Y1511983D03*
X1607955Y106469D03*
X1601873Y146820D03*
X1608185Y236042D03*
X1608483Y783385D03*
X1608383Y798185D03*
X1608283Y812185D03*
X1600333Y1446468D03*
X1605000Y1511983D03*
X1598142Y1530368D03*
X1613362Y653729D03*
X1617362D03*
X1621362D03*
X1616683Y750485D03*
X1616583Y764485D03*
X1634083Y777685D03*
X1632583Y790385D03*
X1631383Y804485D03*
X1652644Y101256D03*
X1656644D03*
X1646561Y101609D03*
X1652750Y262593D03*
X1660750D03*
X1674655Y91859D03*
X1662148Y100533D03*
Y108145D03*
X1680646Y116534D03*
X1691566Y107807D03*
X1687566D03*
X1689591Y130806D03*
X1682780Y157923D03*
X1683523Y321798D03*
X1688676Y345377D03*
X1692676D03*
X1695566Y107807D03*
X1704235Y146820D03*
X1696168Y212889D03*
X1694545Y553195D03*
X1708015Y1140187D03*
X1708889Y1178808D03*
X1708745Y1227183D03*
X1710317Y106469D03*
X1710547Y236042D03*
X1713746Y382631D03*
X1717746D03*
X1725746D03*
X1721746D03*
X1724462Y411985D03*
X1713545Y558195D03*
X1717008Y1140187D03*
X1725674Y1178148D03*
X1721674D03*
X1725702Y1185113D03*
X1721702D03*
X1713721Y1206369D03*
X1709827Y1206323D03*
X1712966Y1227174D03*
X1733746Y382631D03*
X1729746D03*
X1737008Y1140187D03*
X1734999Y1178196D03*
X1730999D03*
X1731021Y1185109D03*
X1734989Y1185146D03*
X1755006Y101256D03*
X1748923Y101609D03*
X1755112Y262593D03*
X1752497Y376537D03*
X1756497D03*
X1756297Y1018535D03*
X1753221Y1621562D03*
X1764510Y100533D03*
X1759006Y101256D03*
X1764510Y108145D03*
X1763112Y262593D03*
X1765497Y376539D03*
X1760497Y376537D03*
X1765131Y1018535D03*
X1760487D03*
X1771992D03*
X1774339Y1443593D03*
X1774216Y1475783D03*
X1763000Y1584983D03*
X1777017Y91859D03*
X1783107Y432320D03*
X1789463Y966233D03*
X1784145Y1018535D03*
X1790035D03*
X1778042D03*
X1796933Y459084D03*
X1793474Y927469D03*
X1796344Y1018535D03*
X1802432D03*
X1805384Y1209377D03*
X1803885Y1440623D03*
X1803762Y1472813D03*
X1808320Y1018535D03*
X1812265D03*
X1816260D03*
X1809349Y1208217D03*
X1813027Y1214943D03*
X1828272Y1102015D03*
Y1109054D03*
G54D154*
X513666Y696458D03*
Y690553D03*
X521540Y688584D03*
X517603Y690553D03*
X519571D03*
X513666Y700395D03*
X515634Y690553D03*
X521540D03*
X513666Y692521D03*
Y694490D03*
Y698427D03*
X511697Y696458D03*
Y698427D03*
X519571Y688584D03*
X517603D03*
X515634D03*
X513666D03*
X511697Y700395D03*
Y688584D03*
Y690553D03*
Y692521D03*
Y694490D03*
X517603Y708269D03*
X513666Y702364D03*
Y708269D03*
X521540D03*
X513666Y704332D03*
Y706301D03*
X519571Y708269D03*
X515634D03*
X511697Y702364D03*
Y704332D03*
Y706301D03*
Y708269D03*
Y710238D03*
X513666D03*
X515634D03*
X517603D03*
X519571D03*
X521540D03*
X531382Y696458D03*
Y692521D03*
X529414Y690553D03*
X525477D03*
X531382D03*
Y700395D03*
X527445Y690553D03*
X523508D03*
X531382Y694490D03*
Y698427D03*
X533351Y700395D03*
Y698427D03*
Y696458D03*
Y694490D03*
Y692521D03*
Y690553D03*
Y688584D03*
X531382D03*
X529414D03*
X527445D03*
X525477D03*
X523508D03*
X525477Y708269D03*
X533351Y702364D03*
X529414Y708269D03*
X531382Y706301D03*
Y702364D03*
Y708269D03*
Y704332D03*
X527445Y708269D03*
X523508D03*
Y710238D03*
X525477D03*
X527445D03*
X529414D03*
X531382D03*
X533351D03*
Y708269D03*
Y706301D03*
Y704332D03*
G54D217*
X1027569Y1344460D03*
Y1348200D03*
Y1351940D03*
X1037883D03*
Y1348200D03*
Y1344460D03*
G54D43*
X34292Y601811D03*
Y607311D03*
X40092Y601811D03*
Y607311D03*
X82715Y656990D03*
X88515D03*
X96871Y1027663D03*
X109164Y1005353D03*
X103364D03*
X102671Y1027663D03*
X115533Y1103108D03*
Y1115708D03*
Y1128308D03*
Y1140908D03*
Y1153508D03*
Y1166108D03*
Y1178708D03*
X127179Y1010371D03*
X132979D03*
X127179Y1022971D03*
X132979D03*
X121333Y1103108D03*
X133954Y1110308D03*
X128154D03*
X133954Y1122908D03*
X128154D03*
X121333Y1115708D03*
X133954Y1135508D03*
X128154D03*
X121333Y1128308D03*
Y1140908D03*
X133954Y1148108D03*
X128154D03*
X121333Y1153508D03*
X133954Y1160708D03*
X128154D03*
X133954Y1173308D03*
X128154D03*
X121333Y1166108D03*
X133954Y1185908D03*
X128154D03*
X121333Y1178708D03*
X145600Y1017571D03*
X139800D03*
X145600Y1030171D03*
X139800D03*
X400728Y344439D03*
X406528D03*
Y349939D03*
X400728D03*
X399300Y793800D03*
X405100D03*
X456439Y1247517D03*
X462239D03*
X491378Y601811D03*
Y607311D03*
X497178Y601811D03*
Y607311D03*
X534624Y774889D03*
X540424D03*
X549304Y846389D03*
X555104D03*
X553958Y1027663D03*
X566251Y1005353D03*
X560451D03*
X559758Y1027663D03*
X572620Y1103108D03*
Y1115708D03*
Y1128308D03*
Y1140908D03*
Y1153508D03*
Y1166108D03*
Y1178708D03*
X584266Y1010371D03*
Y1022971D03*
X578420Y1103108D03*
Y1115708D03*
X585241Y1110308D03*
Y1122908D03*
Y1135508D03*
X578420Y1128308D03*
Y1140908D03*
X585241Y1148108D03*
X578420Y1153508D03*
X585241Y1160708D03*
Y1173308D03*
X578420Y1166108D03*
X585241Y1185908D03*
X578420Y1178708D03*
X590066Y1010371D03*
X602687Y1017571D03*
X596887D03*
X590066Y1022971D03*
X602687Y1030171D03*
X596887D03*
X591041Y1110308D03*
Y1122908D03*
Y1135508D03*
Y1148108D03*
Y1160708D03*
Y1173308D03*
Y1185908D03*
X948465Y601811D03*
X954265D03*
Y607311D03*
X948465D03*
X1011044Y1027663D03*
X1023337Y1005353D03*
X1017537D03*
X1016844Y1027663D03*
X1041352Y1010371D03*
Y1022971D03*
X1029706Y1103108D03*
X1035506D03*
X1029706Y1115708D03*
X1035506D03*
X1042327Y1110308D03*
Y1122908D03*
X1029706Y1140908D03*
X1035506D03*
X1029706Y1128308D03*
X1035506D03*
X1042327Y1135508D03*
X1029706Y1153508D03*
X1035506D03*
X1042327Y1148108D03*
X1029706Y1166108D03*
X1035506D03*
X1042327Y1160708D03*
Y1173308D03*
X1029706Y1178708D03*
X1035506D03*
X1042327Y1185908D03*
X1047152Y1010371D03*
Y1022971D03*
X1059773Y1017571D03*
X1053973D03*
X1059773Y1030171D03*
X1053973D03*
X1048127Y1110308D03*
Y1122908D03*
Y1135508D03*
Y1148108D03*
Y1160708D03*
Y1173308D03*
Y1185908D03*
X1303313Y351454D03*
Y356954D03*
X1309113Y351454D03*
Y356954D03*
X1405552Y601811D03*
X1411352D03*
Y607311D03*
X1405552D03*
X1480424Y1005353D03*
X1474624D03*
X1468131Y1027663D03*
X1473931D03*
X1498439Y1010371D03*
Y1022971D03*
X1486793Y1103108D03*
X1492593D03*
X1486793Y1115708D03*
X1492593D03*
X1486793Y1128308D03*
X1492593D03*
X1486793Y1140908D03*
X1492593D03*
X1486793Y1153508D03*
X1492593D03*
X1486793Y1166108D03*
X1492593D03*
X1486793Y1178708D03*
X1492593D03*
X1499383Y902240D03*
X1505183D03*
X1514063Y973740D03*
X1504239Y1010371D03*
Y1022971D03*
X1511060Y1017571D03*
Y1030171D03*
X1505214Y1122908D03*
X1499414D03*
X1505214Y1110308D03*
X1499414D03*
X1505214Y1135508D03*
X1499414D03*
X1505214Y1148108D03*
X1499414D03*
X1505214Y1173308D03*
X1499414D03*
X1505214Y1160708D03*
X1499414D03*
X1505214Y1185908D03*
X1499414D03*
X1519863Y973740D03*
X1516860Y1017571D03*
Y1030171D03*
X1777250Y929249D03*
X1783050D03*
X1802965Y1075688D03*
X1808765D03*
G54D163*
X714937Y734432D03*
X707063Y738172D03*
X714937Y741912D03*
X893324Y715230D03*
Y722710D03*
X907324Y706030D03*
Y713510D03*
X901198Y718970D03*
X915198Y709770D03*
X1025466Y1373216D03*
Y1380696D03*
X1033340Y1376956D03*
G54D127*
X397498Y1539978D03*
Y1538009D03*
Y1541947D03*
Y1545883D03*
Y1543915D03*
Y1549821D03*
Y1547852D03*
X416494Y1543915D03*
Y1541947D03*
Y1538009D03*
Y1545883D03*
Y1539978D03*
Y1547852D03*
Y1549821D03*
X911845Y359317D03*
Y357348D03*
Y361286D03*
Y369160D03*
Y367191D03*
Y365222D03*
Y363254D03*
X930841Y357348D03*
Y359317D03*
Y363254D03*
Y361286D03*
Y367191D03*
Y365222D03*
Y369160D03*
G54D208*
X942586Y1475447D03*
G54D52*
X41988Y83425D03*
Y81063D03*
Y78701D03*
Y76339D03*
Y73977D03*
Y99961D03*
Y97599D03*
Y95236D03*
Y92874D03*
Y90512D03*
Y88150D03*
Y85788D03*
Y116496D03*
Y114134D03*
Y111772D03*
Y109410D03*
Y107047D03*
Y104685D03*
Y102323D03*
Y133032D03*
Y130670D03*
Y128307D03*
Y125945D03*
Y123583D03*
Y121221D03*
Y118859D03*
Y137756D03*
Y135394D03*
X60098Y83425D03*
Y81063D03*
Y78701D03*
Y76339D03*
Y73977D03*
Y99961D03*
Y97599D03*
Y95236D03*
Y92874D03*
Y90512D03*
Y88150D03*
Y85788D03*
Y116496D03*
Y114134D03*
Y111772D03*
Y109410D03*
Y107047D03*
Y104685D03*
Y102323D03*
Y133032D03*
Y130670D03*
Y128307D03*
Y125945D03*
Y123583D03*
Y121221D03*
Y118859D03*
Y137756D03*
Y135394D03*
X144350Y83425D03*
Y81063D03*
Y78701D03*
Y76339D03*
Y73977D03*
Y99961D03*
Y97599D03*
Y95236D03*
Y92874D03*
Y90512D03*
Y88150D03*
Y85788D03*
Y116496D03*
Y114134D03*
Y111772D03*
Y109410D03*
Y107047D03*
Y104685D03*
Y102323D03*
Y133032D03*
Y130670D03*
Y128307D03*
Y125945D03*
Y123583D03*
Y121221D03*
Y118859D03*
Y137756D03*
Y135394D03*
X162460Y83425D03*
Y81063D03*
Y78701D03*
Y76339D03*
Y73977D03*
Y99961D03*
Y97599D03*
Y95236D03*
Y92874D03*
Y90512D03*
Y88150D03*
Y85788D03*
Y116496D03*
Y114134D03*
Y111772D03*
Y109410D03*
Y107047D03*
Y104685D03*
Y102323D03*
Y133032D03*
Y130670D03*
Y128307D03*
Y125945D03*
Y123583D03*
Y121221D03*
Y118859D03*
Y137756D03*
Y135394D03*
X246712Y83425D03*
Y81063D03*
Y78701D03*
Y76339D03*
Y73977D03*
Y99961D03*
Y97599D03*
Y95236D03*
Y92874D03*
Y90512D03*
Y88150D03*
Y85788D03*
Y116496D03*
Y114134D03*
Y111772D03*
Y109410D03*
Y107047D03*
Y104685D03*
Y102323D03*
Y133032D03*
Y130670D03*
Y128307D03*
Y125945D03*
Y123583D03*
Y121221D03*
Y118859D03*
Y137756D03*
Y135394D03*
X264822Y83425D03*
Y81063D03*
Y78701D03*
Y76339D03*
Y73977D03*
Y99961D03*
Y97599D03*
Y95236D03*
Y92874D03*
Y90512D03*
Y88150D03*
Y85788D03*
Y116496D03*
Y114134D03*
Y111772D03*
Y109410D03*
Y107047D03*
Y104685D03*
Y102323D03*
Y133032D03*
Y130670D03*
Y128307D03*
Y125945D03*
Y123583D03*
Y121221D03*
Y118859D03*
Y137756D03*
Y135394D03*
X349074Y83425D03*
Y81063D03*
Y78701D03*
Y76339D03*
Y73977D03*
Y99961D03*
Y97599D03*
Y95236D03*
Y92874D03*
Y90512D03*
Y88150D03*
Y85788D03*
Y116496D03*
Y114134D03*
Y111772D03*
Y109410D03*
Y107047D03*
Y104685D03*
Y102323D03*
Y133032D03*
Y130670D03*
Y128307D03*
Y125945D03*
Y123583D03*
Y121221D03*
Y118859D03*
Y137756D03*
Y135394D03*
X367184Y83425D03*
Y81063D03*
Y78701D03*
Y76339D03*
Y73977D03*
Y99961D03*
Y97599D03*
Y95236D03*
Y92874D03*
Y90512D03*
Y88150D03*
Y85788D03*
Y116496D03*
Y114134D03*
Y111772D03*
Y109410D03*
Y107047D03*
Y104685D03*
Y102323D03*
Y133032D03*
Y130670D03*
Y128307D03*
Y125945D03*
Y123583D03*
Y121221D03*
Y118859D03*
Y137756D03*
Y135394D03*
X499075Y83425D03*
Y81063D03*
Y78701D03*
Y76339D03*
Y73977D03*
Y99961D03*
Y97599D03*
Y95236D03*
Y92874D03*
Y90512D03*
Y88150D03*
Y85788D03*
Y116496D03*
Y114134D03*
Y111772D03*
Y109410D03*
Y107047D03*
Y104685D03*
Y102323D03*
Y133032D03*
Y130670D03*
Y128307D03*
Y125945D03*
Y123583D03*
Y121221D03*
Y118859D03*
Y137756D03*
Y135394D03*
X517185Y83425D03*
Y81063D03*
Y78701D03*
Y76339D03*
Y73977D03*
Y99961D03*
Y97599D03*
Y95236D03*
Y92874D03*
Y90512D03*
Y88150D03*
Y85788D03*
Y116496D03*
Y114134D03*
Y111772D03*
Y109410D03*
Y107047D03*
Y104685D03*
Y102323D03*
Y133032D03*
Y130670D03*
Y128307D03*
Y125945D03*
Y123583D03*
Y121221D03*
Y118859D03*
Y137756D03*
Y135394D03*
X601437Y83425D03*
Y81063D03*
Y78701D03*
Y76339D03*
Y73977D03*
Y99961D03*
Y97599D03*
Y95236D03*
Y92874D03*
Y90512D03*
Y88150D03*
Y85788D03*
Y116496D03*
Y114134D03*
Y111772D03*
Y109410D03*
Y107047D03*
Y104685D03*
Y102323D03*
Y133032D03*
Y130670D03*
Y128307D03*
Y125945D03*
Y123583D03*
Y121221D03*
Y118859D03*
Y137756D03*
Y135394D03*
X619547Y83425D03*
Y81063D03*
Y78701D03*
Y76339D03*
Y73977D03*
Y99961D03*
Y97599D03*
Y95236D03*
Y92874D03*
Y90512D03*
Y88150D03*
Y85788D03*
Y116496D03*
Y114134D03*
Y111772D03*
Y109410D03*
Y107047D03*
Y104685D03*
Y102323D03*
Y133032D03*
Y130670D03*
Y128307D03*
Y125945D03*
Y123583D03*
Y121221D03*
Y118859D03*
Y137756D03*
Y135394D03*
X703799Y83425D03*
Y81063D03*
Y78701D03*
Y76339D03*
Y73977D03*
Y99961D03*
Y97599D03*
Y95236D03*
Y92874D03*
Y90512D03*
Y88150D03*
Y85788D03*
Y116496D03*
Y114134D03*
Y111772D03*
Y109410D03*
Y107047D03*
Y104685D03*
Y102323D03*
Y133032D03*
Y130670D03*
Y128307D03*
Y125945D03*
Y123583D03*
Y121221D03*
Y118859D03*
Y137756D03*
Y135394D03*
X721909Y83425D03*
Y81063D03*
Y78701D03*
Y76339D03*
Y73977D03*
Y99961D03*
Y97599D03*
Y95236D03*
Y92874D03*
Y90512D03*
Y88150D03*
Y85788D03*
Y116496D03*
Y114134D03*
Y111772D03*
Y109410D03*
Y107047D03*
Y104685D03*
Y102323D03*
Y133032D03*
Y130670D03*
Y128307D03*
Y125945D03*
Y123583D03*
Y121221D03*
Y118859D03*
Y137756D03*
Y135394D03*
X806161Y83425D03*
Y81063D03*
Y78701D03*
Y76339D03*
Y73977D03*
Y99961D03*
Y97599D03*
Y95236D03*
Y92874D03*
Y90512D03*
Y88150D03*
Y85788D03*
Y116496D03*
Y114134D03*
Y111772D03*
Y109410D03*
Y107047D03*
Y104685D03*
Y102323D03*
Y133032D03*
Y130670D03*
Y128307D03*
Y125945D03*
Y123583D03*
Y121221D03*
Y118859D03*
Y137756D03*
Y135394D03*
X824271Y83425D03*
Y81063D03*
Y78701D03*
Y76339D03*
Y73977D03*
Y99961D03*
Y97599D03*
Y95236D03*
Y92874D03*
Y90512D03*
Y88150D03*
Y85788D03*
Y116496D03*
Y114134D03*
Y111772D03*
Y109410D03*
Y107047D03*
Y104685D03*
Y102323D03*
Y133032D03*
Y130670D03*
Y128307D03*
Y125945D03*
Y123583D03*
Y121221D03*
Y118859D03*
Y137756D03*
Y135394D03*
X956161Y83425D03*
Y81063D03*
Y78701D03*
Y76339D03*
Y73977D03*
Y99961D03*
Y97599D03*
Y95236D03*
Y92874D03*
Y90512D03*
Y88150D03*
Y85788D03*
Y116496D03*
Y114134D03*
Y111772D03*
Y109410D03*
Y107047D03*
Y104685D03*
Y102323D03*
Y133032D03*
Y130670D03*
Y128307D03*
Y125945D03*
Y123583D03*
Y121221D03*
Y118859D03*
Y137756D03*
Y135394D03*
X974271Y83425D03*
Y81063D03*
Y78701D03*
Y76339D03*
Y73977D03*
Y99961D03*
Y97599D03*
Y95236D03*
Y92874D03*
Y90512D03*
Y88150D03*
Y85788D03*
Y116496D03*
Y114134D03*
Y111772D03*
Y109410D03*
Y107047D03*
Y104685D03*
Y102323D03*
Y133032D03*
Y130670D03*
Y128307D03*
Y125945D03*
Y123583D03*
Y121221D03*
Y118859D03*
Y137756D03*
Y135394D03*
X1058523Y83425D03*
Y81063D03*
Y78701D03*
Y76339D03*
Y73977D03*
Y99961D03*
Y97599D03*
Y95236D03*
Y92874D03*
Y90512D03*
Y88150D03*
Y85788D03*
Y116496D03*
Y114134D03*
Y111772D03*
Y109410D03*
Y107047D03*
Y104685D03*
Y102323D03*
Y133032D03*
Y130670D03*
Y128307D03*
Y125945D03*
Y123583D03*
Y121221D03*
Y118859D03*
Y137756D03*
Y135394D03*
X1076633Y83425D03*
Y81063D03*
Y78701D03*
Y76339D03*
Y73977D03*
Y99961D03*
Y97599D03*
Y95236D03*
Y92874D03*
Y90512D03*
Y88150D03*
Y85788D03*
Y116496D03*
Y114134D03*
Y111772D03*
Y109410D03*
Y107047D03*
Y104685D03*
Y102323D03*
Y133032D03*
Y130670D03*
Y128307D03*
Y125945D03*
Y123583D03*
Y121221D03*
Y118859D03*
Y137756D03*
Y135394D03*
X1160885Y83425D03*
Y81063D03*
Y78701D03*
Y76339D03*
Y73977D03*
Y99961D03*
Y97599D03*
Y95236D03*
Y92874D03*
Y90512D03*
Y88150D03*
Y85788D03*
Y116496D03*
Y114134D03*
Y111772D03*
Y109410D03*
Y107047D03*
Y104685D03*
Y102323D03*
Y133032D03*
Y130670D03*
Y128307D03*
Y125945D03*
Y123583D03*
Y121221D03*
Y118859D03*
Y137756D03*
Y135394D03*
X1178995Y83425D03*
Y81063D03*
Y78701D03*
Y76339D03*
Y73977D03*
Y99961D03*
Y97599D03*
Y95236D03*
Y92874D03*
Y90512D03*
Y88150D03*
Y85788D03*
Y116496D03*
Y114134D03*
Y111772D03*
Y109410D03*
Y107047D03*
Y104685D03*
Y102323D03*
Y133032D03*
Y130670D03*
Y128307D03*
Y125945D03*
Y123583D03*
Y121221D03*
Y118859D03*
Y137756D03*
Y135394D03*
X1263247Y83425D03*
Y81063D03*
Y78701D03*
Y76339D03*
Y73977D03*
Y99961D03*
Y97599D03*
Y95236D03*
Y92874D03*
Y90512D03*
Y88150D03*
Y85788D03*
Y116496D03*
Y114134D03*
Y111772D03*
Y109410D03*
Y107047D03*
Y104685D03*
Y102323D03*
Y133032D03*
Y130670D03*
Y128307D03*
Y125945D03*
Y123583D03*
Y121221D03*
Y118859D03*
Y137756D03*
Y135394D03*
X1281357Y83425D03*
Y81063D03*
Y78701D03*
Y76339D03*
Y73977D03*
Y99961D03*
Y97599D03*
Y95236D03*
Y92874D03*
Y90512D03*
Y88150D03*
Y85788D03*
Y116496D03*
Y114134D03*
Y111772D03*
Y109410D03*
Y107047D03*
Y104685D03*
Y102323D03*
Y133032D03*
Y130670D03*
Y128307D03*
Y125945D03*
Y123583D03*
Y121221D03*
Y118859D03*
Y137756D03*
Y135394D03*
X1413248Y83425D03*
Y81063D03*
Y78701D03*
Y76339D03*
Y73977D03*
Y99961D03*
Y97599D03*
Y95236D03*
Y92874D03*
Y90512D03*
Y88150D03*
Y85788D03*
Y116496D03*
Y114134D03*
Y111772D03*
Y109410D03*
Y107047D03*
Y104685D03*
Y102323D03*
Y133032D03*
Y130670D03*
Y128307D03*
Y125945D03*
Y123583D03*
Y121221D03*
Y118859D03*
Y137756D03*
Y135394D03*
X1431358Y83425D03*
Y81063D03*
Y78701D03*
Y76339D03*
Y73977D03*
Y99961D03*
Y97599D03*
Y95236D03*
Y92874D03*
Y90512D03*
Y88150D03*
Y85788D03*
Y116496D03*
Y114134D03*
Y111772D03*
Y109410D03*
Y107047D03*
Y104685D03*
Y102323D03*
Y133032D03*
Y130670D03*
Y128307D03*
Y125945D03*
Y123583D03*
Y121221D03*
Y118859D03*
Y137756D03*
Y135394D03*
X1515610Y83425D03*
Y81063D03*
Y78701D03*
Y76339D03*
Y73977D03*
Y99961D03*
Y97599D03*
Y95236D03*
Y92874D03*
Y90512D03*
Y88150D03*
Y85788D03*
Y116496D03*
Y114134D03*
Y111772D03*
Y109410D03*
Y107047D03*
Y104685D03*
Y102323D03*
Y133032D03*
Y130670D03*
Y128307D03*
Y125945D03*
Y123583D03*
Y121221D03*
Y118859D03*
Y137756D03*
Y135394D03*
X1533720Y83425D03*
Y81063D03*
Y78701D03*
Y76339D03*
Y73977D03*
Y99961D03*
Y97599D03*
Y95236D03*
Y92874D03*
Y90512D03*
Y88150D03*
Y85788D03*
Y116496D03*
Y114134D03*
Y111772D03*
Y109410D03*
Y107047D03*
Y104685D03*
Y102323D03*
Y133032D03*
Y130670D03*
Y128307D03*
Y125945D03*
Y123583D03*
Y121221D03*
Y118859D03*
Y137756D03*
Y135394D03*
X1617972Y83425D03*
Y81063D03*
Y78701D03*
Y76339D03*
Y73977D03*
Y99961D03*
Y97599D03*
Y95236D03*
Y92874D03*
Y90512D03*
Y88150D03*
Y85788D03*
Y116496D03*
Y114134D03*
Y111772D03*
Y109410D03*
Y107047D03*
Y104685D03*
Y102323D03*
Y133032D03*
Y130670D03*
Y128307D03*
Y125945D03*
Y123583D03*
Y121221D03*
Y118859D03*
Y137756D03*
Y135394D03*
X1636082Y83425D03*
Y81063D03*
Y78701D03*
Y76339D03*
Y73977D03*
Y99961D03*
Y97599D03*
Y95236D03*
Y92874D03*
Y90512D03*
Y88150D03*
Y85788D03*
Y116496D03*
Y114134D03*
Y111772D03*
Y109410D03*
Y107047D03*
Y104685D03*
Y102323D03*
Y133032D03*
Y130670D03*
Y128307D03*
Y125945D03*
Y123583D03*
Y121221D03*
Y118859D03*
Y137756D03*
Y135394D03*
X1720334Y83425D03*
Y81063D03*
Y78701D03*
Y76339D03*
Y73977D03*
Y99961D03*
Y97599D03*
Y95236D03*
Y92874D03*
Y90512D03*
Y88150D03*
Y85788D03*
Y116496D03*
Y114134D03*
Y111772D03*
Y109410D03*
Y107047D03*
Y104685D03*
Y102323D03*
Y133032D03*
Y130670D03*
Y128307D03*
Y125945D03*
Y123583D03*
Y121221D03*
Y118859D03*
Y137756D03*
Y135394D03*
X1738444Y83425D03*
Y81063D03*
Y78701D03*
Y76339D03*
Y73977D03*
Y99961D03*
Y97599D03*
Y95236D03*
Y92874D03*
Y90512D03*
Y88150D03*
Y85788D03*
Y116496D03*
Y114134D03*
Y111772D03*
Y109410D03*
Y107047D03*
Y104685D03*
Y102323D03*
Y133032D03*
Y130670D03*
Y128307D03*
Y125945D03*
Y123583D03*
Y121221D03*
Y118859D03*
Y137756D03*
Y135394D03*
G54D226*
X1155929Y786294D03*
Y808342D03*
X1171284Y786294D03*
X1158488D03*
X1161047D03*
X1163606D03*
X1166166D03*
X1168725D03*
X1158488Y808342D03*
X1171284D03*
X1161047D03*
X1163606D03*
X1166166D03*
X1168725D03*
X1173843Y786294D03*
Y808342D03*
G54D25*
X18745Y200645D03*
X25745D03*
X29424Y667294D03*
X36424D03*
X29424Y675765D03*
X36424D03*
X34410Y1220505D03*
Y1234305D03*
Y1227405D03*
Y1241205D03*
X49393Y523969D03*
X37959Y559194D03*
X44959D03*
X37959Y567194D03*
X44959D03*
X37959Y575194D03*
X44959D03*
X41410Y1220505D03*
X47750Y1221988D03*
X41410Y1234305D03*
Y1227405D03*
X47750Y1228888D03*
Y1235788D03*
X41410Y1241205D03*
X59203Y477988D03*
X66203D03*
X56393Y523969D03*
X63149Y822618D03*
X54750Y1221988D03*
Y1228888D03*
Y1235788D03*
X83998Y229621D03*
X76998D03*
X83525Y664104D03*
X70149Y822618D03*
X90525Y664104D03*
X121107Y200645D03*
X128107D03*
X179360Y229621D03*
X186360D03*
X223469Y200645D03*
X230469D03*
X242583Y669913D03*
X246583Y661113D03*
X250583Y669913D03*
X288722Y229621D03*
X281722D03*
X325831Y200645D03*
X327427Y312849D03*
X319427D03*
X323427Y321649D03*
X332831Y200645D03*
X358676Y466326D03*
X365676D03*
X372500Y494216D03*
X365500D03*
X391084Y229621D03*
X384084D03*
X392767Y408142D03*
X385767D03*
X400968Y846677D03*
X407968D03*
X398190Y1093068D03*
X405190D03*
X398184Y1085881D03*
X405184D03*
X421726Y654538D03*
Y647730D03*
X423241Y846644D03*
X416241D03*
X423241Y862644D03*
X416241D03*
X423241Y854644D03*
X416241D03*
X440090Y515536D03*
X438226Y654538D03*
Y647730D03*
X428726Y654538D03*
Y647730D03*
X439744Y1093088D03*
X447090Y515536D03*
X445226Y654538D03*
Y647730D03*
X452591Y996766D03*
X459591D03*
X446744Y1093088D03*
X475832Y200645D03*
X471770Y480801D03*
X464770D03*
X463777Y1093068D03*
X470777D03*
X482832Y200645D03*
X506479Y523969D03*
X495045Y559194D03*
X502045D03*
X495045Y567194D03*
X502045D03*
X495045Y575194D03*
X502045D03*
X505331Y1093088D03*
X505189Y1085890D03*
X516289Y477988D03*
X523289D03*
X513479Y523969D03*
X512331Y1093088D03*
X512189Y1085890D03*
X534085Y229621D03*
X541085D03*
X578194Y200645D03*
X585194D03*
X580203Y936707D03*
X587203D03*
X636447Y229621D03*
X643447D03*
X680556Y200645D03*
X687556D03*
X699669Y669913D03*
X707669D03*
X703669Y661113D03*
X745809Y229621D03*
X738809D03*
X782918Y200645D03*
X784513Y312849D03*
X776513D03*
X780513Y321649D03*
X789918Y200645D03*
X815762Y460326D03*
X822762D03*
X829586Y489216D03*
X822586D03*
X848171Y229621D03*
X841171D03*
X881093Y421483D03*
X876440Y1236491D03*
Y1229591D03*
Y1243391D03*
Y1250291D03*
X888093Y421483D03*
X891440Y1230991D03*
Y1237891D03*
X883440Y1236491D03*
Y1229591D03*
X891440Y1244791D03*
X883440Y1243391D03*
Y1250291D03*
X898440Y1230991D03*
Y1237891D03*
Y1244791D03*
X933584Y185816D03*
X940584D03*
X940417Y1229591D03*
Y1236491D03*
Y1243391D03*
Y1250291D03*
X952132Y559194D03*
X959132D03*
X952132Y567194D03*
X959132D03*
X952132Y575194D03*
X959132D03*
X962417Y1230991D03*
X955417D03*
X962417Y1237891D03*
X955417D03*
X947417Y1229591D03*
Y1236491D03*
X962417Y1244791D03*
X955417D03*
X947417Y1243391D03*
Y1250291D03*
X973376Y477988D03*
X963566Y523969D03*
X970566D03*
X976703Y842659D03*
X991171Y229621D03*
X980376Y477988D03*
X983703Y842659D03*
X998171Y229621D03*
X1021703Y843159D03*
X1014703D03*
X1021819Y933722D03*
X1035280Y200645D03*
X1042280D03*
X1028819Y933722D03*
X1100533Y229621D03*
X1093533D03*
X1137642Y200645D03*
X1144642D03*
X1156756Y669913D03*
X1164756D03*
X1160756Y661113D03*
X1202895Y229621D03*
X1195895D03*
X1233600Y312849D03*
X1237600Y321649D03*
X1240004Y200645D03*
X1247004D03*
X1241600Y312849D03*
X1279849Y466326D03*
X1272849D03*
X1286673Y494216D03*
X1279673D03*
X1298257Y229621D03*
X1299940Y408142D03*
X1305257Y229621D03*
X1306940Y408142D03*
X1312364Y1093068D03*
X1319364D03*
X1312358Y1085881D03*
X1319358D03*
X1366765Y996766D03*
X1360918Y1093088D03*
X1353918D03*
X1373765Y996766D03*
X1377951Y1093068D03*
X1384951D03*
X1390005Y200645D03*
X1397005D03*
X1409219Y559194D03*
X1416219D03*
X1409219Y567194D03*
X1416219D03*
X1409219Y575194D03*
X1416219D03*
X1430463Y477988D03*
X1420653Y523969D03*
X1427653D03*
X1426505Y1093088D03*
X1419505D03*
X1426363Y1085890D03*
X1419363D03*
X1448258Y229621D03*
X1437463Y477988D03*
X1455258Y229621D03*
X1492367Y200645D03*
X1499367D03*
X1557620Y229621D03*
X1550620D03*
X1594729Y200645D03*
X1601729D03*
X1613843Y669913D03*
X1621843D03*
X1617843Y661113D03*
X1659982Y229621D03*
X1652982D03*
X1690687Y312849D03*
X1697091Y200645D03*
X1704091D03*
X1698687Y312849D03*
X1694687Y321649D03*
X1736936Y466326D03*
X1729936D03*
X1736760Y494216D03*
X1755344Y229621D03*
X1757027Y408142D03*
X1743760Y494216D03*
X1762344Y229621D03*
X1764027Y408142D03*
X1784397Y1236977D03*
X1791397D03*
X1784397Y1230077D03*
X1791397D03*
X1784397Y1243877D03*
X1791397D03*
X1784397Y1250777D03*
X1791397D03*
X1796463Y964560D03*
X1803463D03*
X1806397Y1231477D03*
X1799397D03*
X1806397Y1238377D03*
X1799397D03*
X1806397Y1245277D03*
X1799397D03*
G54D181*
X855812Y1445699D03*
Y1459479D03*
X873530Y1445699D03*
Y1459479D03*
X897812Y1445699D03*
Y1459479D03*
X915530Y1445699D03*
Y1459479D03*
G54D34*
X17874Y1041679D03*
X26360D03*
X48093D03*
X39607D03*
X440077Y1234726D03*
X448563D03*
X478786D03*
X487272D03*
X864564Y1050682D03*
X873050D03*
X894783D03*
X886297D03*
X928541D03*
X937027D03*
X958760D03*
X950274D03*
X1362737Y1234726D03*
X1354251D03*
X1392960D03*
X1401446D03*
X1772521Y1051168D03*
X1781007D03*
X1802740D03*
X1794254D03*
G54D109*
X360727Y453485D03*
X466821Y467960D03*
X817813Y447485D03*
X1274900Y453485D03*
X1731987D03*
G54D61*
X45012Y671782D03*
X66862D03*
G54D136*
X424040Y532429D03*
Y549751D03*
X447704Y532429D03*
Y549751D03*
G54D172*
X795791Y1446386D03*
Y1448158D03*
Y1457016D03*
Y1458788D03*
Y1453473D03*
Y1449930D03*
Y1455244D03*
Y1451701D03*
X821283Y1446386D03*
Y1448158D03*
Y1458788D03*
Y1451701D03*
Y1457016D03*
Y1453473D03*
Y1455244D03*
Y1449930D03*
G54D70*
X51653Y1355533D03*
X97806Y23214D03*
X105562Y826044D03*
X382749Y609811D03*
X520770Y330592D03*
X582703Y1464683D03*
X657531Y943324D03*
X811771Y518798D03*
X899546Y1369736D03*
X908190Y63396D03*
X1244511Y960614D03*
X1308096Y548593D03*
X1344628Y177855D03*
X1679534Y33878D03*
X1773034Y1565233D03*
X1795900Y852600D03*
G54D190*
X887193Y564037D03*
X889161D03*
X891130D03*
X893098D03*
X895067D03*
Y594549D03*
X893098D03*
X891130D03*
X889161D03*
X887193D03*
X910815Y564037D03*
X908846D03*
X906878D03*
X904909D03*
X899004D03*
X897035D03*
X902941D03*
X900972D03*
X912783D03*
Y594549D03*
X910815D03*
X900972D03*
X899004D03*
X897035D03*
X908846D03*
X906878D03*
X904909D03*
X902941D03*
X1009555Y316659D03*
Y347171D03*
X1011523Y316659D03*
X1013492D03*
X1015460D03*
X1017429D03*
X1019397D03*
X1021366D03*
X1023334D03*
X1025303D03*
X1015460Y347171D03*
X1013492D03*
X1025303D03*
X1023334D03*
X1021366D03*
X1019397D03*
X1017429D03*
X1011523D03*
X1031208Y316659D03*
X1027271D03*
X1029240D03*
X1033177D03*
X1035145D03*
Y347171D03*
X1033177D03*
X1031208D03*
X1029240D03*
X1027271D03*
G54D71*
X59848Y211751D03*
Y227499D03*
X59617Y271043D03*
Y286791D03*
X83374Y480347D03*
Y496095D03*
X73543Y526091D03*
Y541839D03*
X162210Y211751D03*
Y227499D03*
X161979Y271043D03*
Y286791D03*
X264572Y211751D03*
Y227499D03*
X264341Y271043D03*
Y286791D03*
X348329Y476109D03*
Y491857D03*
X366934Y211751D03*
Y227499D03*
X366703Y271043D03*
Y286791D03*
X390521Y437459D03*
Y453207D03*
X419390Y496242D03*
Y511990D03*
X516935Y211751D03*
Y227499D03*
X516704Y271043D03*
Y286791D03*
X540460Y480347D03*
Y496095D03*
X530629Y526091D03*
Y541839D03*
X619297Y211751D03*
Y227499D03*
X619066Y271043D03*
Y286791D03*
X721659Y211751D03*
Y227499D03*
X721428Y271043D03*
Y286791D03*
X805415Y471109D03*
Y486857D03*
X824021Y211751D03*
Y227499D03*
X823790Y271043D03*
Y286791D03*
X885801Y453800D03*
Y469548D03*
X974021Y211751D03*
Y227499D03*
X973790Y271043D03*
Y286791D03*
X987716Y526091D03*
Y541839D03*
X997547Y480347D03*
Y496095D03*
X1076383Y211751D03*
Y227499D03*
X1076152Y271043D03*
Y286791D03*
X1178745Y211751D03*
Y227499D03*
X1178514Y271043D03*
Y286791D03*
X1262502Y476109D03*
Y491857D03*
X1281107Y211751D03*
Y227499D03*
X1280876Y271043D03*
Y286791D03*
X1304748Y437459D03*
Y453207D03*
X1431108Y211751D03*
Y227499D03*
X1430877Y271043D03*
Y286791D03*
X1444803Y526091D03*
Y541839D03*
X1454634Y480347D03*
Y496095D03*
X1533470Y211751D03*
Y227499D03*
X1533239Y271043D03*
Y286791D03*
X1635832Y211751D03*
Y227499D03*
X1635601Y271043D03*
Y286791D03*
X1719589Y476109D03*
Y491857D03*
X1738194Y211751D03*
Y227499D03*
X1737963Y271043D03*
Y286791D03*
X1761835Y437459D03*
Y453207D03*
G54D35*
X15424Y1041679D03*
X28810D03*
X37157D03*
X50543D03*
X437627Y1234726D03*
X451013D03*
X476336D03*
X489722D03*
X862114Y1050682D03*
X875500D03*
X897233D03*
X883847D03*
X926091D03*
X947824D03*
X939477D03*
X961210D03*
X1351801Y1234726D03*
X1365187D03*
X1390510D03*
X1403896D03*
X1770071Y1051168D03*
X1783457D03*
X1791804D03*
X1805190D03*
G54D62*
X45449Y1074996D03*
X346629Y1218602D03*
X349458Y1221429D03*
X356156Y1215651D03*
X358985Y1218480D03*
X353328Y1212823D03*
X352287Y1224258D03*
X355116Y1227087D03*
X364642Y1224137D03*
X810415Y1212823D03*
X816072Y1218480D03*
X813243Y1215651D03*
X806545Y1221429D03*
X803716Y1218602D03*
X809374Y1224258D03*
X812203Y1227087D03*
X821729Y1224137D03*
X892139Y1083999D03*
X956116D03*
X1263631Y1221429D03*
X1260802Y1218602D03*
X1270329Y1215651D03*
X1267501Y1212823D03*
X1266460Y1224258D03*
X1269289Y1227087D03*
X1273158Y1218480D03*
X1278815Y1224137D03*
X1720718Y1221429D03*
X1717889Y1218602D03*
X1724588Y1212823D03*
X1723547Y1224258D03*
X1727416Y1215651D03*
X1730245Y1218480D03*
X1735902Y1224137D03*
X1726376Y1227087D03*
X1800096Y1084485D03*
G54D128*
X406996Y1543915D03*
X921343Y363254D03*
G54D17*
X8460Y111710D03*
X16728D03*
X8460Y128836D03*
X16728D03*
X202994Y64722D03*
X211262D03*
X202994Y81848D03*
X211262D03*
X305356Y64722D03*
Y81848D03*
X313624Y64722D03*
Y81848D03*
X360982Y1146842D03*
X352714D03*
X360982Y1163968D03*
X352714D03*
X557719Y64722D03*
X565987D03*
X557719Y81848D03*
X565987D03*
X660081Y64722D03*
X668349D03*
X660081Y81848D03*
X668349D03*
X762443Y64722D03*
Y81848D03*
X770711Y64722D03*
Y81848D03*
X809801Y1146842D03*
Y1163968D03*
X830829Y935779D03*
Y952905D03*
X818069Y1146842D03*
Y1163968D03*
X839097Y935779D03*
Y952905D03*
X864805Y64722D03*
Y81848D03*
X873073Y64722D03*
Y81848D03*
X1014805Y64722D03*
X1023073D03*
X1014805Y81848D03*
X1023073D03*
X1117167Y64722D03*
Y81848D03*
X1125435Y64722D03*
Y81848D03*
X1219529Y64722D03*
Y81848D03*
X1227797Y64722D03*
Y81848D03*
X1266887Y1146842D03*
Y1163968D03*
X1275155Y1146842D03*
Y1163968D03*
X1471892Y64722D03*
X1480160D03*
X1471892Y81848D03*
X1480160D03*
X1574254Y64722D03*
Y81848D03*
X1582522Y64722D03*
Y81848D03*
X1594312Y1479190D03*
Y1496316D03*
X1602580Y1479190D03*
Y1496316D03*
X1676616Y64722D03*
Y81848D03*
X1684884Y64722D03*
Y81848D03*
X1723974Y1146842D03*
Y1163968D03*
X1732242Y1146842D03*
Y1163968D03*
X1778978Y64722D03*
X1787246D03*
X1778978Y81848D03*
X1787246D03*
G54D146*
X436004Y566055D03*
Y610547D03*
G54D218*
X1015674Y1396137D03*
X1023862D03*
G54D227*
X1298720Y807880D03*
Y802762D03*
X1305412Y807880D03*
Y802762D03*
G54D53*
X39423Y163264D03*
X48085Y167004D03*
X39423Y170744D03*
G54D44*
X37955Y1138071D03*
Y1180649D03*
X885145Y1147074D03*
Y1189652D03*
X949122Y1147074D03*
Y1189652D03*
X1793102Y1147560D03*
Y1190138D03*
G54D173*
X814069Y848569D03*
Y859199D03*
X826165Y848651D03*
X828134D03*
X830102D03*
X819975Y848569D03*
X816038D03*
X818006D03*
X826165Y859281D03*
X828134D03*
X830102D03*
X816038Y859199D03*
X818006D03*
X819975D03*
X832071Y848651D03*
Y859281D03*
G54D191*
X888691Y684403D03*
X897291D03*
X918361Y720570D03*
X926961D03*
G54D80*
X64242Y1434190D03*
X68664Y1483644D03*
X414025Y1509344D03*
X429730Y1457016D03*
X420388Y1467886D03*
G54D119*
X393536Y780320D03*
X395505D03*
X397473D03*
X399442D03*
X401410D03*
X403379D03*
X405347D03*
X407316D03*
X409284D03*
X411253D03*
X413221D03*
X415190D03*
X417158D03*
X419127D03*
X421095D03*
X423064D03*
X1766236Y912920D03*
X1768205D03*
X1770173D03*
X1772142D03*
X1774110D03*
X1776079D03*
X1778047D03*
X1780016D03*
X1781984D03*
X1783953D03*
X1785921D03*
X1787890D03*
X1789858D03*
X1791827D03*
X1793795D03*
X1795764D03*
G54D26*
X12422Y214006D03*
Y207006D03*
X27201Y155151D03*
Y162151D03*
X48949Y826718D03*
Y833718D03*
X50602Y971296D03*
Y978296D03*
X70236Y281155D03*
Y274155D03*
X62733Y531055D03*
Y538055D03*
X61555Y971296D03*
Y978296D03*
X57909Y985176D03*
Y992176D03*
X68342Y985014D03*
Y992014D03*
X70658Y215535D03*
Y222535D03*
X72643Y448919D03*
Y455919D03*
X72564Y484311D03*
Y491311D03*
X114784Y214006D03*
Y207006D03*
X123599Y112672D03*
Y119672D03*
X145882Y586056D03*
Y579056D03*
X152882Y586056D03*
Y579056D03*
X173020Y215535D03*
Y222535D03*
X172598Y281155D03*
Y274155D03*
X225961Y112672D03*
Y119672D03*
X217146Y214006D03*
Y207006D03*
X275382Y215535D03*
Y222535D03*
X274960Y281155D03*
Y274155D03*
X328323Y112672D03*
Y119672D03*
X319508Y214006D03*
Y207006D03*
X317549Y419937D03*
Y426937D03*
Y439431D03*
Y446431D03*
X362042Y441402D03*
Y434402D03*
X358933Y488017D03*
Y481017D03*
X377744Y215535D03*
Y222535D03*
X377322Y281155D03*
Y274155D03*
X371919Y441002D03*
Y448002D03*
X379919Y441002D03*
Y448002D03*
X399853Y391802D03*
Y398802D03*
X405121Y930778D03*
X397121D03*
X405121Y937778D03*
X397121D03*
X400004Y1198971D03*
Y1191971D03*
X413121Y930778D03*
X421121D03*
X413121Y937778D03*
X421121D03*
X426934Y1198971D03*
Y1191971D03*
X431764Y507650D03*
Y500650D03*
X453864Y1198971D03*
Y1191971D03*
X469509Y214006D03*
Y207006D03*
X473206Y1198971D03*
Y1191971D03*
X478324Y112672D03*
Y119672D03*
X500136Y1198971D03*
Y1191971D03*
X519819Y531055D03*
Y538055D03*
X527745Y215535D03*
Y222535D03*
X527323Y281155D03*
Y274155D03*
X527729Y445919D03*
Y452919D03*
X529650Y484311D03*
Y491311D03*
X527066Y1198971D03*
Y1191971D03*
X571871Y214006D03*
Y207006D03*
X566003Y940807D03*
Y947807D03*
X580686Y112672D03*
Y119672D03*
X602968Y586056D03*
Y579056D03*
X609968Y586056D03*
Y579056D03*
X630107Y215535D03*
Y222535D03*
X629685Y281155D03*
Y274155D03*
X683048Y112672D03*
Y119672D03*
X674233Y214006D03*
Y207006D03*
X732469Y215535D03*
Y222535D03*
X732047Y281155D03*
Y274155D03*
X776595Y214006D03*
Y207006D03*
X780434Y419937D03*
Y426937D03*
X773434Y419937D03*
Y426937D03*
X785410Y112672D03*
Y119672D03*
X816019Y476017D03*
Y483017D03*
X834831Y215535D03*
Y222535D03*
X834409Y281155D03*
Y274155D03*
X858882Y467675D03*
Y460675D03*
X866135Y985334D03*
Y992334D03*
X859242Y985334D03*
Y992334D03*
X852117Y985334D03*
Y992334D03*
X874882Y467675D03*
Y460675D03*
X866882Y467675D03*
Y460675D03*
X895179Y408143D03*
Y415143D03*
X907953Y998291D03*
Y1005291D03*
X927261Y199177D03*
Y192177D03*
X935410Y112672D03*
Y119672D03*
X955165Y996486D03*
Y1003486D03*
X948285Y996437D03*
Y1003437D03*
X976906Y531055D03*
Y538055D03*
X979129Y997259D03*
Y1004259D03*
X967028Y996535D03*
Y1003535D03*
X984831Y215535D03*
Y222535D03*
X984409Y281155D03*
Y274155D03*
X986816Y448919D03*
Y455919D03*
X986737Y484311D03*
Y491311D03*
X1007619Y937822D03*
Y944822D03*
X1037772Y112672D03*
Y119672D03*
X1028957Y214006D03*
Y207006D03*
X1060055Y586056D03*
Y579056D03*
X1067055Y586056D03*
Y579056D03*
X1087193Y215535D03*
Y222535D03*
X1086771Y281155D03*
Y274155D03*
X1140134Y112672D03*
Y119672D03*
X1131319Y214006D03*
Y207006D03*
X1189555Y215535D03*
Y222535D03*
X1189133Y281155D03*
Y274155D03*
X1233681Y214006D03*
Y207006D03*
X1231722Y419937D03*
Y426937D03*
Y439431D03*
Y446431D03*
X1242496Y112672D03*
Y119672D03*
X1276215Y441402D03*
Y434402D03*
X1286092Y441002D03*
Y448002D03*
X1273106Y488017D03*
Y481017D03*
X1291917Y215535D03*
Y222535D03*
X1291495Y281155D03*
Y274155D03*
X1294092Y441002D03*
Y448002D03*
X1314026Y391802D03*
Y398802D03*
X1314178Y1198971D03*
Y1191971D03*
X1341108Y1198971D03*
Y1191971D03*
X1368038Y1198971D03*
Y1191971D03*
X1383682Y214006D03*
Y207006D03*
X1392497Y112672D03*
Y119672D03*
X1387380Y1198971D03*
Y1191971D03*
X1414310Y1198971D03*
Y1191971D03*
X1433993Y531055D03*
Y538055D03*
X1441918Y215535D03*
Y222535D03*
X1441496Y281155D03*
Y274155D03*
X1441903Y445919D03*
Y452919D03*
X1443824Y484311D03*
Y491311D03*
X1441240Y1198971D03*
Y1191971D03*
X1494859Y112672D03*
Y119672D03*
X1486044Y214006D03*
Y207006D03*
X1517142Y586056D03*
Y579056D03*
X1524142Y586056D03*
Y579056D03*
X1544280Y215535D03*
Y222535D03*
X1543858Y281155D03*
Y274155D03*
X1597221Y112672D03*
Y119672D03*
X1588406Y214006D03*
Y207006D03*
X1646642Y215535D03*
Y222535D03*
X1646220Y281155D03*
Y274155D03*
X1690768Y214006D03*
Y207006D03*
X1688809Y419937D03*
Y426937D03*
Y439431D03*
Y446431D03*
X1699583Y112672D03*
Y119672D03*
X1743179Y441002D03*
X1733302Y441402D03*
Y434402D03*
X1743179Y448002D03*
X1730193Y488017D03*
Y481017D03*
X1749004Y215535D03*
Y222535D03*
X1748582Y281155D03*
Y274155D03*
X1751179Y441002D03*
Y448002D03*
X1771113Y391802D03*
Y398802D03*
X1782263Y968660D03*
Y975660D03*
X1804012Y997858D03*
Y1004858D03*
X1817965Y997858D03*
Y1004858D03*
X1811133Y997858D03*
Y1004858D03*
X1824814Y997895D03*
Y1004895D03*
G54D164*
X729727Y736204D03*
Y743684D03*
X740357D03*
Y739944D03*
Y736204D03*
X1041602Y1334065D03*
X1032272Y1330325D03*
Y1337805D03*
G54D182*
X855862Y1447668D03*
Y1457510D03*
Y1451605D03*
Y1455542D03*
Y1449636D03*
Y1453573D03*
X873480Y1447668D03*
Y1451605D03*
Y1457510D03*
Y1453573D03*
Y1455542D03*
Y1449636D03*
X897862Y1447668D03*
Y1457510D03*
Y1451605D03*
Y1455542D03*
Y1449636D03*
Y1453573D03*
X915480Y1447668D03*
Y1451605D03*
Y1457510D03*
Y1453573D03*
Y1455542D03*
Y1449636D03*
G54D137*
X425820Y750005D03*
Y748036D03*
Y765753D03*
Y763784D03*
Y761816D03*
Y759847D03*
Y757879D03*
Y755910D03*
Y753942D03*
Y751973D03*
Y777564D03*
Y775595D03*
Y773627D03*
Y771658D03*
Y769690D03*
Y767721D03*
X1798520Y880636D03*
Y896384D03*
Y894416D03*
Y892447D03*
Y890479D03*
Y888510D03*
Y886542D03*
Y884573D03*
Y882605D03*
Y910164D03*
Y908195D03*
Y906227D03*
Y904258D03*
Y902290D03*
Y900321D03*
Y898353D03*
G54D209*
X942586Y1499857D03*
G54D155*
X522524Y699411D03*
G54D219*
X1019768Y1411117D03*
G54D156*
X537944Y760782D03*
Y767474D03*
X546606D03*
Y760782D03*
X1511365Y894825D03*
X1502703Y888133D03*
Y894825D03*
X1511365Y888133D03*
G54D18*
X13874Y111710D03*
X11314D03*
X13874Y128836D03*
X11314D03*
X208408Y64722D03*
X205848D03*
X208408Y81848D03*
X205848D03*
X310770Y64722D03*
X308210D03*
X310770Y81848D03*
X308210D03*
X355568Y1146842D03*
X358128D03*
X355568Y1163968D03*
X358128D03*
X563133Y64722D03*
X560573D03*
X563133Y81848D03*
X560573D03*
X665495Y64722D03*
X662935D03*
X665495Y81848D03*
X662935D03*
X765297Y64722D03*
Y81848D03*
X767857Y64722D03*
Y81848D03*
X812655Y1146842D03*
X815215D03*
X812655Y1163968D03*
X815215D03*
X836243Y935779D03*
X833683D03*
Y952905D03*
X836243D03*
X870219Y64722D03*
X867659D03*
X870219Y81848D03*
X867659D03*
X1020219Y64722D03*
X1017659D03*
X1020219Y81848D03*
X1017659D03*
X1122581Y64722D03*
X1120021D03*
X1122581Y81848D03*
X1120021D03*
X1224943Y64722D03*
X1222383D03*
X1224943Y81848D03*
X1222383D03*
X1269741Y1146842D03*
Y1163968D03*
X1272301Y1146842D03*
Y1163968D03*
X1477306Y64722D03*
X1474746D03*
X1477306Y81848D03*
X1474746D03*
X1577108Y64722D03*
Y81848D03*
X1579668Y64722D03*
Y81848D03*
X1599726Y1479190D03*
X1597166D03*
X1599726Y1496316D03*
X1597166D03*
X1682030Y64722D03*
X1679470D03*
X1682030Y81848D03*
X1679470D03*
X1726828Y1146842D03*
X1729388D03*
X1726828Y1163968D03*
X1729388D03*
X1784392Y64722D03*
X1781832D03*
X1784392Y81848D03*
X1781832D03*
G54D192*
X889303Y691560D03*
X895751Y696678D03*
X889303Y694119D03*
X895751Y691560D03*
X889303Y696678D03*
X895751Y694119D03*
G54D90*
X103958Y1021783D03*
Y1014303D03*
X561045Y1021783D03*
Y1014303D03*
X1018131Y1021783D03*
Y1014303D03*
X1475218Y1021783D03*
Y1014303D03*
G54D72*
X67159Y560848D03*
X85663D03*
X346698Y422440D03*
X365202D03*
X524245Y560848D03*
X542749D03*
X839129Y429363D03*
X857633D03*
X981332Y560848D03*
X999836D03*
X1260871Y422440D03*
X1279375D03*
X1438419Y560848D03*
X1456923D03*
X1717958Y422440D03*
X1736462D03*
G54D36*
X24792Y1072879D03*
Y1091383D03*
X62945Y170686D03*
Y189190D03*
X165307Y170686D03*
Y189190D03*
X267669Y170686D03*
Y189190D03*
X370031Y170686D03*
Y189190D03*
X414809Y951287D03*
Y969791D03*
X520032Y170686D03*
Y189190D03*
X622394Y170686D03*
Y189190D03*
X724756Y170686D03*
Y189190D03*
X827118Y170686D03*
Y189190D03*
X871249Y1081804D03*
Y1100308D03*
X935382Y1081609D03*
Y1100113D03*
X977118Y170686D03*
Y189190D03*
X1079480Y170686D03*
Y189190D03*
X1181842Y170686D03*
Y189190D03*
X1284204Y170686D03*
Y189190D03*
X1434205Y170686D03*
Y189190D03*
X1536567Y170686D03*
Y189190D03*
X1638929Y170686D03*
Y189190D03*
X1741291Y170686D03*
Y189190D03*
X1779439Y1082446D03*
Y1100950D03*
G54D54*
X45643Y454376D03*
Y461462D03*
X246031Y633786D03*
Y640872D03*
X485485Y421374D03*
Y428460D03*
X500729Y451376D03*
Y458462D03*
X703117Y633786D03*
Y640872D03*
X943111Y242721D03*
Y249807D03*
X959816Y454376D03*
Y461462D03*
X1160204Y633786D03*
Y640872D03*
X1292500Y938043D03*
Y930957D03*
X1414903Y451376D03*
Y458462D03*
X1429546Y1508327D03*
Y1515413D03*
X1600410Y1456276D03*
Y1463362D03*
X1617291Y633786D03*
Y640872D03*
G54D81*
X68689Y1597855D03*
Y1618721D03*
X73689Y1597855D03*
X78689D03*
X83689D03*
Y1618721D03*
X78689D03*
X73689D03*
X1758820Y1604357D03*
X1763820D03*
X1768820D03*
X1773820D03*
X1758820Y1625223D03*
X1773820D03*
X1768820D03*
X1763820D03*
G54D129*
X406996Y1534417D03*
X403059D03*
X405028D03*
X401090D03*
X408964D03*
X406996Y1553413D03*
X408964D03*
X405028D03*
X403059D03*
X401090D03*
X412902Y1534417D03*
X410933D03*
Y1553413D03*
X412902D03*
X927249Y353756D03*
X921343D03*
X917406D03*
X925280D03*
X919375D03*
X915437D03*
X923311D03*
X921343Y372752D03*
X923311D03*
X919375D03*
X917406D03*
X915437D03*
X925280D03*
X927249D03*
G54D174*
X814800Y876864D03*
Y885526D03*
X826804Y878504D03*
X831922D03*
X829363D03*
X819918Y876864D03*
X831922Y887166D03*
X826804D03*
X819918Y885526D03*
X817359D03*
X1285941Y913331D03*
Y904669D03*
X1291059Y913331D03*
Y904669D03*
X1288500D03*
X1443428Y1023064D03*
X1438310D03*
Y1014402D03*
X1443428D03*
X1440869D03*
G54D228*
X1439234Y938291D03*
Y940850D03*
Y943410D03*
Y945969D03*
X1453800Y943410D03*
Y940850D03*
Y938291D03*
Y945969D03*
G54D183*
X877727Y722060D03*
Y727178D03*
X870727D03*
Y722060D03*
Y724619D03*
G54D138*
X421962Y875715D03*
G54D27*
X18463Y247292D03*
Y253198D03*
Y267292D03*
Y273198D03*
X25549Y247292D03*
Y253198D03*
Y267292D03*
Y273198D03*
X82918Y146461D03*
Y152367D03*
X84679Y1009260D03*
Y1015166D03*
X90004Y146461D03*
Y152367D03*
X91765Y1009260D03*
Y1015166D03*
X127911Y247292D03*
X120825D03*
Y253198D03*
X127911D03*
X192366Y146461D03*
X185280D03*
Y152367D03*
X192366D03*
X230273Y247292D03*
X223187D03*
Y253198D03*
X230273D03*
X294728Y146461D03*
X287642D03*
Y152367D03*
X294728D03*
X325549Y247292D03*
Y253198D03*
X332635Y247292D03*
Y253198D03*
X408758Y468607D03*
Y474513D03*
X415844Y468607D03*
Y474513D03*
X437643Y146461D03*
Y152367D03*
X444729Y146461D03*
Y152367D03*
X482636Y247292D03*
X475550D03*
Y253198D03*
X482636D03*
X540005Y146461D03*
Y152367D03*
X547091Y146461D03*
Y152367D03*
X548852Y1009260D03*
X541766D03*
Y1015166D03*
X548852D03*
X584998Y247292D03*
X577912D03*
Y253198D03*
X584998D03*
X649453Y146461D03*
X642367D03*
Y152367D03*
X649453D03*
X680274Y247292D03*
Y253198D03*
X687360Y247292D03*
Y253198D03*
X744729Y146461D03*
Y152367D03*
X751815Y146461D03*
Y152367D03*
X782636Y247292D03*
Y253198D03*
X789722Y247292D03*
Y253198D03*
X879997Y480350D03*
X872911D03*
Y486256D03*
X879997D03*
X894729Y146461D03*
Y152367D03*
X901815Y146461D03*
Y152367D03*
X1004177Y146461D03*
X997091D03*
Y152367D03*
X1004177D03*
X1005938Y1009260D03*
X998852D03*
Y1015166D03*
X1005938D03*
X1042084Y247292D03*
X1034998D03*
Y253198D03*
X1042084D03*
X1106539Y146461D03*
X1099453D03*
Y152367D03*
X1106539D03*
X1137360Y247292D03*
Y253198D03*
X1144446Y247292D03*
Y253198D03*
X1201815Y146461D03*
Y152367D03*
X1208901Y146461D03*
Y152367D03*
X1246808Y247292D03*
X1239722D03*
Y253198D03*
X1246808D03*
X1267792Y902371D03*
Y908277D03*
X1274878Y902371D03*
Y908277D03*
X1330017Y468607D03*
X1322931D03*
Y474513D03*
X1330017D03*
X1351816Y146461D03*
Y152367D03*
X1358902Y146461D03*
Y152367D03*
X1396809Y247292D03*
X1389723D03*
Y253198D03*
X1396809D03*
X1421368Y1537432D03*
Y1543338D03*
X1428454D03*
Y1537432D03*
X1420995Y1558072D03*
X1428081D03*
X1420995Y1563978D03*
X1428081D03*
X1461264Y146461D03*
X1454178D03*
Y152367D03*
X1461264D03*
X1463025Y1009260D03*
X1455939D03*
Y1015166D03*
X1463025D03*
X1492085Y247292D03*
Y253198D03*
X1499171Y247292D03*
Y253198D03*
X1556540Y146461D03*
Y152367D03*
X1563626Y146461D03*
Y152367D03*
X1594447Y247292D03*
Y253198D03*
X1601533Y247292D03*
Y253198D03*
X1627155Y699930D03*
Y705836D03*
Y717830D03*
X1627455Y732430D03*
X1627155Y723736D03*
X1627455Y738336D03*
Y750630D03*
Y756536D03*
X1623741Y780736D03*
Y774830D03*
X1616655D03*
Y780736D03*
X1623541Y793436D03*
Y787530D03*
X1616455D03*
Y793436D03*
X1623241Y807536D03*
Y801630D03*
X1616155D03*
Y807536D03*
X1623341Y815730D03*
X1616255D03*
X1623341Y821636D03*
X1616255D03*
X1634241Y699930D03*
Y705836D03*
Y717830D03*
X1634541Y732430D03*
X1634241Y723736D03*
X1634541Y738336D03*
Y750630D03*
Y756536D03*
X1658902Y146461D03*
Y152367D03*
X1665988Y146461D03*
Y152367D03*
X1703895Y247292D03*
X1696809D03*
Y253198D03*
X1703895D03*
X1787104Y468607D03*
X1780018D03*
Y474513D03*
X1787104D03*
X1790264Y1446668D03*
Y1440762D03*
X1783178D03*
Y1446668D03*
X1790141Y1478858D03*
Y1472952D03*
X1783055D03*
Y1478858D03*
G54D147*
X438244Y1059069D03*
Y1080329D03*
X471246Y1059069D03*
Y1080329D03*
X1352418Y1059069D03*
Y1080329D03*
X1385420Y1059069D03*
Y1080329D03*
G54D63*
X49754Y1079154D03*
X51723D03*
X49754Y1090178D03*
X51723D03*
X55660D03*
Y1079154D03*
X53691D03*
Y1090178D03*
X76452Y582336D03*
X70546D03*
X74483D03*
X72515D03*
X70546Y593360D03*
X72515D03*
X76452D03*
X74483D03*
X86992Y177338D03*
X92898D03*
X90929D03*
X88961D03*
X92898Y188362D03*
X86992D03*
X88961D03*
X90929D03*
X189354Y177338D03*
X195260D03*
X193291D03*
X191323D03*
X195260Y188362D03*
X189354D03*
X191323D03*
X193291D03*
X291716Y177338D03*
X295653D03*
X293685D03*
X291716Y188362D03*
X293685D03*
X295653D03*
X297622Y177338D03*
Y188362D03*
X360480Y389013D03*
X356543D03*
X358512D03*
X356543Y400037D03*
X358512D03*
X360480D03*
X362449Y389013D03*
Y400037D03*
X384856Y952115D03*
X390762D03*
X388793D03*
X386825D03*
X390762Y963139D03*
X384856D03*
X386825D03*
X388793D03*
X394078Y177338D03*
X399984D03*
X398015D03*
X396047D03*
X399984Y188362D03*
X394078D03*
X396047D03*
X398015D03*
X409101Y1110233D03*
X419731D03*
X425046D03*
X416187D03*
X412644D03*
X421502D03*
X423274D03*
X417959D03*
X410872D03*
X414416D03*
X441229D03*
X451859D03*
X457174D03*
X448315D03*
X444772D03*
X453630D03*
X455402D03*
X450087D03*
X443000D03*
X446544D03*
X474688D03*
X485318D03*
X490633D03*
X481774D03*
X478231D03*
X487089D03*
X488861D03*
X483546D03*
X476459D03*
X480003D03*
X506816D03*
X517446D03*
X522761D03*
X513902D03*
X510359D03*
X519217D03*
X520989D03*
X515674D03*
X508587D03*
X512131D03*
X533538Y582336D03*
X527632D03*
X531569D03*
X529601D03*
X527632Y593360D03*
X529601D03*
X533538D03*
X531569D03*
X544079Y177338D03*
X549985D03*
X548016D03*
X546048D03*
X549985Y188362D03*
X544079D03*
X546048D03*
X548016D03*
X646441Y177338D03*
X652347D03*
X650378D03*
X648410D03*
X652347Y188362D03*
X646441D03*
X648410D03*
X650378D03*
X748803Y177338D03*
Y188362D03*
X754709Y177338D03*
X752740D03*
X750772D03*
X754709Y188362D03*
X750772D03*
X752740D03*
X851165Y177338D03*
X857071D03*
X855102D03*
X853134D03*
X857071Y188362D03*
X851165D03*
X853134D03*
X855102D03*
X857298Y408038D03*
X863204D03*
X859267D03*
X863204Y397014D03*
X861235Y408038D03*
Y397014D03*
X857298D03*
X859267D03*
X896444Y1088157D03*
Y1099181D03*
X902350Y1088157D03*
X900381D03*
X898413D03*
Y1099181D03*
X900381D03*
X902350D03*
X960421Y1088157D03*
Y1099181D03*
X966327Y1088157D03*
X964358D03*
X962390D03*
Y1099181D03*
X964358D03*
X966327D03*
X990625Y582336D03*
X984719D03*
X988656D03*
X986688D03*
X984719Y593360D03*
X986688D03*
X990625D03*
X988656D03*
X1001165Y177338D03*
X1007071D03*
X1005102D03*
X1003134D03*
X1007071Y188362D03*
X1001165D03*
X1003134D03*
X1005102D03*
X1103527Y177338D03*
X1107464D03*
X1105496D03*
X1103527Y188362D03*
X1105496D03*
X1107464D03*
X1109433Y177338D03*
Y188362D03*
X1205889Y177338D03*
X1211795D03*
X1209826D03*
X1207858D03*
X1211795Y188362D03*
X1205889D03*
X1207858D03*
X1209826D03*
X1276622Y389013D03*
X1274653D03*
X1270716D03*
X1272685D03*
X1270716Y400037D03*
X1276622D03*
X1272685D03*
X1274653D03*
X1308251Y177338D03*
X1314157D03*
X1312188D03*
X1310220D03*
X1314157Y188362D03*
X1308251D03*
X1310220D03*
X1312188D03*
X1323275Y1110233D03*
X1333905D03*
X1330361D03*
X1326818D03*
X1332133D03*
X1325046D03*
X1328590D03*
X1339220D03*
X1335676D03*
X1337448D03*
X1355403D03*
X1366033D03*
X1362489D03*
X1358946D03*
X1367804D03*
X1364261D03*
X1357174D03*
X1360718D03*
X1371348D03*
X1369576D03*
X1388862D03*
X1399492D03*
X1395948D03*
X1392405D03*
X1397720D03*
X1390633D03*
X1394177D03*
X1404807D03*
X1401263D03*
X1403035D03*
X1420990D03*
X1431620D03*
X1428076D03*
X1424533D03*
X1429848D03*
X1422761D03*
X1426305D03*
X1447712Y582336D03*
X1441806D03*
X1445743D03*
X1443775D03*
X1441806Y593360D03*
X1443775D03*
X1447712D03*
X1445743D03*
X1436935Y1110233D03*
X1433391D03*
X1435163D03*
X1458252Y177338D03*
X1464158D03*
X1462189D03*
X1460221D03*
X1464158Y188362D03*
X1458252D03*
X1460221D03*
X1462189D03*
X1560614Y177338D03*
X1562583D03*
X1560614Y188362D03*
X1562583D03*
X1566520Y177338D03*
X1564551D03*
X1566520Y188362D03*
X1564551D03*
X1662976Y177338D03*
X1668882D03*
X1666913D03*
X1664945D03*
X1668882Y188362D03*
X1662976D03*
X1664945D03*
X1666913D03*
X1733709Y389013D03*
X1731740D03*
X1727803D03*
X1729772D03*
X1727803Y400037D03*
X1733709D03*
X1729772D03*
X1731740D03*
X1765338Y177338D03*
X1771244D03*
X1769275D03*
X1767307D03*
X1771244Y188362D03*
X1765338D03*
X1767307D03*
X1769275D03*
X1804401Y1088643D03*
X1806370D03*
X1804401Y1099667D03*
X1806370D03*
X1810307Y1088643D03*
X1808338D03*
X1810307Y1099667D03*
X1808338D03*
G54D165*
X736702Y1431659D03*
Y1451659D03*
X747528Y1441659D03*
G54D45*
X34731Y1206917D03*
X427063Y634044D03*
X878421Y1215920D03*
X942398D03*
X1786378Y1216406D03*
G54D19*
X6305Y105001D03*
X13806Y242078D03*
X9836Y248371D03*
X13806Y262078D03*
X9836Y268371D03*
X9206Y1496782D03*
X6548Y1556883D03*
X22912Y51296D03*
Y55305D03*
X26820Y67527D03*
Y63527D03*
Y59527D03*
X24930Y106495D03*
X29448Y177448D03*
X21614Y206864D03*
X20785Y242078D03*
Y262078D03*
X30447Y250599D03*
Y270599D03*
X23570Y292608D03*
X31786Y281272D03*
X28490Y536726D03*
Y531726D03*
Y552726D03*
Y540726D03*
Y544726D03*
X30208Y629311D03*
Y625311D03*
X45417Y177606D03*
X38321Y478982D03*
Y483982D03*
Y487982D03*
Y499982D03*
Y491982D03*
X40615Y597393D03*
X47270Y631212D03*
X50240Y1072761D03*
X40707Y1093757D03*
X39543Y1248448D03*
X56265Y847718D03*
X68751Y843118D03*
X64600Y1091656D03*
X58301Y1213720D03*
X62419Y1544571D03*
X74291Y151540D03*
X77750Y168697D03*
X77945Y191941D03*
X79914Y224321D03*
X80292Y571614D03*
Y575614D03*
X69035Y575841D03*
X78830Y686107D03*
X94902Y149768D03*
X101838Y192665D03*
Y196665D03*
X101933Y204864D03*
X116168Y242078D03*
X112198Y252371D03*
X127301Y106495D03*
X123976Y206864D03*
X123147Y242078D03*
X132809Y250599D03*
X144204Y554555D03*
Y558555D03*
Y562555D03*
X151116Y382600D03*
Y463600D03*
X150484Y595588D03*
Y591588D03*
X150516Y603600D03*
X150484Y599588D03*
X150516Y611600D03*
Y619600D03*
X150484Y607588D03*
X150516Y615600D03*
Y623600D03*
Y627600D03*
Y637969D03*
Y641974D03*
X176653Y151540D03*
X180112Y168697D03*
X180307Y191941D03*
X182276Y224321D03*
X194014Y68581D03*
Y80581D03*
X197264Y149768D03*
X203339Y58013D03*
X199557Y114488D03*
X204200Y196665D03*
Y192665D03*
X204295Y204864D03*
X214560Y252371D03*
X229654Y106495D03*
X226338Y206864D03*
X218530Y242078D03*
X225509D03*
X230780Y384718D03*
Y380718D03*
Y392718D03*
Y396718D03*
Y400718D03*
Y404718D03*
Y408718D03*
Y412718D03*
X218316Y458800D03*
X227116Y553700D03*
X218516Y545800D03*
X227116Y557700D03*
X227560Y1474522D03*
X227559Y1478442D03*
Y1486442D03*
X229559Y1510442D03*
X229564Y1518578D03*
X235171Y250599D03*
X241941Y675832D03*
X246402Y816300D03*
X245402Y836800D03*
X246401Y1506058D03*
X249216Y453873D03*
Y458859D03*
X248401Y542712D03*
X248701Y1517958D03*
X279015Y151540D03*
X296376Y68581D03*
Y80581D03*
X282474Y168697D03*
X282669Y191941D03*
X284638Y224321D03*
X309197Y35007D03*
X305701Y58013D03*
X301919Y114488D03*
X299626Y149768D03*
X306562Y192665D03*
Y196665D03*
X306657Y204864D03*
X328700Y206864D03*
X320892Y242078D03*
X327871D03*
X316922Y252371D03*
X323973Y306652D03*
X315601Y545912D03*
Y626912D03*
X332016Y106495D03*
X337533Y250599D03*
X343941Y1146071D03*
X347541Y458334D03*
Y450334D03*
X357914Y1170370D03*
X351283Y1191599D03*
X368416Y488816D03*
X376102Y745300D03*
X374402Y764500D03*
X363984Y943480D03*
X372948Y959812D03*
Y955812D03*
Y951812D03*
Y963812D03*
Y967812D03*
Y971812D03*
X384836Y168697D03*
X385031Y191941D03*
X387000Y224321D03*
X388184Y470382D03*
X389711Y868286D03*
X384533Y1547700D03*
Y1555700D03*
X404281Y114488D03*
X408924Y192665D03*
Y196665D03*
X409019Y204864D03*
X404072Y331589D03*
Y335589D03*
X399817Y467560D03*
Y479560D03*
X402904Y889786D03*
X404481Y1446807D03*
X416991Y35983D03*
X415649Y425413D03*
X418189Y455301D03*
Y459101D03*
Y463101D03*
X421817Y474560D03*
X411305Y889551D03*
X410717Y1523296D03*
X424132Y1537088D03*
X424652Y1550211D03*
X429016Y151540D03*
X440689Y424601D03*
Y428101D03*
Y431601D03*
X449627Y149768D03*
X452675Y328285D03*
Y324685D03*
Y344033D03*
Y340433D03*
Y336159D03*
Y332559D03*
Y351907D03*
Y348307D03*
X453635Y464809D03*
Y472809D03*
X442956Y508999D03*
X450493Y638279D03*
X456301Y1002180D03*
Y1007180D03*
X453801Y1012325D03*
Y1016325D03*
X445607Y1022766D03*
Y1034266D03*
Y1030266D03*
X452685Y1043140D03*
X452608Y1047047D03*
X470893Y242078D03*
X466923Y252371D03*
X462919Y495669D03*
Y516609D03*
X482017Y106495D03*
X478701Y206864D03*
X477872Y242078D03*
X487534Y250599D03*
X485426Y387089D03*
Y391589D03*
X485576Y536726D03*
Y531726D03*
Y544726D03*
Y540726D03*
X487294Y629311D03*
Y625311D03*
X478878Y652906D03*
X482301Y1031680D03*
X491301Y1032180D03*
X495407Y478982D03*
Y483982D03*
Y487982D03*
Y499982D03*
Y491982D03*
X497701Y597393D03*
X504356Y631212D03*
X499619Y660441D03*
X505110Y989235D03*
X501107Y1004766D03*
Y996766D03*
Y1008766D03*
X500974Y1020258D03*
X501107Y1030766D03*
X515723Y749443D03*
X509107Y1000766D03*
Y1004766D03*
Y996766D03*
Y1016266D03*
Y1020266D03*
Y1030766D03*
X531378Y151540D03*
X534837Y168697D03*
X535032Y191941D03*
X537001Y224321D03*
X535702Y345723D03*
Y359223D03*
Y354723D03*
Y350223D03*
Y363723D03*
Y377223D03*
Y372723D03*
Y368223D03*
Y386223D03*
Y390723D03*
X537378Y571614D03*
Y575614D03*
X526121Y575841D03*
X532540Y779889D03*
X529202Y840700D03*
X548739Y68581D03*
Y80581D03*
X554282Y114488D03*
X551989Y149768D03*
X545702Y345723D03*
Y350223D03*
Y359223D03*
Y354723D03*
Y377223D03*
Y372723D03*
Y368223D03*
Y363723D03*
Y381723D03*
X549989Y684509D03*
Y700509D03*
Y688509D03*
Y692509D03*
Y696509D03*
Y704509D03*
Y708509D03*
Y712509D03*
Y716509D03*
Y720509D03*
X552642Y841388D03*
X558064Y58013D03*
X558925Y192665D03*
Y196665D03*
X559020Y204864D03*
X569285Y252371D03*
X567519Y747079D03*
X584379Y106495D03*
X581063Y206864D03*
X580234Y242078D03*
X573255D03*
X585805Y957207D03*
X573319Y961807D03*
X585448Y1509687D03*
X589896Y250599D03*
X601290Y554555D03*
Y558555D03*
Y562555D03*
X595001Y1493658D03*
Y1497558D03*
X595101Y1501458D03*
X591197Y1505794D03*
X608202Y382600D03*
Y463600D03*
X607570Y595588D03*
Y591588D03*
X607602Y603600D03*
X607570Y599588D03*
X607602Y611600D03*
Y619600D03*
X607570Y607588D03*
X607602Y615600D03*
Y623600D03*
Y627600D03*
Y637969D03*
Y641974D03*
X633740Y151540D03*
X637199Y168697D03*
X637394Y191941D03*
X651101Y68581D03*
Y80581D03*
X639363Y224321D03*
X660426Y58013D03*
X656644Y114488D03*
X654351Y149768D03*
X661287Y192665D03*
Y196665D03*
X661382Y204864D03*
X655843Y666275D03*
X657959Y710129D03*
X683425Y206864D03*
X675617Y242078D03*
X682596D03*
X671647Y252371D03*
X675402Y458800D03*
X684202Y553700D03*
X675602Y545800D03*
X684202Y557700D03*
X675602Y558800D03*
Y562800D03*
X686741Y106495D03*
X692258Y250599D03*
X687866Y384718D03*
Y380718D03*
Y392718D03*
Y396718D03*
Y400718D03*
Y404718D03*
Y408718D03*
Y412718D03*
X699027Y675832D03*
X706302Y453873D03*
Y458859D03*
X705487Y542712D03*
X713291Y696718D03*
X717212Y779958D03*
X710366Y783453D03*
X724862Y756137D03*
Y764137D03*
Y768137D03*
Y772137D03*
X732916Y1606600D03*
X732267Y1634485D03*
X732283Y1630030D03*
X736102Y151540D03*
X739561Y168697D03*
X739756Y191941D03*
X741725Y224321D03*
X762788Y58013D03*
X753463Y68581D03*
Y80581D03*
X759006Y114488D03*
X756713Y149768D03*
X763649Y196665D03*
Y192665D03*
X763744Y204864D03*
X777979Y242078D03*
X774009Y252371D03*
X781059Y306652D03*
X781608Y442498D03*
X781640Y450510D03*
Y446510D03*
X772687Y545912D03*
Y626912D03*
X780265Y1427432D03*
Y1431432D03*
Y1439432D03*
X778519Y1458066D03*
X771648Y1449870D03*
X789103Y106495D03*
X785787Y206864D03*
X784958Y242078D03*
X794620Y250599D03*
X796360Y1436559D03*
X804627Y444334D03*
Y452334D03*
X808840Y836919D03*
X812340Y893419D03*
X801028Y1146071D03*
X814958Y1171120D03*
X803360Y1436559D03*
X805021Y1476616D03*
X825502Y483816D03*
X827016Y758500D03*
Y762500D03*
Y780500D03*
Y776500D03*
Y794500D03*
Y798500D03*
Y812500D03*
Y816500D03*
X819250Y830038D03*
X816840Y900919D03*
X831220Y1444849D03*
X841923Y168697D03*
X842118Y191941D03*
X844087Y224321D03*
X845270Y465382D03*
X842801Y831558D03*
X836332Y839953D03*
X842873Y839292D03*
X839974Y879459D03*
X842761Y875507D03*
X840284Y871459D03*
X839974Y883459D03*
X841194Y892564D03*
X839881Y887490D03*
X835016Y901500D03*
X842247Y1440859D03*
X842260Y1448959D03*
Y1444959D03*
Y1457959D03*
X855825Y68581D03*
Y80581D03*
X861368Y114488D03*
X863970Y491303D03*
Y479303D03*
X860777Y713170D03*
Y705170D03*
X861516Y768000D03*
Y786000D03*
Y804000D03*
Y822000D03*
X853744Y831469D03*
X853775Y843459D03*
Y847459D03*
Y839459D03*
Y863459D03*
Y859459D03*
Y855459D03*
Y851459D03*
Y867459D03*
Y879459D03*
Y875459D03*
Y871459D03*
Y892959D03*
Y883459D03*
Y887759D03*
X865150Y58013D03*
X866011Y192665D03*
Y196665D03*
X866106Y204864D03*
X880493Y309368D03*
Y305368D03*
Y313368D03*
Y325368D03*
Y321368D03*
Y317368D03*
Y329368D03*
X872600Y337342D03*
X880493D03*
Y333368D03*
X869584Y554703D03*
Y558703D03*
Y574703D03*
Y586828D03*
X869010Y698388D03*
X878777Y686970D03*
Y698970D03*
X886102Y151540D03*
X885970Y486303D03*
X892516Y529633D03*
X883777Y718570D03*
X896930Y1081764D03*
X887397Y1102760D03*
X883233Y1257451D03*
X883760Y1440859D03*
Y1448859D03*
Y1464859D03*
X883735Y1452663D03*
X883760Y1472859D03*
X906713Y149768D03*
X899276Y362369D03*
Y370369D03*
X910975Y441754D03*
X913515Y471642D03*
Y479442D03*
Y475442D03*
X910669Y547348D03*
X906977Y683770D03*
Y695770D03*
Y699770D03*
X911290Y1104659D03*
Y1100659D03*
X901991Y1222723D03*
X927668Y305255D03*
X916861Y304585D03*
X926168Y561578D03*
Y565578D03*
X926152Y585578D03*
Y589578D03*
X926168Y594329D03*
Y598329D03*
X920966Y704111D03*
X921744Y1472100D03*
X939103Y106495D03*
X936453Y192035D03*
X942659Y236866D03*
X944605Y316739D03*
X938693Y351281D03*
X936015Y440942D03*
Y444442D03*
Y447942D03*
X942663Y536726D03*
Y531726D03*
Y544726D03*
Y540726D03*
X944381Y629311D03*
Y625311D03*
X944786Y878216D03*
X936386Y883790D03*
X936388Y887508D03*
X944930Y899890D03*
X952494Y478982D03*
Y483982D03*
Y487982D03*
Y499982D03*
Y491982D03*
X954788Y597393D03*
X961443Y631212D03*
X949700Y792505D03*
X954573Y846665D03*
X947659Y846635D03*
X953214Y870278D03*
X960907Y1081764D03*
X951374Y1102760D03*
X947210Y1257451D03*
X978122Y343112D03*
Y346612D03*
X975267Y1100659D03*
Y1104659D03*
X965968Y1222723D03*
X988464Y151540D03*
X991923Y168697D03*
X992118Y191941D03*
X994087Y224321D03*
X979641Y338972D03*
Y331972D03*
X994465Y571614D03*
Y575614D03*
X983208Y575841D03*
X979637Y848597D03*
X981719Y837159D03*
X983951Y1104622D03*
X983988Y1100302D03*
X1005825Y68581D03*
Y80581D03*
X1009075Y149768D03*
X1008687Y196620D03*
X1011024Y1353714D03*
X1010977Y1363533D03*
X1010999Y1372734D03*
X1010994Y1376752D03*
X1015150Y58013D03*
X1011368Y114488D03*
X1016011Y196665D03*
Y192665D03*
X1016106Y204864D03*
X1026371Y252371D03*
X1015219Y837659D03*
X1014935Y958822D03*
X1041465Y106495D03*
X1038149Y206864D03*
X1030341Y242078D03*
X1037320D03*
X1030004Y847222D03*
X1027421Y954222D03*
X1046982Y250599D03*
X1055741Y314539D03*
Y322843D03*
Y328156D03*
Y319243D03*
X1055628Y339509D03*
X1055741Y331756D03*
X1055220Y360151D03*
Y364276D03*
X1058377Y554555D03*
Y558555D03*
Y562555D03*
X1065289Y382600D03*
Y463600D03*
X1064657Y595588D03*
Y591588D03*
X1064689Y603600D03*
X1064657Y599588D03*
X1064689Y611600D03*
Y619600D03*
X1064657Y607588D03*
X1064689Y615600D03*
Y623600D03*
Y627600D03*
Y637969D03*
Y641974D03*
X1090826Y151540D03*
X1108187Y68581D03*
Y80581D03*
X1094285Y168697D03*
X1094480Y191941D03*
X1096449Y224321D03*
X1117512Y58013D03*
X1113730Y114488D03*
X1111437Y149768D03*
X1109994Y168713D03*
X1118373Y192665D03*
Y196665D03*
X1118468Y204864D03*
X1117516Y329000D03*
Y334000D03*
Y339000D03*
X1112930Y666275D03*
X1115046Y710129D03*
X1140511Y206864D03*
X1132703Y242078D03*
X1139682D03*
X1128733Y252371D03*
X1126016Y329000D03*
Y334000D03*
Y339000D03*
X1132489Y458800D03*
X1132689Y545800D03*
Y558800D03*
Y562800D03*
X1143827Y106495D03*
X1149344Y250599D03*
X1144953Y392718D03*
Y384718D03*
Y380718D03*
Y404718D03*
Y408718D03*
Y396718D03*
Y400718D03*
Y412718D03*
X1141289Y553700D03*
Y557700D03*
X1156114Y675832D03*
X1163389Y453873D03*
Y458859D03*
X1162574Y542712D03*
X1184100Y324142D03*
X1188980Y329398D03*
X1174686Y774434D03*
X1193188Y151540D03*
X1196647Y168697D03*
X1196842Y191941D03*
X1198811Y224321D03*
X1219874Y58013D03*
X1210549Y68581D03*
Y80581D03*
X1216092Y114488D03*
X1213799Y149768D03*
X1212356Y168713D03*
X1220735Y192665D03*
Y196665D03*
X1220830Y204864D03*
X1235065Y242078D03*
X1231095Y252371D03*
X1238146Y306652D03*
X1229774Y545912D03*
Y626912D03*
X1246189Y106495D03*
X1242873Y206864D03*
X1242044Y242078D03*
X1251706Y250599D03*
X1252956Y1192376D03*
X1258016Y336000D03*
X1261714Y450334D03*
Y458334D03*
X1261710Y894866D03*
X1258114Y1146071D03*
X1257201Y1523458D03*
X1257162Y1527334D03*
X1257201Y1543558D03*
X1257162Y1531334D03*
Y1539334D03*
X1257186Y1535385D03*
X1282589Y488816D03*
X1282030Y768576D03*
Y780576D03*
X1273687Y848145D03*
X1273783Y864487D03*
Y859487D03*
X1273771Y852029D03*
X1273783Y874487D03*
Y869487D03*
Y879487D03*
Y889487D03*
Y884487D03*
X1284016Y919500D03*
X1280392Y933598D03*
X1272044Y1171120D03*
X1299009Y168697D03*
X1299204Y191941D03*
X1301173Y224321D03*
X1295516Y326500D03*
Y337000D03*
Y330000D03*
Y333500D03*
X1302357Y470382D03*
X1288016Y819500D03*
Y839500D03*
Y843500D03*
Y847500D03*
Y851500D03*
Y863500D03*
Y867000D03*
X1288011Y885783D03*
X1301016Y942500D03*
X1318454Y114488D03*
X1314718Y168713D03*
X1313990Y467560D03*
Y479560D03*
X1331164Y35983D03*
X1323097Y196665D03*
Y192665D03*
X1323192Y204864D03*
X1329822Y425413D03*
X1332362Y455301D03*
Y459101D03*
Y463101D03*
X1329516Y558500D03*
Y562500D03*
Y566500D03*
X1321516D03*
X1329516Y574500D03*
Y586500D03*
Y578500D03*
Y582500D03*
X1321516D03*
Y586500D03*
X1329516Y590500D03*
Y605000D03*
X1321516Y590500D03*
X1329516Y609000D03*
Y613000D03*
Y621000D03*
X1321516Y613000D03*
X1329516Y637000D03*
Y633000D03*
Y625000D03*
Y629000D03*
X1321516D03*
Y633000D03*
Y637000D03*
X1329516Y653500D03*
Y649500D03*
X1321516Y645000D03*
X1329516Y665500D03*
Y657500D03*
X1321516D03*
X1329516Y669500D03*
X1321516Y677500D03*
Y681500D03*
Y673500D03*
X1329516D03*
Y681500D03*
Y677500D03*
Y696500D03*
Y700500D03*
X1321516Y704500D03*
X1329516D03*
Y712500D03*
Y716500D03*
X1321516Y720500D03*
Y728500D03*
Y724500D03*
X1329516Y728500D03*
Y724500D03*
Y720500D03*
X1321486Y736464D03*
X1343189Y151540D03*
X1335990Y474560D03*
X1339309Y749675D03*
Y745675D03*
Y741675D03*
Y737675D03*
Y765675D03*
Y761675D03*
Y757675D03*
Y753675D03*
Y769675D03*
Y781675D03*
X1363800Y149768D03*
X1355260Y327777D03*
Y331377D03*
Y335651D03*
Y339251D03*
Y343525D03*
Y347125D03*
Y351399D03*
Y354999D03*
X1354862Y424601D03*
Y428101D03*
Y431601D03*
X1367975Y1012325D03*
Y1016325D03*
X1359781Y1022766D03*
Y1034266D03*
X1366859Y1043140D03*
X1359781Y1030266D03*
X1366782Y1047047D03*
X1381096Y252371D03*
X1370475Y1002180D03*
Y1007180D03*
X1396190Y106495D03*
X1392874Y206864D03*
X1392045Y242078D03*
X1385066D03*
X1387967Y361371D03*
Y356871D03*
X1399750Y536726D03*
Y531726D03*
Y544726D03*
Y540726D03*
X1385602Y577192D03*
X1385603Y627817D03*
X1399516Y652000D03*
Y660000D03*
Y703000D03*
Y707000D03*
X1396475Y1031680D03*
X1401707Y250599D03*
X1409581Y478982D03*
Y483982D03*
Y487982D03*
Y499982D03*
Y491982D03*
X1411875Y597393D03*
X1401468Y629311D03*
Y625311D03*
X1412516Y689000D03*
Y705000D03*
Y713000D03*
Y709000D03*
Y733000D03*
X1412485Y720894D03*
X1412516Y749000D03*
Y753000D03*
Y757000D03*
X1412539Y765343D03*
X1408114Y815683D03*
X1408016Y832000D03*
Y828000D03*
X1407965Y823934D03*
X1407918Y819817D03*
X1408016Y848000D03*
Y840000D03*
Y836000D03*
Y852000D03*
Y864000D03*
Y856000D03*
Y880000D03*
Y868000D03*
Y884000D03*
Y896000D03*
Y900000D03*
X1411085Y992307D03*
X1415281Y1004766D03*
Y996766D03*
Y1008766D03*
X1415285Y1020250D03*
X1415281Y1030766D03*
X1405475Y1032180D03*
X1408627Y1539557D03*
X1408135Y1562235D03*
X1418530Y631212D03*
X1420516Y681000D03*
Y685000D03*
Y689000D03*
Y697000D03*
Y701000D03*
Y713000D03*
Y709000D03*
Y705000D03*
Y725000D03*
Y729000D03*
Y733000D03*
Y741000D03*
Y745000D03*
Y749000D03*
Y753000D03*
Y757000D03*
X1429516Y774500D03*
Y798500D03*
Y790500D03*
Y794500D03*
Y818500D03*
Y834500D03*
Y838500D03*
Y842500D03*
X1418230Y939292D03*
X1425097Y951563D03*
X1425037Y947595D03*
X1423281Y1000766D03*
Y1004766D03*
Y996766D03*
Y1016266D03*
Y1020266D03*
Y1030766D03*
X1423487Y1494706D03*
X1426457Y1524252D03*
X1445551Y151540D03*
X1449010Y168697D03*
X1449205Y191941D03*
X1443223Y320861D03*
Y325361D03*
Y329861D03*
Y334361D03*
Y338861D03*
Y343361D03*
Y347861D03*
Y352361D03*
Y356861D03*
X1440295Y575841D03*
X1437516Y766500D03*
Y774500D03*
Y770500D03*
Y782500D03*
Y798500D03*
Y794500D03*
Y790500D03*
Y786500D03*
Y814500D03*
Y810500D03*
Y830500D03*
Y826500D03*
Y818500D03*
Y834500D03*
Y838500D03*
Y842500D03*
X1462912Y68581D03*
Y80581D03*
X1464719Y168713D03*
X1451174Y224321D03*
X1453223Y320861D03*
Y325361D03*
Y329861D03*
Y334361D03*
Y338861D03*
Y343361D03*
Y347861D03*
Y352361D03*
X1451552Y571614D03*
Y575614D03*
X1456634Y950980D03*
X1476913Y38244D03*
X1472237Y58013D03*
X1468455Y114488D03*
X1466162Y149768D03*
X1473098Y196665D03*
Y192665D03*
X1473193Y204864D03*
X1482016Y685630D03*
X1466633Y947600D03*
X1495236Y206864D03*
X1487428Y242078D03*
X1494407D03*
X1483458Y252371D03*
X1490062Y358700D03*
Y354200D03*
X1482516Y727500D03*
X1497299Y907240D03*
X1498552Y106495D03*
X1504069Y250599D03*
X1499516Y769000D03*
Y813000D03*
X1522376Y382600D03*
Y463600D03*
X1515464Y554555D03*
Y558555D03*
Y562555D03*
X1521744Y595588D03*
Y591588D03*
X1521776Y603600D03*
X1521744Y599588D03*
X1521776Y611600D03*
Y619600D03*
X1521744Y607588D03*
X1521776Y615600D03*
Y623600D03*
Y627600D03*
Y637969D03*
Y641974D03*
X1517401Y968739D03*
X1543663Y969737D03*
X1547913Y151540D03*
X1551372Y168697D03*
X1551567Y191941D03*
X1553536Y224321D03*
X1558395Y316363D03*
Y325363D03*
X1548395Y316363D03*
Y325363D03*
X1558395Y329863D03*
Y334363D03*
Y343363D03*
X1548395Y329863D03*
Y334363D03*
Y343363D03*
X1558395Y352363D03*
X1574599Y58013D03*
X1565274Y68581D03*
Y80581D03*
X1570817Y114488D03*
X1568524Y149768D03*
X1567081Y168713D03*
X1575460Y192665D03*
Y196665D03*
X1575555Y204864D03*
X1571716Y341600D03*
X1570017Y666275D03*
X1572133Y710129D03*
X1589790Y242078D03*
X1585820Y252371D03*
X1589576Y458800D03*
X1589776Y545800D03*
X1590824Y1442557D03*
X1600914Y106495D03*
X1597598Y206864D03*
X1596769Y242078D03*
X1606431Y250599D03*
X1608813Y336252D03*
Y344252D03*
Y340252D03*
X1602040Y384718D03*
Y380718D03*
Y392718D03*
Y400718D03*
Y404718D03*
Y408718D03*
Y396718D03*
Y412718D03*
X1598376Y553700D03*
Y557700D03*
X1611118Y699917D03*
Y717817D03*
X1611418Y732417D03*
X1599382Y1468023D03*
X1603619Y1527334D03*
X1620476Y453873D03*
Y458859D03*
X1619661Y542712D03*
X1613201Y675832D03*
X1627518Y744317D03*
X1626818Y762717D03*
X1616518Y828117D03*
X1612701Y1528558D03*
X1616301Y1539358D03*
X1612401Y1535258D03*
X1631118Y711417D03*
X1638518Y728117D03*
X1640766Y881999D03*
X1641114Y917241D03*
X1640872Y952125D03*
X1650275Y151540D03*
X1653734Y168697D03*
X1653929Y191941D03*
X1655898Y224321D03*
X1648331Y871345D03*
X1648868Y909279D03*
X1648475Y942136D03*
X1676961Y58013D03*
X1667636Y68581D03*
Y80581D03*
X1673179Y114488D03*
X1670886Y149768D03*
X1669443Y168713D03*
X1677822Y192665D03*
Y196665D03*
X1677917Y204864D03*
X1692152Y242078D03*
X1688182Y252371D03*
X1686861Y545912D03*
Y626912D03*
X1703276Y106495D03*
X1699960Y206864D03*
X1699131Y242078D03*
X1708793Y250599D03*
X1695233Y306652D03*
X1718801Y458334D03*
Y450334D03*
X1715201Y1146071D03*
X1739676Y488816D03*
X1729131Y1171120D03*
X1756096Y168697D03*
X1756291Y191941D03*
X1758260Y224321D03*
X1750123Y879199D03*
X1750178Y897279D03*
X1754216Y935100D03*
X1769998Y68581D03*
Y80581D03*
X1771805Y168713D03*
X1759444Y470382D03*
X1771077Y471560D03*
Y479560D03*
X1779323Y58013D03*
X1775541Y114488D03*
X1780184Y196665D03*
Y192665D03*
X1780279Y204864D03*
X1789678Y200716D03*
X1786909Y425413D03*
X1789449Y455301D03*
Y459101D03*
Y463101D03*
X1789579Y989660D03*
X1787150Y1430956D03*
X1793077Y474560D03*
X1802065Y985060D03*
X1804887Y1082250D03*
X1795354Y1103246D03*
X1791190Y1257937D03*
X1811949Y424601D03*
Y428101D03*
Y431601D03*
X1819247Y1101145D03*
Y1105145D03*
X1809948Y1223209D03*
G54D139*
X420656Y1116630D03*
X452784D03*
X486243D03*
X518371D03*
X1334830D03*
X1366958D03*
X1400417D03*
X1432545D03*
G54D175*
X812474Y1452587D03*
X864671Y1452589D03*
X906671D03*
G54D91*
X114974Y1109408D03*
Y1122008D03*
Y1134608D03*
Y1147208D03*
Y1159808D03*
Y1172408D03*
Y1185008D03*
X134100Y1016671D03*
X126620D03*
X134100Y1029271D03*
X126620D03*
X122454Y1109408D03*
Y1122008D03*
Y1134608D03*
Y1147208D03*
Y1159808D03*
Y1172408D03*
Y1185008D03*
X572061Y1109408D03*
Y1122008D03*
Y1134608D03*
Y1147208D03*
Y1159808D03*
Y1172408D03*
Y1185008D03*
X583707Y1016671D03*
Y1029271D03*
X579541Y1109408D03*
Y1122008D03*
Y1134608D03*
Y1147208D03*
Y1159808D03*
Y1172408D03*
Y1185008D03*
X591187Y1016671D03*
Y1029271D03*
X1040793Y1016671D03*
Y1029271D03*
X1036627Y1109408D03*
X1029147D03*
X1036627Y1122008D03*
X1029147D03*
X1036627Y1134608D03*
X1029147D03*
X1036627Y1147208D03*
X1029147D03*
X1036627Y1159808D03*
X1029147D03*
X1036627Y1172408D03*
X1029147D03*
X1036627Y1185008D03*
X1029147D03*
X1048273Y1016671D03*
Y1029271D03*
X1497880Y1016671D03*
Y1029271D03*
X1493714Y1109408D03*
X1486234D03*
X1493714Y1122008D03*
X1486234D03*
X1493714Y1134608D03*
X1486234D03*
X1493714Y1147208D03*
X1486234D03*
X1493714Y1172408D03*
X1486234D03*
X1493714Y1159808D03*
X1486234D03*
X1493714Y1185008D03*
X1486234D03*
X1505360Y1016671D03*
Y1029271D03*
G54D193*
X903297Y245669D03*
Y243307D03*
Y240945D03*
Y238583D03*
Y236221D03*
Y233858D03*
Y231496D03*
Y262205D03*
Y259843D03*
Y257480D03*
Y255118D03*
Y252756D03*
Y250394D03*
Y248032D03*
Y274016D03*
Y271654D03*
Y269291D03*
Y266929D03*
Y264567D03*
X915423Y245669D03*
Y243307D03*
Y240945D03*
Y238583D03*
Y236221D03*
Y233858D03*
Y231496D03*
Y262205D03*
Y259843D03*
Y257480D03*
Y255118D03*
Y252756D03*
Y250394D03*
Y248032D03*
Y274016D03*
Y271654D03*
Y269291D03*
Y266929D03*
Y264567D03*
G54D28*
X18463Y250245D03*
Y270245D03*
X19075Y284082D03*
X25549Y250245D03*
Y270245D03*
X82918Y149414D03*
X84679Y1012213D03*
X90004Y149414D03*
X91765Y1012213D03*
X108643Y139695D03*
X127911Y250245D03*
X120825D03*
X192366Y149414D03*
X185280D03*
X211005Y139695D03*
X230273Y250245D03*
X223187D03*
X294728Y149414D03*
X287642D03*
X313367Y139695D03*
X325549Y250245D03*
X332635D03*
X408758Y471560D03*
X415844D03*
X437643Y149414D03*
X444729D03*
X463368Y139695D03*
X482636Y250245D03*
X475550D03*
X540005Y149414D03*
X547091D03*
X548852Y1012213D03*
X541766D03*
X565730Y139695D03*
X584998Y250245D03*
X577912D03*
X649453Y149414D03*
X642367D03*
X668092Y139695D03*
X680274Y250245D03*
X687360D03*
X744729Y149414D03*
X751815D03*
X770454Y139695D03*
X782636Y250245D03*
X789722D03*
X879997Y483303D03*
X872911D03*
X894729Y149414D03*
X901815D03*
X920454Y139695D03*
X1004177Y149414D03*
X997091D03*
X1005938Y1012213D03*
X998852D03*
X1022816Y139695D03*
X1042084Y250245D03*
X1034998D03*
X1106539Y149414D03*
X1099453D03*
X1125178Y139695D03*
X1137360Y250245D03*
X1144446D03*
X1201815Y149414D03*
X1208901D03*
X1227540Y139695D03*
X1246808Y250245D03*
X1239722D03*
X1267792Y905324D03*
X1274878D03*
X1330017Y471560D03*
X1322931D03*
X1351816Y149414D03*
X1358902D03*
X1377541Y139695D03*
X1396809Y250245D03*
X1389723D03*
X1421368Y1540385D03*
X1428454D03*
X1420995Y1561025D03*
X1428081D03*
X1461264Y149414D03*
X1454178D03*
X1463025Y1012213D03*
X1455939D03*
X1479903Y139695D03*
X1492085Y250245D03*
X1499171D03*
X1556540Y149414D03*
X1563626D03*
X1582265Y139695D03*
X1594447Y250245D03*
X1601533D03*
X1627155Y702883D03*
Y720783D03*
X1627455Y735383D03*
Y753583D03*
X1623741Y777783D03*
X1616655D03*
X1623541Y790483D03*
X1616455D03*
X1623241Y804583D03*
X1616155D03*
X1623341Y818683D03*
X1616255D03*
X1634241Y702883D03*
Y720783D03*
X1634541Y735383D03*
Y753583D03*
X1658902Y149414D03*
X1665988D03*
X1684627Y139695D03*
X1703895Y250245D03*
X1696809D03*
X1787104Y471560D03*
X1780018D03*
X1790264Y1443715D03*
X1783178D03*
X1790141Y1475905D03*
X1783055D03*
G54D148*
X427378Y1555499D03*
X434070Y1560617D03*
Y1555499D03*
X427378Y1560617D03*
X948452Y360607D03*
X955144D03*
Y365725D03*
X948452D03*
G54D157*
X526897Y797102D03*
Y799071D03*
Y812850D03*
Y804976D03*
Y803008D03*
Y801039D03*
Y806945D03*
Y808913D03*
Y810882D03*
Y814819D03*
Y826630D03*
Y824661D03*
Y822693D03*
Y816787D03*
Y818756D03*
Y820724D03*
X571975Y799071D03*
Y797102D03*
Y803008D03*
Y812850D03*
Y814819D03*
Y810882D03*
Y808913D03*
Y806945D03*
Y804976D03*
Y801039D03*
Y824661D03*
Y826630D03*
Y822693D03*
Y820724D03*
Y818756D03*
Y816787D03*
X1491656Y924453D03*
Y926422D03*
Y928390D03*
Y940201D03*
Y932327D03*
Y930359D03*
Y934296D03*
Y936264D03*
Y938233D03*
Y942170D03*
Y944138D03*
Y953981D03*
Y952012D03*
Y950044D03*
Y946107D03*
Y948075D03*
X1536734Y928390D03*
Y926422D03*
Y924453D03*
Y930359D03*
Y940201D03*
Y944138D03*
Y942170D03*
Y938233D03*
Y936264D03*
Y934296D03*
Y932327D03*
Y952012D03*
Y953981D03*
Y950044D03*
Y948075D03*
Y946107D03*
G54D166*
X733058Y1614451D03*
X739358Y1611892D03*
Y1617010D03*
G54D229*
X1775991Y826570D03*
X1783471D03*
Y818696D03*
G54D46*
X34731Y1199141D03*
X45755Y1212527D03*
X410938Y870105D03*
X421962Y883491D03*
X427063Y626268D03*
X438087Y639654D03*
X878421Y1208144D03*
X889445Y1221530D03*
X942398Y1208144D03*
X953422Y1221530D03*
X1786378Y1208630D03*
X1797402Y1222016D03*
G54D73*
X58395Y619312D03*
X515481D03*
X972568D03*
X1429655D03*
G54D82*
X83565Y273540D03*
X185927D03*
X288289D03*
X390651D03*
X540652D03*
X643014D03*
X745376D03*
X847738D03*
X997738D03*
X1100100D03*
X1202462D03*
X1304824D03*
X1454825D03*
X1557187D03*
X1659549D03*
X1761911D03*
G54D55*
X54060Y492696D03*
X44229Y539440D03*
X89162Y214150D03*
X191524D03*
X293886D03*
X375084Y477527D03*
X396248Y214150D03*
X448704Y498641D03*
X501315Y539440D03*
X511146Y492696D03*
X546249Y214150D03*
X648611D03*
X750973D03*
X832170Y472527D03*
X853335Y214150D03*
X958402Y539440D03*
X968233Y492696D03*
X1003335Y214150D03*
X1105697D03*
X1208059D03*
X1289257Y477527D03*
X1310421Y214150D03*
X1415489Y539440D03*
X1425320Y492696D03*
X1460422Y214150D03*
X1562784D03*
X1665146D03*
X1746344Y477527D03*
X1767508Y214150D03*
G54D184*
X879794Y837418D03*
Y840568D03*
Y843717D03*
Y846867D03*
Y850016D03*
Y853166D03*
Y856316D03*
Y859465D03*
Y862615D03*
Y865764D03*
Y872064D03*
Y878363D03*
Y868914D03*
Y875213D03*
Y881512D03*
Y884662D03*
X886093Y846867D03*
X882944Y840568D03*
X889243Y846867D03*
X882944D03*
X895542D03*
Y840568D03*
X892392D03*
X895542Y837418D03*
Y843717D03*
X889243Y837418D03*
X892392Y846867D03*
X889243Y843717D03*
X892392D03*
X886093Y840568D03*
X882944Y837418D03*
X886093Y843717D03*
Y837418D03*
X882944Y843717D03*
X892392Y837418D03*
X889243Y840568D03*
X892392Y859465D03*
Y856316D03*
X895542Y862615D03*
Y859465D03*
Y856316D03*
X886093Y850016D03*
X889243Y856316D03*
Y853166D03*
Y850016D03*
X882944D03*
X886093Y856316D03*
Y853166D03*
X882944D03*
X892392D03*
X895542Y850016D03*
Y853166D03*
X892392Y850016D03*
X889243Y859465D03*
X886093D03*
X892392Y862615D03*
X889243D03*
X882944Y856316D03*
Y859465D03*
X886093Y862615D03*
X882944D03*
X892392Y865764D03*
Y868914D03*
X889243Y875213D03*
X895542Y872064D03*
Y868914D03*
Y865764D03*
X882944Y868914D03*
X886093Y872064D03*
X882944Y875213D03*
X886093D03*
X892392Y878363D03*
X882944Y865764D03*
X886093Y868914D03*
X882944Y872064D03*
X889243D03*
X882944Y878363D03*
X889243D03*
X886093Y865764D03*
X889243Y868914D03*
Y865764D03*
X892392Y872064D03*
X895542Y878363D03*
X886093D03*
X892392Y875213D03*
X895542D03*
X882944Y881512D03*
X886093D03*
X882944Y884662D03*
X886093D03*
X889243Y881512D03*
Y884662D03*
X892392Y881512D03*
Y884662D03*
X895542Y881512D03*
Y884662D03*
X904991Y840568D03*
X908140Y846867D03*
X911290D03*
X908140Y843717D03*
X911290D03*
X908140Y840568D03*
X901841D03*
Y843717D03*
X904991Y837418D03*
X901841Y846867D03*
X898692Y840568D03*
Y837418D03*
X901841D03*
X911290D03*
Y840568D03*
X908140Y837418D03*
X904991Y843717D03*
Y846867D03*
X898692Y843717D03*
Y846867D03*
X901841Y853166D03*
X904991D03*
X898692D03*
X901841Y850016D03*
X904991D03*
X898692D03*
X901841Y862615D03*
X904991D03*
X908140D03*
X911290D03*
X898692D03*
X901841Y859465D03*
X904991D03*
X908140D03*
X911290D03*
X898692D03*
X901841Y856316D03*
X904991D03*
X908140D03*
X911290D03*
X898692D03*
X911290Y853166D03*
Y850016D03*
X908140Y853166D03*
Y850016D03*
X901841Y875213D03*
X904991D03*
X911290Y872064D03*
X908140Y875213D03*
X898692D03*
X901841Y872064D03*
X904991D03*
X908140D03*
X898692D03*
X901841Y868914D03*
X904991D03*
X908140D03*
X911290D03*
X898692D03*
X901841Y865764D03*
X904991D03*
X908140D03*
X911290D03*
X898692D03*
Y878363D03*
X901841D03*
X904991D03*
X911290Y875213D03*
X908140Y878363D03*
X911290D03*
X898692Y881512D03*
Y884662D03*
X901841Y881512D03*
Y884662D03*
X904991D03*
Y881512D03*
X908140Y884662D03*
Y881512D03*
X911290Y884662D03*
Y881512D03*
X927038Y837418D03*
X914440Y840568D03*
X917589D03*
Y837418D03*
X914440D03*
Y843717D03*
Y846867D03*
X920739Y843717D03*
X917589D03*
X923888Y837418D03*
X920739Y840568D03*
Y837418D03*
X917589Y846867D03*
X923888D03*
X927038D03*
X923888Y843717D03*
X920739Y846867D03*
X927038Y843717D03*
Y840568D03*
X923888D03*
X914440Y859465D03*
Y856316D03*
X917589Y859465D03*
Y856316D03*
X920739D03*
Y853166D03*
X917589Y850016D03*
Y853166D03*
X914440D03*
Y850016D03*
X920739Y862615D03*
X923888Y850016D03*
X920739Y859465D03*
X927038Y850016D03*
Y856316D03*
X923888Y853166D03*
Y856316D03*
X927038Y853166D03*
X914440Y862615D03*
X927038Y859465D03*
X923888D03*
X920739Y850016D03*
X927038Y862615D03*
X923888D03*
X917589D03*
X914440Y868914D03*
Y865764D03*
X923888D03*
X917589D03*
X920739D03*
X927038Y875213D03*
X923888D03*
X920739D03*
X927038Y872064D03*
X923888D03*
X920739D03*
X927038Y868914D03*
X923888D03*
X917589Y872064D03*
Y868914D03*
X920739D03*
X927038Y865764D03*
X914440Y872064D03*
Y875213D03*
X920739Y878363D03*
X923888D03*
X914440D03*
X927038D03*
X917589D03*
Y875213D03*
X914440Y884662D03*
X917589D03*
X914440Y881512D03*
X917589D03*
X920739Y884662D03*
X923888D03*
X920739Y881512D03*
X927038Y884662D03*
X923888Y881512D03*
X927038D03*
X1315330Y831445D03*
X1318480D03*
Y844044D03*
Y834595D03*
Y837744D03*
X1315330Y834595D03*
Y837744D03*
X1318480Y840894D03*
X1315330D03*
Y844044D03*
X1318480Y847193D03*
X1315330D03*
X1318480Y850343D03*
X1315330D03*
X1318480Y853492D03*
X1315330D03*
X1318480Y856642D03*
X1315330D03*
X1318480Y859792D03*
X1315330D03*
Y862941D03*
X1318480D03*
Y866091D03*
X1315330Y878689D03*
X1318480D03*
X1315330Y866091D03*
Y869240D03*
X1318480D03*
X1315330Y872390D03*
X1318480D03*
X1315330Y875540D03*
X1318480D03*
Y881839D03*
Y891288D03*
X1315330Y894437D03*
X1318480D03*
X1315330Y881839D03*
Y884988D03*
X1318480D03*
X1315330Y888138D03*
X1318480D03*
X1315330Y891288D03*
Y897587D03*
X1318480D03*
X1324779Y831445D03*
X1321629D03*
X1334228D03*
X1331078D03*
X1327929D03*
X1334228Y837744D03*
X1321629Y844044D03*
X1334228Y840894D03*
Y847193D03*
X1324779Y834595D03*
X1327929Y840894D03*
X1324779Y837744D03*
X1321629Y834595D03*
X1331078Y847193D03*
Y844044D03*
X1334228Y834595D03*
Y844044D03*
X1331078Y840894D03*
Y834595D03*
Y837744D03*
X1327929D03*
Y834595D03*
Y844044D03*
X1324779Y840894D03*
X1321629Y837744D03*
Y840894D03*
X1327929Y847193D03*
X1324779Y844044D03*
Y847193D03*
X1321629D03*
X1324779Y862941D03*
X1321629D03*
X1334228Y850343D03*
X1331078D03*
X1327929D03*
X1324779D03*
X1321629D03*
X1334228Y853492D03*
X1331078D03*
X1334228Y856642D03*
X1327929Y853492D03*
X1324779D03*
X1321629D03*
X1331078Y856642D03*
X1327929D03*
X1334228Y859792D03*
X1331078D03*
X1327929D03*
X1324779Y856642D03*
X1334228Y862941D03*
X1321629Y856642D03*
X1324779Y859792D03*
X1321629D03*
X1327929Y862941D03*
X1331078D03*
X1321629Y875540D03*
X1324779D03*
Y878689D03*
X1321629D03*
X1331078Y875540D03*
X1327929Y878689D03*
X1334228Y875540D03*
X1331078Y878689D03*
X1334228D03*
X1324779Y866091D03*
X1321629D03*
X1327929D03*
X1331078D03*
X1321629Y869240D03*
X1324779D03*
X1327929D03*
X1334228Y866091D03*
X1331078Y869240D03*
X1334228D03*
X1321629Y872390D03*
X1324779D03*
X1327929D03*
Y875540D03*
X1331078Y872390D03*
X1334228D03*
X1327929Y884988D03*
X1334228Y894437D03*
X1321629Y881839D03*
X1334228Y891288D03*
Y881839D03*
X1331078Y884988D03*
X1334228Y888138D03*
X1331078Y891288D03*
Y894437D03*
X1334228Y884988D03*
X1331078Y888138D03*
X1327929Y894437D03*
Y891288D03*
Y888138D03*
X1324779Y894437D03*
X1321629D03*
X1324779Y891288D03*
X1321629D03*
X1324779Y881839D03*
X1321629Y884988D03*
X1327929Y881839D03*
X1324779Y884988D03*
X1331078Y881839D03*
X1324779Y888138D03*
X1321629D03*
X1334228Y897587D03*
X1331078D03*
X1327929D03*
X1324779D03*
X1321629D03*
X1349976Y831445D03*
X1346826D03*
X1343677D03*
X1340527D03*
X1337377D03*
X1349976Y840894D03*
X1346826D03*
X1349976Y834595D03*
Y844044D03*
Y847193D03*
Y837744D03*
X1346826D03*
Y844044D03*
Y834595D03*
Y847193D03*
X1343677Y834595D03*
Y837744D03*
X1340527D03*
X1343677Y840894D03*
Y844044D03*
Y847193D03*
X1340527Y834595D03*
Y840894D03*
X1337377Y837744D03*
Y834595D03*
Y840894D03*
X1340527Y844044D03*
Y847193D03*
X1337377D03*
Y844044D03*
Y853492D03*
X1349976Y856642D03*
X1346826D03*
X1343677D03*
X1340527D03*
Y859792D03*
X1343677Y862941D03*
X1340527D03*
X1337377D03*
Y856642D03*
Y859792D03*
X1349976Y853492D03*
X1346826D03*
X1343677D03*
X1340527D03*
X1343677Y859792D03*
X1349976Y862941D03*
X1346826D03*
X1349976Y859792D03*
X1346826D03*
X1337377Y850343D03*
X1349976D03*
X1346826D03*
X1343677D03*
X1340527D03*
X1343677Y866091D03*
X1340527D03*
Y869240D03*
X1349976Y872390D03*
X1346826D03*
X1343677D03*
X1340527D03*
X1343677Y875540D03*
X1337377D03*
Y869240D03*
Y872390D03*
Y866091D03*
X1349976Y875540D03*
X1346826D03*
X1340527D03*
X1343677Y878689D03*
X1349976Y866091D03*
X1346826D03*
X1349976Y869240D03*
X1346826D03*
X1343677D03*
X1349976Y878689D03*
X1346826D03*
X1340527D03*
X1337377D03*
X1346826Y891288D03*
X1349976D03*
X1343677D03*
Y888138D03*
X1340527Y884988D03*
X1337377D03*
X1349976Y881839D03*
Y894437D03*
Y884988D03*
Y888138D03*
X1346826D03*
Y884988D03*
Y894437D03*
Y881839D03*
X1343677Y894437D03*
Y884988D03*
Y881839D03*
X1340527D03*
Y894437D03*
Y888138D03*
Y891288D03*
X1337377Y894437D03*
Y888138D03*
Y891288D03*
Y881839D03*
X1349976Y897587D03*
X1346826D03*
X1343677D03*
X1340527D03*
X1337377D03*
X1365724Y831445D03*
X1362574D03*
X1359425D03*
X1356275D03*
X1353125D03*
X1365724Y847193D03*
X1362574Y837744D03*
Y840894D03*
X1365724Y844044D03*
X1362574Y847193D03*
X1365724Y840894D03*
X1362574Y844044D03*
X1365724Y837744D03*
Y834595D03*
X1359425Y847193D03*
Y844044D03*
X1362574Y834595D03*
X1359425Y840894D03*
Y837744D03*
Y834595D03*
X1356275Y840894D03*
Y837744D03*
Y834595D03*
Y844044D03*
Y847193D03*
X1353125Y840894D03*
Y837744D03*
Y834595D03*
Y847193D03*
Y844044D03*
X1365724Y850343D03*
X1362574Y853492D03*
X1365724D03*
X1362574Y856642D03*
X1365724D03*
Y859792D03*
X1362574D03*
Y862941D03*
X1365724D03*
X1359425Y853492D03*
X1356275Y856642D03*
X1353125D03*
X1356275Y859792D03*
Y862941D03*
X1353125D03*
X1356275Y853492D03*
X1353125D03*
X1359425Y856642D03*
Y859792D03*
Y862941D03*
X1353125Y859792D03*
X1362574Y850343D03*
X1359425D03*
X1356275D03*
X1353125D03*
X1365724Y878689D03*
X1362574D03*
Y866091D03*
X1365724D03*
X1362574Y869240D03*
X1365724D03*
Y872390D03*
X1362574D03*
Y875540D03*
X1365724D03*
X1356275Y866091D03*
X1353125D03*
X1356275Y869240D03*
Y872390D03*
X1353125D03*
X1359425Y875540D03*
X1353125D03*
X1359425Y866091D03*
Y869240D03*
Y872390D03*
X1356275Y875540D03*
X1353125Y878689D03*
Y869240D03*
X1359425Y878689D03*
X1356275D03*
X1365724Y881839D03*
X1362574Y894437D03*
Y891288D03*
X1365724Y884988D03*
X1362574Y881839D03*
X1359425Y884988D03*
X1356275D03*
X1359425Y881839D03*
X1365724Y888138D03*
X1362574Y884988D03*
Y888138D03*
X1365724Y891288D03*
Y894437D03*
X1359425Y888138D03*
Y891288D03*
Y894437D03*
X1356275Y881839D03*
Y888138D03*
Y891288D03*
Y894437D03*
X1353125Y888138D03*
Y891288D03*
Y894437D03*
Y881839D03*
Y884988D03*
X1365724Y897587D03*
X1362574D03*
X1359425D03*
X1356275D03*
X1353125D03*
X1381472Y831445D03*
X1378322D03*
X1375173D03*
X1372023D03*
X1368873D03*
X1375173Y837744D03*
X1372023Y840894D03*
X1375173D03*
X1368873Y844044D03*
X1372023D03*
X1378322Y837744D03*
X1381472Y834595D03*
X1368873Y847193D03*
X1372023D03*
X1378322Y840894D03*
X1381472Y837744D03*
X1375173Y847193D03*
X1381472Y840894D03*
Y844044D03*
X1378322Y847193D03*
X1381472D03*
X1378322Y844044D03*
X1375173D03*
X1378322Y834595D03*
X1368873Y840894D03*
X1372023Y837744D03*
X1375173Y834595D03*
X1372023D03*
X1368873Y837744D03*
Y834595D03*
Y850343D03*
X1372023D03*
X1375173D03*
X1368873Y853492D03*
X1372023D03*
X1375173D03*
X1368873Y856642D03*
X1372023D03*
X1378322Y850343D03*
X1381472D03*
X1375173Y856642D03*
X1381472D03*
X1378322Y853492D03*
X1381472D03*
X1372023Y859792D03*
X1375173D03*
X1378322Y856642D03*
X1381472Y859792D03*
X1368873D03*
X1372023Y862941D03*
X1375173D03*
X1378322D03*
X1381472D03*
X1378322Y859792D03*
X1368873Y862941D03*
X1375173Y875540D03*
X1378322D03*
X1381472D03*
X1368873Y878689D03*
X1372023D03*
X1375173D03*
X1378322D03*
X1381472D03*
Y866091D03*
X1378322D03*
X1381472Y869240D03*
X1375173Y866091D03*
X1372023D03*
X1368873Y869240D03*
X1372023D03*
X1375173D03*
Y872390D03*
X1381472D03*
X1378322D03*
X1372023D03*
X1368873D03*
Y875540D03*
X1372023D03*
X1368873Y866091D03*
X1378322Y869240D03*
X1372023Y881839D03*
X1368873D03*
X1381472D03*
X1375173Y884988D03*
X1372023D03*
X1378322D03*
X1381472D03*
X1375173Y888138D03*
X1372023D03*
X1378322D03*
X1381472D03*
Y891288D03*
X1378322D03*
X1368873Y884988D03*
X1378322Y881839D03*
X1375173D03*
X1381472Y894437D03*
X1375173Y891288D03*
X1372023D03*
X1378322Y894437D03*
X1375173D03*
X1368873Y888138D03*
Y891288D03*
X1372023Y894437D03*
X1368873D03*
X1381472Y897587D03*
X1378322D03*
X1375173D03*
X1372023D03*
X1368873D03*
G54D37*
X11313Y1116633D03*
X28635D03*
X43620Y1110100D03*
X60942D03*
X858003Y1125636D03*
X875325D03*
X890180Y1119103D03*
X907502D03*
X921980Y1125636D03*
X939302D03*
X954287Y1119103D03*
X971609D03*
X1771960Y1126122D03*
X1789282D03*
X1803760Y1119589D03*
X1821082D03*
G54D64*
X47195Y1081713D03*
Y1087619D03*
Y1083682D03*
Y1085650D03*
X67987Y584895D03*
Y586864D03*
Y590801D03*
Y588832D03*
X58219Y1087619D03*
Y1085650D03*
Y1081713D03*
Y1083682D03*
X84433Y179897D03*
Y181866D03*
Y185803D03*
Y183834D03*
X79011Y584895D03*
Y586864D03*
Y590801D03*
Y588832D03*
X95457Y179897D03*
Y181866D03*
Y185803D03*
Y183834D03*
X186795Y179897D03*
Y181866D03*
X197819Y179897D03*
Y181866D03*
X186795Y185803D03*
X197819D03*
X186795Y183834D03*
X197819D03*
X289157Y179897D03*
Y181866D03*
Y185803D03*
Y183834D03*
X300181Y179897D03*
Y181866D03*
Y185803D03*
Y183834D03*
X353984Y391572D03*
Y397478D03*
Y393541D03*
Y395509D03*
X365008Y391572D03*
Y397478D03*
Y395509D03*
Y393541D03*
X391519Y179897D03*
Y181866D03*
Y185803D03*
Y183834D03*
X393321Y960580D03*
Y954674D03*
Y958611D03*
X382297Y954674D03*
X393321Y956643D03*
X382297D03*
Y960580D03*
Y958611D03*
X402543Y179897D03*
Y181866D03*
Y185803D03*
Y183834D03*
X426660Y1112693D03*
Y1116237D03*
Y1118008D03*
Y1119780D03*
Y1121552D03*
Y1114465D03*
X458788Y1112693D03*
Y1116237D03*
Y1118008D03*
Y1119780D03*
Y1121552D03*
Y1114465D03*
X492247Y1112693D03*
Y1116237D03*
Y1118008D03*
Y1119780D03*
Y1121552D03*
Y1114465D03*
X536097Y584895D03*
Y586864D03*
X525073Y584895D03*
Y586864D03*
Y590801D03*
X536097D03*
Y588832D03*
X525073D03*
X524375Y1112693D03*
Y1116237D03*
Y1118008D03*
Y1119780D03*
Y1121552D03*
Y1114465D03*
X541520Y179897D03*
Y181866D03*
X552544Y179897D03*
Y181866D03*
X541520Y185803D03*
X552544D03*
X541520Y183834D03*
X552544D03*
X643882Y179897D03*
Y181866D03*
Y185803D03*
Y183834D03*
X654906Y179897D03*
Y181866D03*
Y185803D03*
Y183834D03*
X746244Y179897D03*
Y181866D03*
Y185803D03*
Y183834D03*
X757268Y179897D03*
Y181866D03*
Y185803D03*
Y183834D03*
X848606Y179897D03*
Y181866D03*
Y185803D03*
Y183834D03*
X859630Y179897D03*
Y181866D03*
Y185803D03*
Y183834D03*
X854739Y405479D03*
Y399573D03*
Y401542D03*
Y403510D03*
X865763Y399573D03*
Y405479D03*
Y403510D03*
Y401542D03*
X893885Y1090716D03*
Y1092685D03*
Y1094653D03*
Y1096622D03*
X904909Y1090716D03*
Y1096622D03*
Y1094653D03*
Y1092685D03*
X957862Y1090716D03*
Y1092685D03*
Y1094653D03*
Y1096622D03*
X968886Y1090716D03*
Y1096622D03*
Y1094653D03*
Y1092685D03*
X993184Y584895D03*
Y586864D03*
X982160Y584895D03*
Y586864D03*
Y590801D03*
X993184D03*
Y588832D03*
X982160D03*
X998606Y179897D03*
Y181866D03*
X1009630Y179897D03*
Y181866D03*
X998606Y185803D03*
X1009630D03*
X998606Y183834D03*
X1009630D03*
X1100968Y179897D03*
Y181866D03*
Y185803D03*
Y183834D03*
X1111992Y179897D03*
Y181866D03*
Y185803D03*
Y183834D03*
X1203330Y179897D03*
Y181866D03*
Y185803D03*
Y183834D03*
X1214354Y179897D03*
Y181866D03*
Y185803D03*
Y183834D03*
X1268157Y391572D03*
Y397478D03*
Y393541D03*
Y395509D03*
X1279181Y391572D03*
Y397478D03*
Y395509D03*
Y393541D03*
X1305692Y179897D03*
Y181866D03*
X1316716Y179897D03*
Y181866D03*
X1305692Y185803D03*
X1316716D03*
X1305692Y183834D03*
X1316716D03*
X1340834Y1112693D03*
Y1116237D03*
Y1118008D03*
Y1119780D03*
Y1121552D03*
Y1114465D03*
X1372962Y1112693D03*
Y1116237D03*
Y1118008D03*
Y1119780D03*
Y1121552D03*
Y1114465D03*
X1406421Y1112693D03*
Y1116237D03*
Y1118008D03*
Y1119780D03*
Y1121552D03*
Y1114465D03*
X1439247Y584895D03*
Y586864D03*
Y590801D03*
Y588832D03*
X1438549Y1112693D03*
Y1116237D03*
Y1118008D03*
Y1119780D03*
Y1121552D03*
Y1114465D03*
X1455693Y179897D03*
Y181866D03*
Y185803D03*
Y183834D03*
X1450271Y584895D03*
Y586864D03*
Y590801D03*
Y588832D03*
X1466717Y179897D03*
Y181866D03*
Y185803D03*
Y183834D03*
X1558055Y179897D03*
Y181866D03*
Y185803D03*
Y183834D03*
X1569079Y179897D03*
Y181866D03*
Y185803D03*
Y183834D03*
X1660417Y179897D03*
Y181866D03*
Y185803D03*
Y183834D03*
X1671441Y179897D03*
Y181866D03*
Y185803D03*
Y183834D03*
X1725244Y391572D03*
Y397478D03*
Y393541D03*
Y395509D03*
X1736268Y391572D03*
Y397478D03*
Y395509D03*
Y393541D03*
X1762779Y179897D03*
Y181866D03*
X1773803Y179897D03*
Y181866D03*
X1762779Y185803D03*
X1773803D03*
X1762779Y183834D03*
X1773803D03*
X1801842Y1091202D03*
Y1097108D03*
Y1093171D03*
Y1095139D03*
X1812866Y1091202D03*
Y1097108D03*
Y1095139D03*
Y1093171D03*
G54D92*
X115257Y1202289D03*
X106772Y1210774D03*
X118091Y1223388D03*
X129405Y1212075D03*
X126576Y1214903D03*
X120918Y1220560D03*
X572344Y1202289D03*
X563859Y1210774D03*
X586492Y1212075D03*
X583663Y1214903D03*
X578005Y1220560D03*
X575178Y1223388D03*
X1020945Y1210774D03*
X1029430Y1202289D03*
X1040749Y1214903D03*
X1043578Y1212075D03*
X1035091Y1220560D03*
X1032264Y1223388D03*
X1478032Y1210774D03*
X1486517Y1202289D03*
X1492178Y1220560D03*
X1497836Y1214903D03*
X1489351Y1223388D03*
X1500665Y1212075D03*
G54D167*
X742224Y1594417D03*
X749704D03*
X745964D03*
Y1604731D03*
X742224D03*
X749704D03*
G54D38*
X20079Y1433831D03*
X12599D03*
X16339Y1441705D03*
X20041Y1449735D03*
X12561D03*
X16301Y1457609D03*
X1056934Y1443022D03*
X1053194Y1450896D03*
X1060674D03*
G54D176*
X832961Y308900D03*
Y337836D03*
X855993Y308900D03*
Y337836D03*
X1298246Y748010D03*
Y776946D03*
X1321278Y748010D03*
Y776946D03*
X1350984Y561032D03*
Y589968D03*
Y607532D03*
Y636468D03*
Y652032D03*
Y680968D03*
Y699032D03*
Y727968D03*
X1374016Y561032D03*
Y589968D03*
Y607532D03*
Y636468D03*
Y652032D03*
Y680968D03*
Y699032D03*
Y727968D03*
X1441984Y683532D03*
Y712468D03*
Y727532D03*
Y756468D03*
X1465016Y683532D03*
Y712468D03*
Y727532D03*
Y756468D03*
X1458984Y769032D03*
Y797968D03*
Y813032D03*
Y841968D03*
X1482016Y769032D03*
Y797968D03*
Y813032D03*
Y841968D03*
G54D158*
X538609Y789327D03*
X536641D03*
X534672D03*
X536641Y834405D03*
X534672D03*
X538609D03*
X550420Y789327D03*
X540578D03*
X544515D03*
X554357D03*
X542546D03*
X548452D03*
X546483D03*
X552389D03*
X546483Y834405D03*
X540578D03*
X542546D03*
X544515D03*
X548452D03*
X550420D03*
X552389D03*
X554357D03*
X556326Y789327D03*
X558294D03*
X560263D03*
X562231D03*
X564200D03*
X556326Y834405D03*
X558294D03*
X560263D03*
X562231D03*
X564200D03*
X1505337Y916678D03*
X1509274D03*
X1503368D03*
X1501400D03*
X1507305D03*
X1499431D03*
X1513211D03*
X1511242D03*
Y961756D03*
X1501400D03*
X1499431D03*
X1503368D03*
X1505337D03*
X1507305D03*
X1509274D03*
X1513211D03*
X1515179Y916678D03*
X1521085D03*
X1523053D03*
X1525022D03*
X1526990D03*
X1519116D03*
X1517148D03*
X1528959D03*
X1521085Y961756D03*
X1523053D03*
X1525022D03*
X1515179D03*
X1517148D03*
X1519116D03*
X1526990D03*
X1528959D03*
G54D56*
X48154Y487775D03*
Y489743D03*
Y491712D03*
Y493680D03*
Y495649D03*
Y497617D03*
X38323Y534519D03*
Y536487D03*
Y538456D03*
X50135D03*
Y536487D03*
Y534519D03*
X38323Y540424D03*
Y542393D03*
Y544361D03*
X50135D03*
Y542393D03*
Y540424D03*
X59966Y489743D03*
Y487775D03*
Y497617D03*
Y495649D03*
Y493680D03*
Y491712D03*
X83256Y209229D03*
Y211197D03*
Y213166D03*
Y215134D03*
Y217103D03*
Y219071D03*
X95068Y213166D03*
Y211197D03*
Y209229D03*
Y219071D03*
Y217103D03*
Y215134D03*
X197430Y213166D03*
Y211197D03*
Y209229D03*
X185618D03*
Y211197D03*
Y213166D03*
X197430Y219071D03*
Y217103D03*
Y215134D03*
X185618D03*
Y217103D03*
Y219071D03*
X287980Y209229D03*
Y211197D03*
Y213166D03*
Y215134D03*
Y217103D03*
Y219071D03*
X299792Y213166D03*
Y211197D03*
Y209229D03*
Y219071D03*
Y217103D03*
Y215134D03*
X369178Y472606D03*
Y474574D03*
Y476543D03*
Y478511D03*
Y480480D03*
Y482448D03*
X390342Y209229D03*
Y211197D03*
Y213166D03*
Y215134D03*
Y217103D03*
Y219071D03*
X380990Y474574D03*
Y472606D03*
Y482448D03*
Y480480D03*
Y478511D03*
Y476543D03*
X402154Y213166D03*
Y211197D03*
Y209229D03*
Y219071D03*
Y217103D03*
Y215134D03*
X442798Y493720D03*
Y495688D03*
Y497657D03*
Y499625D03*
Y501594D03*
Y503562D03*
X454610D03*
Y501594D03*
Y499625D03*
Y497657D03*
Y495688D03*
Y493720D03*
X505240Y487775D03*
Y489743D03*
Y491712D03*
Y493680D03*
Y495649D03*
Y497617D03*
X495409Y534519D03*
Y536487D03*
Y538456D03*
X507221D03*
Y536487D03*
Y534519D03*
X495409Y540424D03*
Y542393D03*
Y544361D03*
X507221D03*
Y542393D03*
Y540424D03*
X517052Y489743D03*
Y487775D03*
Y497617D03*
Y495649D03*
Y493680D03*
Y491712D03*
X552155Y213166D03*
Y211197D03*
Y209229D03*
X540343D03*
Y211197D03*
Y213166D03*
X552155Y219071D03*
Y217103D03*
Y215134D03*
X540343D03*
Y217103D03*
Y219071D03*
X642705Y209229D03*
Y211197D03*
Y213166D03*
Y215134D03*
Y217103D03*
Y219071D03*
X654517Y213166D03*
Y211197D03*
Y209229D03*
Y219071D03*
Y217103D03*
Y215134D03*
X745067Y209229D03*
Y211197D03*
Y213166D03*
Y215134D03*
Y217103D03*
Y219071D03*
X756879Y213166D03*
Y211197D03*
Y209229D03*
Y219071D03*
Y217103D03*
Y215134D03*
X826264Y467606D03*
Y469574D03*
Y471543D03*
Y473511D03*
Y475480D03*
Y477448D03*
X847429Y209229D03*
Y211197D03*
Y213166D03*
Y215134D03*
Y217103D03*
Y219071D03*
X838076Y473511D03*
Y471543D03*
Y469574D03*
Y467606D03*
Y477448D03*
Y475480D03*
X859241Y213166D03*
Y211197D03*
Y209229D03*
Y219071D03*
Y217103D03*
Y215134D03*
X962327Y487775D03*
Y489743D03*
Y491712D03*
Y493680D03*
Y495649D03*
Y497617D03*
X952496Y534519D03*
Y536487D03*
Y538456D03*
Y540424D03*
Y542393D03*
Y544361D03*
X974139Y489743D03*
Y487775D03*
Y497617D03*
Y495649D03*
Y493680D03*
Y491712D03*
X964308Y538456D03*
Y536487D03*
Y534519D03*
Y544361D03*
Y542393D03*
Y540424D03*
X1009241Y213166D03*
Y211197D03*
Y209229D03*
X997429D03*
Y211197D03*
Y213166D03*
X1009241Y219071D03*
Y217103D03*
Y215134D03*
X997429D03*
Y217103D03*
Y219071D03*
X1099791Y209229D03*
Y211197D03*
Y213166D03*
Y215134D03*
Y217103D03*
Y219071D03*
X1111603Y213166D03*
Y211197D03*
Y209229D03*
Y219071D03*
Y217103D03*
Y215134D03*
X1202153Y209229D03*
Y211197D03*
Y213166D03*
Y215134D03*
Y217103D03*
Y219071D03*
X1213965Y213166D03*
Y211197D03*
Y209229D03*
Y219071D03*
Y217103D03*
Y215134D03*
X1283351Y472606D03*
Y474574D03*
Y476543D03*
Y478511D03*
Y480480D03*
Y482448D03*
X1295163Y474574D03*
Y472606D03*
Y482448D03*
Y480480D03*
Y478511D03*
Y476543D03*
X1316327Y213166D03*
Y211197D03*
Y209229D03*
X1304515D03*
Y211197D03*
Y213166D03*
X1316327Y219071D03*
Y217103D03*
Y215134D03*
X1304515D03*
Y217103D03*
Y219071D03*
X1409583Y534519D03*
Y536487D03*
Y538456D03*
Y540424D03*
Y542393D03*
Y544361D03*
X1419414Y487775D03*
Y489743D03*
X1431226D03*
Y487775D03*
X1419414Y491712D03*
Y493680D03*
Y495649D03*
Y497617D03*
X1431226D03*
Y495649D03*
Y493680D03*
Y491712D03*
X1421395Y538456D03*
Y536487D03*
Y534519D03*
Y544361D03*
Y542393D03*
Y540424D03*
X1454516Y209229D03*
Y211197D03*
Y213166D03*
Y215134D03*
Y217103D03*
Y219071D03*
X1466328Y213166D03*
Y211197D03*
Y209229D03*
Y219071D03*
Y217103D03*
Y215134D03*
X1556878Y209229D03*
Y211197D03*
Y213166D03*
Y215134D03*
Y217103D03*
Y219071D03*
X1568690Y213166D03*
Y211197D03*
Y209229D03*
Y219071D03*
Y217103D03*
Y215134D03*
X1659240Y209229D03*
Y211197D03*
Y213166D03*
Y215134D03*
Y217103D03*
Y219071D03*
X1671052Y213166D03*
Y211197D03*
Y209229D03*
Y219071D03*
Y217103D03*
Y215134D03*
X1740438Y472606D03*
Y474574D03*
Y476543D03*
Y478511D03*
Y480480D03*
Y482448D03*
X1752250Y474574D03*
Y472606D03*
Y482448D03*
Y480480D03*
Y478511D03*
Y476543D03*
X1773414Y213166D03*
Y211197D03*
Y209229D03*
X1761602D03*
Y211197D03*
Y213166D03*
X1773414Y219071D03*
Y217103D03*
Y215134D03*
X1761602D03*
Y217103D03*
Y219071D03*
G54D29*
X12804Y252371D03*
Y272371D03*
X11394Y284118D03*
X19363Y1464612D03*
X19274Y1496782D03*
X15691Y1501619D03*
X32082Y97667D03*
X27898Y102495D03*
X33811Y241681D03*
X34754Y289272D03*
Y285272D03*
X31458Y527726D03*
Y548726D03*
X33176Y621311D03*
X41024Y177606D03*
X41289Y495982D03*
X52508Y688473D03*
X38214Y1078372D03*
X44869Y1193263D03*
X51908Y1192250D03*
X63287Y483388D03*
X53477Y529269D03*
X60176Y608311D03*
X59233Y843118D03*
X67568Y1071656D03*
Y1075656D03*
Y1067656D03*
Y1083656D03*
Y1087656D03*
Y1079656D03*
X54647Y1124923D03*
X61269Y1209720D03*
X54395Y1213709D03*
X81229Y141247D03*
X77259Y147540D03*
X88208Y141247D03*
X97870Y145768D03*
X87598Y678107D03*
Y682107D03*
X94495Y1021177D03*
X87200Y1021048D03*
X104806Y172665D03*
Y180665D03*
Y176665D03*
Y168665D03*
Y184665D03*
Y188665D03*
X104901Y200864D03*
Y208864D03*
Y212864D03*
Y216864D03*
Y221864D03*
X104898Y225719D03*
X115166Y248371D03*
X111288Y1027361D03*
X130260Y102495D03*
X124689Y134838D03*
Y138838D03*
X134444Y97667D03*
X136173Y241681D03*
X154084Y378600D03*
Y459600D03*
X154172Y554555D03*
X154204Y562567D03*
X154172Y558555D03*
X153484Y631421D03*
X179621Y147540D03*
X186316Y80140D03*
Y76140D03*
Y84140D03*
X197027Y76587D03*
Y72587D03*
X183591Y141247D03*
X190570D03*
X200232Y145768D03*
X207168Y172665D03*
Y180665D03*
Y176665D03*
Y168665D03*
Y184665D03*
Y188665D03*
X207263Y208864D03*
Y212864D03*
Y216864D03*
Y221864D03*
X207260Y225719D03*
X227051Y134838D03*
Y138838D03*
X217528Y248371D03*
X221284Y462800D03*
X221484Y549800D03*
X230084Y549700D03*
X221484Y562800D03*
Y558800D03*
X221884Y621400D03*
Y625400D03*
X230521Y1494361D03*
X230527Y1482442D03*
Y1490442D03*
X222999Y1515642D03*
X222699Y1522542D03*
X236806Y97667D03*
X232622Y102495D03*
X238535Y241681D03*
X233748Y388718D03*
X232532Y1514578D03*
Y1526578D03*
Y1522578D03*
X252184Y445873D03*
Y449873D03*
Y462859D03*
X251369Y546712D03*
X251749Y675889D03*
X249550Y1514169D03*
Y1510142D03*
X286853Y27156D03*
X288678Y84140D03*
Y76140D03*
Y80140D03*
X281983Y147540D03*
X292932Y141247D03*
X285953D03*
X289999Y317873D03*
X299389Y76587D03*
Y72587D03*
X302594Y145768D03*
X309530Y180665D03*
Y172665D03*
Y176665D03*
Y168665D03*
Y184665D03*
X302575Y196286D03*
X309530Y188665D03*
X309625Y208864D03*
Y212864D03*
Y216864D03*
Y221864D03*
X309622Y225719D03*
X328390Y15806D03*
Y19806D03*
Y11806D03*
Y27806D03*
Y23806D03*
Y31806D03*
X319890Y248371D03*
X320392Y350850D03*
X318569Y541912D03*
Y622912D03*
X339168Y97667D03*
X334984Y102495D03*
X329413Y134838D03*
Y138838D03*
X340897Y241681D03*
X350509Y454334D03*
X353840Y1171120D03*
X364460Y406532D03*
X364804Y447357D03*
X373508Y458309D03*
Y454309D03*
Y462309D03*
X377384Y786400D03*
X375916Y939976D03*
Y943812D03*
Y947812D03*
X391040Y84140D03*
Y80140D03*
Y76140D03*
X389898Y401923D03*
X391152Y466409D03*
Y474382D03*
Y487382D03*
Y482382D03*
Y478382D03*
X379084Y750000D03*
X392654Y864408D03*
X387501Y1539700D03*
Y1543700D03*
Y1551700D03*
Y1559700D03*
X404568Y196620D03*
X402785Y471560D03*
Y475560D03*
X403684Y789000D03*
X401893Y860535D03*
Y864409D03*
X401835Y868286D03*
X399809Y948536D03*
X400004Y971780D03*
X407599Y1442942D03*
X419887Y26534D03*
X419982Y22627D03*
X419959Y30483D03*
X411892Y180665D03*
Y172665D03*
Y176665D03*
Y168665D03*
Y184665D03*
Y188665D03*
X411987Y208864D03*
Y212864D03*
Y216864D03*
Y221864D03*
X411984Y225719D03*
X419922Y834800D03*
X412174Y1098826D03*
X420188Y1523296D03*
X435954Y141247D03*
X431984Y147540D03*
X437575Y620456D03*
X427708Y1546372D03*
X434708Y1550158D03*
X452595Y145768D03*
X442933Y141247D03*
X443657Y435101D03*
Y439101D03*
Y443101D03*
Y447101D03*
Y452601D03*
X456603Y468809D03*
X446121Y620456D03*
X453461Y634279D03*
X446492Y640876D03*
X453456Y642588D03*
X445320Y711199D03*
X448575Y1026266D03*
X457075Y1024766D03*
X444302Y1098826D03*
X469891Y248371D03*
X470875Y461864D03*
X465887Y491669D03*
Y499669D03*
Y503669D03*
Y507669D03*
Y512669D03*
X489169Y97667D03*
X484985Y102495D03*
X479414Y134838D03*
Y138838D03*
X490898Y241681D03*
X478291Y347995D03*
Y352495D03*
X478394Y360089D03*
X488291Y347995D03*
Y352495D03*
X488394Y360089D03*
X478394Y364589D03*
Y369089D03*
Y373589D03*
X488394Y364589D03*
Y369089D03*
Y373589D03*
X478394Y378089D03*
Y382589D03*
Y387089D03*
Y391589D03*
X488394Y378089D03*
Y382589D03*
X479602Y468784D03*
Y472784D03*
Y476784D03*
X488544Y527726D03*
Y548726D03*
X490262Y621311D03*
X481890Y648968D03*
X477761Y1098826D03*
X498375Y495982D03*
X502664Y655149D03*
X498418Y685006D03*
Y689006D03*
Y697006D03*
Y693006D03*
X504075Y1000766D03*
Y1016266D03*
Y1012266D03*
X520373Y483388D03*
X510563Y529269D03*
X517262Y608311D03*
X509225Y844649D03*
X513754Y969933D03*
X513706Y973885D03*
X509889Y1098826D03*
X538316Y141247D03*
X534346Y147540D03*
X538670Y381723D03*
X535051Y394309D03*
X528164Y1103717D03*
X541041Y80140D03*
Y76140D03*
Y84140D03*
X551752Y76587D03*
Y72587D03*
X545295Y141247D03*
X554957Y145768D03*
X548670Y386223D03*
Y390723D03*
X555665Y738558D03*
X547686Y746514D03*
X542508Y779889D03*
X551582Y1021177D03*
X544287Y1021048D03*
X561893Y180665D03*
Y172665D03*
Y176665D03*
Y168665D03*
Y184665D03*
Y188665D03*
X561988Y208864D03*
Y212864D03*
Y216864D03*
Y221864D03*
X561985Y225719D03*
X572253Y248371D03*
X570504Y743122D03*
X564271Y754992D03*
X567829Y1026933D03*
X587347Y102495D03*
X581776Y134838D03*
Y138838D03*
X575098Y776700D03*
Y780700D03*
X576287Y957207D03*
X588416Y1497687D03*
Y1493687D03*
X585199Y1514042D03*
X588416Y1501687D03*
X584450Y1505724D03*
X575241Y1526224D03*
X591531Y97667D03*
X593260Y241681D03*
X611170Y378600D03*
Y459600D03*
X611258Y554555D03*
Y558555D03*
X611290Y562567D03*
X610570Y631421D03*
X636708Y147540D03*
X643403Y76140D03*
Y84140D03*
Y80140D03*
X647657Y141247D03*
X640678D03*
X654114Y76587D03*
Y72587D03*
X657319Y145768D03*
X664255Y180665D03*
Y172665D03*
Y176665D03*
Y168665D03*
Y184665D03*
Y188665D03*
X664350Y208864D03*
Y212864D03*
Y216864D03*
Y221864D03*
X664347Y225719D03*
X661026Y660402D03*
X665047Y689694D03*
X669830Y763137D03*
X656330Y759137D03*
Y767137D03*
Y763137D03*
X669830Y779137D03*
Y771137D03*
X656330Y779137D03*
Y775137D03*
Y771137D03*
Y783137D03*
Y787137D03*
X669830D03*
X684138Y134838D03*
Y138838D03*
X674615Y248371D03*
X678370Y462800D03*
X678570Y549800D03*
X678970Y621400D03*
Y625400D03*
X693893Y97667D03*
X689709Y102495D03*
X695622Y241681D03*
X690834Y388718D03*
X687170Y549700D03*
X709270Y445873D03*
Y449873D03*
Y462859D03*
X708455Y546712D03*
X708835Y675889D03*
X707069Y709303D03*
X710074Y728050D03*
X720273Y691609D03*
X727830Y760137D03*
X745765Y84140D03*
Y76140D03*
Y80140D03*
X750019Y141247D03*
X743040D03*
X739070Y147540D03*
X747085Y317873D03*
X739214Y1622015D03*
X756476Y72562D03*
Y76587D03*
X759681Y145768D03*
X766617Y180665D03*
Y172665D03*
Y176665D03*
Y168665D03*
Y184665D03*
Y188665D03*
X759293Y196620D03*
X766712Y200864D03*
Y208864D03*
Y212864D03*
Y216864D03*
Y221864D03*
X776977Y248371D03*
X777478Y350850D03*
X775655Y541912D03*
Y622912D03*
X783245Y1443445D03*
X783233Y1435432D03*
X774694Y1454305D03*
X796255Y97667D03*
X792071Y102495D03*
X786500Y134838D03*
Y138838D03*
X797984Y241681D03*
X791608Y442510D03*
Y450510D03*
Y446510D03*
X814961Y305368D03*
Y309368D03*
X806961Y305368D03*
Y309368D03*
X814961Y313368D03*
X806961D03*
X814961Y317368D03*
Y321368D03*
Y325368D03*
X806961Y317368D03*
Y321368D03*
Y325368D03*
X814961Y329368D03*
X806961D03*
X814961Y333368D03*
X806961Y337368D03*
Y333368D03*
X814961Y346368D03*
X806961D03*
X814961Y350368D03*
X814958Y354741D03*
X807595Y448334D03*
X811808Y840919D03*
X810927Y1171120D03*
X810113Y1404769D03*
X807978Y1484354D03*
X821867Y441389D03*
X830594Y456309D03*
Y448309D03*
Y452309D03*
X820047Y742502D03*
X829984Y766500D03*
Y784500D03*
Y802500D03*
Y820500D03*
X823461Y933571D03*
X828894Y1462461D03*
X848127Y76140D03*
Y80140D03*
Y84140D03*
X848238Y461382D03*
Y469382D03*
Y473382D03*
Y482382D03*
Y477382D03*
X841326Y827459D03*
X843748Y843790D03*
Y847490D03*
X845793Y835459D03*
Y851459D03*
X843221Y863413D03*
X843348Y855395D03*
X843221Y867413D03*
X834188Y1440849D03*
Y1448849D03*
X845228Y1461959D03*
X834206Y1454525D03*
X858838Y76587D03*
Y72587D03*
X861655Y196620D03*
X853458Y414760D03*
X864715Y414533D03*
X853458Y418760D03*
X863745Y701170D03*
Y709170D03*
X863545Y722670D03*
X864484Y756000D03*
Y760000D03*
Y764000D03*
Y778000D03*
Y782000D03*
Y774000D03*
Y792000D03*
Y796000D03*
Y800000D03*
Y814000D03*
Y810000D03*
X856815Y827468D03*
X864484Y818000D03*
X849124Y827686D03*
X856743Y835459D03*
X868979Y180665D03*
Y172665D03*
Y176665D03*
Y168665D03*
Y184665D03*
Y188665D03*
X869074Y208864D03*
Y212864D03*
Y216864D03*
Y221864D03*
X875461Y309368D03*
Y305368D03*
Y313368D03*
Y325368D03*
Y321368D03*
Y317368D03*
X865229Y340454D03*
X875461Y329368D03*
Y333368D03*
X866938Y487303D03*
Y483303D03*
X872397Y549771D03*
X872552Y562703D03*
Y570703D03*
Y566703D03*
Y578703D03*
Y582828D03*
X876212Y794227D03*
X893040Y141247D03*
X889070Y147540D03*
X883461Y341342D03*
X891371Y341537D03*
X883461Y345342D03*
X885224Y415264D03*
X881745Y694970D03*
Y690970D03*
X886745Y727178D03*
Y722770D03*
X884904Y1087375D03*
X888559Y1202266D03*
X895598Y1201253D03*
X886728Y1444859D03*
Y1460859D03*
Y1476859D03*
Y1468859D03*
X900019Y141247D03*
X909681Y145768D03*
X902244Y358369D03*
Y354369D03*
Y374369D03*
Y366369D03*
X909945Y687770D03*
Y691770D03*
X910745Y718970D03*
X906818Y948607D03*
X901337Y1133926D03*
X904959Y1218723D03*
X898085Y1222712D03*
X920051Y310985D03*
X920870Y547348D03*
X929136Y557641D03*
Y569578D03*
Y573578D03*
Y577578D03*
Y581578D03*
X914258Y1076659D03*
Y1080659D03*
Y1084659D03*
Y1088659D03*
Y1092659D03*
Y1096659D03*
X925324Y1449536D03*
X924688Y1468100D03*
X942071Y102495D03*
X936500Y134838D03*
Y138838D03*
X938983Y451442D03*
Y455442D03*
Y459442D03*
Y463442D03*
Y468942D03*
X945631Y527726D03*
Y548726D03*
X943570Y792330D03*
X930690Y798271D03*
X939312Y891216D03*
X946255Y97667D03*
X948650Y226852D03*
X955462Y495982D03*
X947349Y621311D03*
X952512Y782467D03*
X952668Y799233D03*
X952437Y786366D03*
X947611Y864862D03*
X947548Y883146D03*
X955048Y899890D03*
X948881Y1087375D03*
X952536Y1202122D03*
X959575Y1201253D03*
X962062Y1222712D03*
X977460Y483388D03*
X967650Y529269D03*
X974349Y608311D03*
X976569Y831799D03*
X976575Y827907D03*
X978235Y1076659D03*
Y1088659D03*
Y1084659D03*
Y1080659D03*
Y1092659D03*
Y1096659D03*
X965314Y1133926D03*
X968936Y1218723D03*
X991432Y147540D03*
X982609Y328472D03*
Y335472D03*
X984687Y825159D03*
Y829159D03*
Y833159D03*
X998127Y84140D03*
Y76140D03*
Y80140D03*
X1008838Y72587D03*
Y76587D03*
X1002381Y141247D03*
X995402D03*
X997661Y314653D03*
X1008668Y1021177D03*
X1012043Y145768D03*
X1018979Y180665D03*
Y172665D03*
Y176665D03*
Y168665D03*
Y184665D03*
Y188665D03*
X1019074Y200864D03*
Y208864D03*
Y212864D03*
Y216864D03*
Y221864D03*
X1019071Y225719D03*
X1019379Y754546D03*
Y771974D03*
Y775974D03*
X1019342Y815046D03*
X1019379Y825981D03*
Y818974D03*
X1018187Y833659D03*
X1018687Y848680D03*
X1017903Y954222D03*
X1024915Y1026933D03*
X1013988Y1357938D03*
X1013976Y1368835D03*
X1013971Y1380797D03*
X1038862Y134838D03*
Y138838D03*
X1029339Y248371D03*
X1043147Y1309487D03*
X1038924Y1357372D03*
X1038867Y1361287D03*
X1038875Y1365009D03*
X1048617Y97667D03*
X1044433Y102495D03*
X1050346Y241681D03*
X1058709Y310574D03*
X1058596Y343509D03*
X1058188Y356151D03*
Y368276D03*
X1057471Y1311436D03*
X1057517Y1315605D03*
X1051420Y1323611D03*
X1068257Y378600D03*
Y459600D03*
X1068345Y554555D03*
Y558555D03*
X1068377Y562567D03*
X1067657Y631421D03*
X1061319Y1456486D03*
X1100489Y76140D03*
Y80140D03*
Y84140D03*
X1093794Y147540D03*
X1104743Y141247D03*
X1097764D03*
X1111200Y72587D03*
Y76587D03*
X1114405Y145768D03*
X1121341Y180665D03*
Y172665D03*
Y176665D03*
Y168665D03*
Y188665D03*
Y184665D03*
X1121436Y200864D03*
Y208864D03*
Y212864D03*
Y216864D03*
Y221864D03*
X1121433Y225719D03*
X1118113Y660402D03*
X1122134Y689694D03*
X1131701Y248371D03*
X1135457Y462800D03*
X1135657Y549800D03*
X1136057Y621400D03*
Y625400D03*
X1150979Y97667D03*
X1146795Y102495D03*
X1141224Y134838D03*
Y138838D03*
X1152708Y241681D03*
X1147921Y388718D03*
X1144257Y549700D03*
X1166357Y445873D03*
Y449873D03*
Y462859D03*
X1165542Y546712D03*
X1165922Y675889D03*
X1182820Y339103D03*
X1202851Y84140D03*
Y76140D03*
Y80140D03*
X1200126Y141247D03*
X1196156Y147540D03*
X1204172Y317873D03*
X1213562Y72587D03*
Y76587D03*
X1216767Y145768D03*
X1207105Y141247D03*
X1216379Y196620D03*
X1223703Y180665D03*
Y172665D03*
Y176665D03*
Y168665D03*
Y184665D03*
Y188665D03*
X1223798Y200864D03*
Y208864D03*
Y212864D03*
Y216864D03*
Y221864D03*
X1223795Y225719D03*
X1234063Y248371D03*
X1234565Y350850D03*
X1232742Y541912D03*
Y622912D03*
X1253341Y97667D03*
X1249157Y102495D03*
X1243586Y134838D03*
Y138838D03*
X1250599Y1531342D03*
X1255070Y241681D03*
X1261984Y327000D03*
X1264682Y454334D03*
X1268013Y1171120D03*
X1260117Y1519459D03*
X1278633Y406532D03*
X1278977Y447357D03*
X1284998Y776576D03*
Y772576D03*
Y784576D03*
X1280984Y914000D03*
X1271774Y914949D03*
Y918956D03*
X1287681Y458309D03*
Y454309D03*
Y462309D03*
X1298550Y796321D03*
X1290984Y827500D03*
Y831500D03*
Y823500D03*
Y835500D03*
Y859500D03*
Y855500D03*
X1290979Y877783D03*
Y881783D03*
Y889767D03*
X1293984Y919500D03*
X1305213Y84140D03*
Y76140D03*
Y80140D03*
X1318741Y196620D03*
X1304071Y401923D03*
X1305325Y466409D03*
X1316958Y471560D03*
X1305325Y474382D03*
Y487382D03*
Y482382D03*
X1316958Y475560D03*
X1305325Y478382D03*
X1334060Y26534D03*
X1334132Y30483D03*
X1334155Y22627D03*
X1326065Y168665D03*
Y176665D03*
Y172665D03*
Y180665D03*
Y184665D03*
Y188665D03*
X1326160Y200864D03*
Y208864D03*
Y212864D03*
Y216864D03*
Y221864D03*
X1326157Y225719D03*
X1324484Y558500D03*
Y562500D03*
Y574500D03*
Y578500D03*
X1332484Y594500D03*
X1324484D03*
Y605000D03*
Y621000D03*
Y609000D03*
Y625000D03*
X1332484Y641000D03*
X1324484Y653500D03*
Y641000D03*
Y649500D03*
Y665500D03*
Y669500D03*
Y685500D03*
X1332484D03*
X1324484Y700500D03*
Y696500D03*
Y716500D03*
Y712500D03*
Y732500D03*
X1332484D03*
X1326348Y1098826D03*
X1350127Y141247D03*
X1346157Y147540D03*
X1342277Y773675D03*
X1357106Y141247D03*
X1366768Y145768D03*
X1357830Y435101D03*
Y439101D03*
Y443101D03*
Y447101D03*
Y452601D03*
X1362749Y1026266D03*
X1358476Y1098826D03*
X1384064Y248371D03*
X1380935Y320871D03*
Y325371D03*
Y343371D03*
Y338871D03*
Y334371D03*
Y329871D03*
Y347871D03*
Y361371D03*
Y356871D03*
Y352371D03*
X1371249Y1024766D03*
X1399158Y102495D03*
X1393587Y134838D03*
Y138838D03*
X1390935Y320871D03*
Y325371D03*
Y329871D03*
Y343371D03*
Y338871D03*
Y334371D03*
Y352371D03*
Y347871D03*
X1388225Y569000D03*
Y565000D03*
Y561000D03*
X1388571Y581317D03*
X1388225Y615500D03*
Y611500D03*
Y607500D03*
X1388570Y623692D03*
X1394484Y652000D03*
Y656000D03*
Y660000D03*
X1393984Y675000D03*
X1394484Y699000D03*
Y703000D03*
Y707000D03*
X1393984Y722000D03*
X1391935Y1098826D03*
X1403342Y97667D03*
X1405071Y241681D03*
X1412549Y495982D03*
X1402718Y527726D03*
Y548726D03*
X1404436Y621311D03*
X1402484Y656000D03*
X1401984Y675000D03*
X1415484Y681000D03*
Y685000D03*
X1402484Y699000D03*
X1415484Y697000D03*
Y701000D03*
Y717000D03*
X1401984Y722000D03*
X1415484Y725000D03*
Y729000D03*
Y741000D03*
Y745000D03*
Y761000D03*
X1410984Y844000D03*
Y860000D03*
Y876000D03*
Y872000D03*
Y888000D03*
Y892000D03*
Y904000D03*
X1410798Y911137D03*
Y915186D03*
X1414052Y988403D03*
X1424737Y529269D03*
X1431436Y608311D03*
X1423484Y717000D03*
X1432484Y766500D03*
X1423484Y761000D03*
X1432484Y770500D03*
Y782500D03*
Y786500D03*
Y802500D03*
Y814500D03*
Y810500D03*
Y830500D03*
Y826500D03*
Y846500D03*
X1428017Y943390D03*
X1418249Y1000766D03*
Y1016266D03*
Y1012266D03*
X1424063Y1098826D03*
X1426461Y1498545D03*
X1429423Y1520364D03*
X1419648Y1548217D03*
X1419006Y1569486D03*
X1448519Y147540D03*
X1437667Y359673D03*
X1434547Y483388D03*
X1440484Y802500D03*
Y846500D03*
X1438940Y951902D03*
X1443096Y1001518D03*
X1435578Y1001519D03*
X1442338Y1103717D03*
X1454569Y26393D03*
Y30393D03*
X1454285Y39193D03*
X1455214Y84140D03*
Y76140D03*
Y80140D03*
X1452489Y141247D03*
X1459468D03*
X1456191Y356861D03*
X1461680Y928177D03*
X1464832Y932887D03*
X1458460Y1021048D03*
X1465755Y1021177D03*
X1465925Y72587D03*
Y76587D03*
X1469130Y145768D03*
X1476066Y168665D03*
Y176665D03*
Y172665D03*
Y180665D03*
Y184665D03*
Y188665D03*
X1476161Y200864D03*
Y208864D03*
Y212864D03*
Y216864D03*
Y221864D03*
X1476158Y225719D03*
X1469684Y939543D03*
X1469648Y943496D03*
X1473984Y972000D03*
X1482002Y1026933D03*
X1496106Y19043D03*
Y15043D03*
Y23043D03*
Y31043D03*
Y27043D03*
Y35043D03*
X1495949Y138838D03*
Y134838D03*
X1486426Y248371D03*
X1493030Y322700D03*
X1483030Y327200D03*
Y322700D03*
X1493030Y327200D03*
Y331700D03*
Y340700D03*
X1483030D03*
Y331700D03*
X1493030Y349700D03*
X1483030Y345200D03*
Y358700D03*
Y354200D03*
Y349700D03*
X1493030Y345200D03*
X1492997Y368576D03*
X1484984Y681630D03*
Y677630D03*
Y697630D03*
Y689630D03*
Y693630D03*
X1492984Y706500D03*
X1484984D03*
X1485484Y731500D03*
Y723500D03*
Y735500D03*
X1484984Y750500D03*
X1485484Y743500D03*
Y739500D03*
X1492984Y750500D03*
X1505704Y97667D03*
X1501520Y102495D03*
X1507433Y241681D03*
X1502484Y765000D03*
Y781000D03*
Y773000D03*
Y777000D03*
X1509984Y792000D03*
X1501984D03*
X1502484Y785000D03*
Y809000D03*
Y817000D03*
Y825000D03*
Y821000D03*
Y829000D03*
X1509984Y836000D03*
X1501984D03*
X1507267Y907240D03*
X1525344Y378600D03*
Y459600D03*
X1525432Y554555D03*
Y558555D03*
X1525464Y562567D03*
X1524744Y631421D03*
X1541192Y352053D03*
X1557576Y84140D03*
Y76140D03*
Y80140D03*
X1550881Y147540D03*
X1561830Y141247D03*
X1554851D03*
X1551363Y352363D03*
X1554198Y956600D03*
X1568287Y72587D03*
Y76587D03*
X1571492Y145768D03*
X1578428Y168665D03*
Y176665D03*
Y172665D03*
Y180665D03*
Y184665D03*
Y188665D03*
X1578523Y200864D03*
Y208864D03*
Y212864D03*
Y216864D03*
Y221864D03*
X1578520Y225719D03*
X1574684Y336200D03*
X1575200Y660402D03*
X1579221Y689694D03*
X1588788Y248371D03*
X1592544Y462800D03*
X1592744Y549800D03*
Y558800D03*
Y562800D03*
X1593144Y621400D03*
Y625400D03*
X1593766Y1446488D03*
X1608066Y97667D03*
X1603882Y102495D03*
X1598311Y134838D03*
Y138838D03*
X1609795Y241681D03*
X1605008Y388718D03*
X1601344Y549700D03*
X1604596Y1471973D03*
X1606587Y1539334D03*
X1606575Y1543373D03*
X1619781Y344252D03*
Y340252D03*
X1623444Y445873D03*
Y449873D03*
Y462859D03*
X1622629Y546712D03*
X1623009Y675889D03*
X1659938Y84140D03*
Y80140D03*
Y76140D03*
X1657213Y141247D03*
X1653243Y147540D03*
X1670649Y72587D03*
Y76587D03*
X1664192Y141247D03*
X1673854Y145768D03*
X1673466Y196620D03*
X1661259Y317873D03*
X1680790Y168665D03*
Y176665D03*
Y172665D03*
Y180665D03*
Y188665D03*
Y184665D03*
X1680885Y200864D03*
Y208864D03*
Y212864D03*
Y216864D03*
Y221864D03*
X1680882Y225719D03*
X1691150Y248371D03*
X1691652Y350850D03*
X1689829Y541912D03*
Y622912D03*
X1706244Y102495D03*
X1700673Y134838D03*
Y138838D03*
X1710428Y97667D03*
X1712157Y241681D03*
X1721769Y454334D03*
X1725100Y1171120D03*
X1735720Y406532D03*
X1736064Y447357D03*
X1744768Y458309D03*
Y454309D03*
Y462309D03*
X1753092Y884649D03*
X1752326Y915451D03*
X1757184Y931100D03*
X1762300Y80140D03*
Y76140D03*
Y84140D03*
X1773011Y72587D03*
Y76587D03*
X1761158Y401923D03*
X1762412Y466409D03*
X1774045Y467560D03*
X1762412Y474382D03*
Y487382D03*
Y482382D03*
X1774045Y475560D03*
X1762412Y478382D03*
X1763991Y824383D03*
Y820883D03*
X1783152Y168665D03*
Y176665D03*
Y172665D03*
Y180665D03*
X1775828Y196620D03*
X1783152Y184665D03*
Y188665D03*
X1783247Y200864D03*
Y208864D03*
Y212864D03*
Y216864D03*
Y221864D03*
X1783244Y225719D03*
X1781452Y924546D03*
X1786114Y1462700D03*
X1792672Y196531D03*
X1792547Y985060D03*
X1792861Y1087861D03*
X1803555Y1201739D03*
X1796516Y1202756D03*
X1806042Y1223198D03*
X1803005Y1444543D03*
X1802882Y1476733D03*
X1814917Y435101D03*
Y439101D03*
Y443101D03*
Y447101D03*
Y452601D03*
X1822215Y1077145D03*
Y1081145D03*
Y1089145D03*
Y1085145D03*
Y1093145D03*
Y1097145D03*
X1813294Y1134412D03*
X1812916Y1219209D03*
G54D74*
X57066Y624724D03*
X514152D03*
X971239D03*
X1428326D03*
G54D65*
X52707Y1084666D03*
X73499Y587848D03*
X89945Y182850D03*
X192307D03*
X294669D03*
X359496Y394525D03*
X387809Y957627D03*
X397031Y182850D03*
X530585Y587848D03*
X547032Y182850D03*
X649394D03*
X751756D03*
X854118D03*
X860251Y402526D03*
X899397Y1093669D03*
X963374D03*
X987672Y587848D03*
X1004118Y182850D03*
X1106480D03*
X1208842D03*
X1273669Y394525D03*
X1311204Y182850D03*
X1444759Y587848D03*
X1461205Y182850D03*
X1563567D03*
X1665929D03*
X1730756Y394525D03*
X1768291Y182850D03*
X1807354Y1094155D03*
G54D185*
X895384Y228740D03*
Y276772D03*
X923336Y226772D03*
Y278740D03*
G54D194*
X906811Y312857D03*
X908385D03*
X906811Y309235D03*
X908385D03*
G54D83*
X78447Y273540D03*
X180809D03*
X283171D03*
X385533D03*
X535534D03*
X637896D03*
X740258D03*
X842620D03*
X992620D03*
X1094982D03*
X1197344D03*
X1299706D03*
X1449707D03*
X1552069D03*
X1654431D03*
X1756793D03*
G54D149*
X466046Y1010216D03*
Y1022815D03*
Y1013366D03*
Y1011791D03*
Y1016516D03*
Y1018090D03*
Y1024390D03*
Y1014941D03*
Y1021240D03*
Y1019665D03*
X484944Y1010216D03*
Y1021240D03*
Y1019665D03*
Y1018090D03*
Y1011791D03*
Y1014941D03*
Y1022815D03*
Y1016516D03*
Y1024390D03*
Y1013366D03*
X1380220Y1010216D03*
Y1022815D03*
Y1013366D03*
Y1011791D03*
Y1016516D03*
Y1018090D03*
Y1024390D03*
Y1014941D03*
Y1021240D03*
Y1019665D03*
X1399118Y1010216D03*
Y1021240D03*
Y1019665D03*
Y1018090D03*
Y1011791D03*
Y1014941D03*
Y1022815D03*
Y1016516D03*
Y1024390D03*
Y1013366D03*
G54D47*
X31623Y1463463D03*
X30543Y1479284D03*
X71404Y1452463D03*
X405498Y1524334D03*
X906950Y322671D03*
X905870Y335995D03*
X918458Y317736D03*
G54D66*
X43350Y1077095D03*
X344530Y1220701D03*
X354057Y1217750D03*
X356886Y1220579D03*
X351229Y1214922D03*
X347359Y1223528D03*
X350188Y1226357D03*
X353017Y1229186D03*
X362543Y1226236D03*
X808316Y1214922D03*
X813973Y1220579D03*
X811144Y1217750D03*
X801617Y1220701D03*
X807275Y1226357D03*
X804446Y1223528D03*
X810104Y1229186D03*
X819630Y1226236D03*
X890040Y1086098D03*
X954017D03*
X1258703Y1220701D03*
X1268230Y1217750D03*
X1271059Y1220579D03*
X1265402Y1214922D03*
X1261532Y1223528D03*
X1264361Y1226357D03*
X1267190Y1229186D03*
X1276716Y1226236D03*
X1715790Y1220701D03*
X1725317Y1217750D03*
X1722489Y1214922D03*
X1718619Y1223528D03*
X1721448Y1226357D03*
X1724277Y1229186D03*
X1728146Y1220579D03*
X1733803Y1226236D03*
X1797997Y1086584D03*
G54D57*
X42408Y511021D03*
X71691Y242569D03*
X61700Y511021D03*
X90983Y242569D03*
X174053D03*
X193345D03*
X276415D03*
X295707D03*
X378777D03*
X398069D03*
X411729Y414384D03*
X431021D03*
X499494Y511021D03*
X518786D03*
X528778Y242569D03*
X548070D03*
X631140D03*
X650432D03*
X733502D03*
X752794D03*
X835864D03*
X855156D03*
X905055Y430725D03*
X924347D03*
X956581Y511021D03*
X975873D03*
X985864Y242569D03*
X1005156D03*
X1088226D03*
X1107518D03*
X1190588D03*
X1209880D03*
X1292950D03*
X1312242D03*
X1325902Y414384D03*
X1345194D03*
X1413668Y511021D03*
X1432960D03*
X1442951Y242569D03*
X1462243D03*
X1545313D03*
X1564605D03*
X1647675D03*
X1666967D03*
X1750037D03*
X1769329D03*
X1782989Y414384D03*
X1802281D03*
G54D84*
X75692Y616665D03*
Y635957D03*
X100833Y271685D03*
Y290977D03*
X203195Y271685D03*
Y290977D03*
X305557Y271685D03*
Y290977D03*
X407919Y271685D03*
Y290977D03*
X412801Y380817D03*
Y400109D03*
X532778Y616665D03*
Y635957D03*
X557920Y271685D03*
Y290977D03*
X660282Y271685D03*
Y290977D03*
X762644Y271685D03*
Y290977D03*
X865006Y271685D03*
Y290977D03*
X908127Y397158D03*
Y416450D03*
X989865Y616665D03*
Y635957D03*
X1015006Y271685D03*
Y290977D03*
X1117368Y271685D03*
Y290977D03*
X1219730Y271685D03*
Y290977D03*
X1322092Y271685D03*
Y290977D03*
X1326974Y380817D03*
Y400109D03*
X1446952Y616665D03*
Y635957D03*
X1472093Y271685D03*
Y290977D03*
X1574455Y271685D03*
Y290977D03*
X1676817Y271685D03*
Y290977D03*
X1779179Y271685D03*
Y290977D03*
X1784061Y380817D03*
Y400109D03*
G54D93*
X117356Y1204388D03*
X108871Y1212873D03*
X131504Y1214174D03*
X128675Y1217002D03*
X123017Y1222659D03*
X120190Y1225487D03*
X565958Y1212873D03*
X574443Y1204388D03*
X588591Y1214174D03*
X585762Y1217002D03*
X580104Y1222659D03*
X577277Y1225487D03*
X1023044Y1212873D03*
X1031529Y1204388D03*
X1042848Y1217002D03*
X1037190Y1222659D03*
X1034363Y1225487D03*
X1045677Y1214174D03*
X1480131Y1212873D03*
X1488616Y1204388D03*
X1494277Y1222659D03*
X1491450Y1225487D03*
X1502764Y1214174D03*
X1499935Y1217002D03*
G54D39*
X17644Y1480986D03*
X10952D03*
X17644Y1489648D03*
X10952D03*
G54D177*
X832961Y311852D03*
Y314411D03*
Y316970D03*
Y319529D03*
Y322088D03*
Y324648D03*
Y327207D03*
Y332325D03*
Y329766D03*
Y334884D03*
X855993Y311852D03*
Y327207D03*
Y324648D03*
Y322088D03*
Y319529D03*
Y316970D03*
Y314411D03*
Y334884D03*
Y332325D03*
Y329766D03*
X1298246Y750962D03*
Y753521D03*
Y756080D03*
Y758639D03*
Y761198D03*
Y763758D03*
Y766317D03*
Y768876D03*
Y771435D03*
Y773994D03*
X1321278Y750962D03*
Y766317D03*
Y763758D03*
Y761198D03*
Y758639D03*
Y756080D03*
Y753521D03*
Y773994D03*
Y771435D03*
Y768876D03*
X1350984Y563984D03*
Y566543D03*
Y569102D03*
Y571661D03*
Y574220D03*
Y576780D03*
Y579339D03*
Y581898D03*
Y584457D03*
Y587016D03*
Y610484D03*
Y613043D03*
Y615602D03*
Y618161D03*
Y620720D03*
Y623280D03*
Y625839D03*
Y628398D03*
Y630957D03*
Y633516D03*
Y654984D03*
Y657543D03*
Y660102D03*
Y662661D03*
Y665220D03*
Y667780D03*
Y670339D03*
Y672898D03*
Y675457D03*
Y678016D03*
Y701984D03*
Y704543D03*
Y707102D03*
Y709661D03*
Y712220D03*
Y714780D03*
Y717339D03*
Y719898D03*
Y722457D03*
Y725016D03*
X1374016Y571661D03*
Y569102D03*
Y566543D03*
Y563984D03*
Y587016D03*
Y584457D03*
Y579339D03*
Y576780D03*
Y574220D03*
Y581898D03*
Y620720D03*
Y618161D03*
Y615602D03*
Y613043D03*
Y610484D03*
Y633516D03*
Y630957D03*
Y625839D03*
Y623280D03*
Y628398D03*
Y667780D03*
Y665220D03*
Y662661D03*
Y660102D03*
Y657543D03*
Y654984D03*
Y678016D03*
Y675457D03*
Y670339D03*
Y672898D03*
Y701984D03*
Y717339D03*
Y714780D03*
Y712220D03*
Y709661D03*
Y707102D03*
Y704543D03*
Y725016D03*
Y722457D03*
Y719898D03*
X1441984Y686484D03*
Y689043D03*
Y691602D03*
Y694161D03*
Y696720D03*
Y699280D03*
Y701839D03*
Y704398D03*
Y706957D03*
Y709516D03*
Y730484D03*
Y733043D03*
Y735602D03*
Y738161D03*
Y740720D03*
Y743280D03*
Y745839D03*
Y748398D03*
Y750957D03*
Y753516D03*
X1465016Y701839D03*
Y699280D03*
Y696720D03*
Y694161D03*
Y691602D03*
Y689043D03*
Y686484D03*
Y709516D03*
Y706957D03*
Y704398D03*
Y733043D03*
Y730484D03*
Y750957D03*
Y745839D03*
Y743280D03*
Y740720D03*
Y738161D03*
Y735602D03*
Y748398D03*
Y753516D03*
X1458984Y771984D03*
Y774543D03*
Y777102D03*
Y779661D03*
Y782220D03*
Y784780D03*
Y787339D03*
Y789898D03*
Y792457D03*
Y795016D03*
Y815984D03*
Y818543D03*
Y821102D03*
Y823661D03*
Y826220D03*
Y828780D03*
Y831339D03*
Y833898D03*
Y836457D03*
Y839016D03*
X1482016Y782220D03*
Y779661D03*
Y777102D03*
Y774543D03*
Y771984D03*
Y795016D03*
Y792457D03*
Y787339D03*
Y784780D03*
Y789898D03*
Y815984D03*
Y831339D03*
Y828780D03*
Y826220D03*
Y823661D03*
Y821102D03*
Y818543D03*
Y839016D03*
Y836457D03*
Y833898D03*
G54D159*
X553958Y744599D03*
Y747158D03*
Y749717D03*
X561832D03*
Y747158D03*
Y744599D03*
X699789Y697094D03*
Y699653D03*
Y702212D03*
X707663Y699653D03*
Y697094D03*
Y702212D03*
G54D168*
X766516Y1622460D03*
X759036D03*
Y1633090D03*
X762776D03*
X766516D03*
X944110Y1444139D03*
X939110D03*
X934110D03*
X949110D03*
X960268Y1444392D03*
X975268D03*
X970268D03*
X965268D03*
X993334D03*
X988334D03*
X983334D03*
X998334D03*
X1011366Y1444492D03*
X1006366D03*
X1021366D03*
X1016366D03*
X1039252Y1444608D03*
X1034252D03*
X1029252D03*
X1044252D03*
G54D75*
X56446Y829677D03*
X68652D03*
X56446Y831645D03*
X68652D03*
X56446Y837551D03*
X68652D03*
X56446Y833614D03*
Y835583D03*
X68652D03*
Y833614D03*
X573500Y943766D03*
X585706D03*
X573500Y951640D03*
X585706D03*
X573500Y945734D03*
Y947703D03*
Y949672D03*
X585706D03*
Y947703D03*
Y945734D03*
X995234Y838324D03*
Y846198D03*
Y840292D03*
Y842261D03*
Y844230D03*
X1007440Y846198D03*
Y838324D03*
Y844230D03*
Y842261D03*
Y840292D03*
X1015116Y940781D03*
X1027322D03*
X1015116Y942749D03*
Y944718D03*
X1027322D03*
Y942749D03*
X1015116Y948655D03*
X1027322D03*
X1015116Y946687D03*
X1027322D03*
X1789760Y971619D03*
Y973587D03*
Y975556D03*
Y977525D03*
Y979493D03*
X1801966Y971619D03*
Y977525D03*
Y975556D03*
Y973587D03*
Y979493D03*
G54D186*
X887685Y569450D03*
Y571419D03*
Y575356D03*
Y579293D03*
Y583230D03*
Y585199D03*
Y577325D03*
Y587167D03*
Y573387D03*
Y581261D03*
Y589136D03*
X912291Y571419D03*
Y569450D03*
Y585199D03*
Y581261D03*
Y577325D03*
Y579293D03*
Y587167D03*
Y573387D03*
Y575356D03*
Y583230D03*
Y589136D03*
X1010047Y322072D03*
Y326009D03*
Y327978D03*
Y324041D03*
Y329947D03*
Y333883D03*
Y337821D03*
Y339789D03*
Y331915D03*
Y341758D03*
Y335852D03*
X1034653Y327978D03*
Y326009D03*
Y324041D03*
Y322072D03*
Y341758D03*
Y337821D03*
Y335852D03*
Y331915D03*
Y339789D03*
Y333883D03*
Y329947D03*
G54D195*
X910492Y311046D03*
Y309471D03*
X904704Y311046D03*
Y309471D03*
X910492Y312621D03*
X904704D03*
G36*
G01X51103Y1510814D02*
G02X50906Y1510617I-197J0D01*
G01X47520D01*
G02X47323Y1510814I0J197D01*
G01Y1514200D01*
G02X47520Y1514397I197J0D01*
G01X48963D01*
Y1515184D01*
X47520D01*
G02X47323Y1515381I0J197D01*
G01Y1518767D01*
G02X47520Y1518964I197J0D01*
G01X48963D01*
Y1519751D01*
X47520D01*
G02X47323Y1519948I0J197D01*
G01Y1521391D01*
X46536D01*
Y1519948D01*
G02X46339Y1519751I-197J0D01*
G01X44896D01*
Y1518964D01*
X46339D01*
G02X46536Y1518767I0J-197D01*
G01Y1515381D01*
G02X46339Y1515184I-197J0D01*
G01X44896D01*
Y1514397D01*
X46339D01*
G02X46536Y1514200I0J-197D01*
G01Y1510814D01*
G02X46339Y1510617I-197J0D01*
G01X42953D01*
G02X42756Y1510814I0J197D01*
G01Y1514200D01*
G02X42953Y1514397I197J0D01*
G01X44396D01*
Y1515184D01*
X42953D01*
G02X42756Y1515381I0J197D01*
G01Y1518767D01*
G02X42953Y1518964I197J0D01*
G01X44396D01*
Y1519751D01*
X42953D01*
G02X42756Y1519948I0J197D01*
G01Y1521391D01*
X41969D01*
Y1519948D01*
G02X41772Y1519751I-197J0D01*
G01X40329D01*
Y1518964D01*
X41772D01*
G02X41969Y1518767I0J-197D01*
G01Y1515381D01*
G02X41772Y1515184I-197J0D01*
G01X40329D01*
Y1514397D01*
X41772D01*
G02X41969Y1514200I0J-197D01*
G01Y1510814D01*
G02X41772Y1510617I-197J0D01*
G01X38386D01*
G02X38189Y1510814I0J197D01*
G01Y1514200D01*
G02X38386Y1514397I197J0D01*
G01X39829D01*
Y1515184D01*
X38386D01*
G02X38189Y1515381I0J197D01*
G01Y1518767D01*
G02X38386Y1518964I197J0D01*
G01X39829D01*
Y1519751D01*
X38386D01*
G02X38189Y1519948I0J197D01*
G01Y1521391D01*
X37402D01*
Y1519948D01*
G02X37205Y1519751I-197J0D01*
G01X35762D01*
Y1518964D01*
X37205D01*
G02X37402Y1518767I0J-197D01*
G01Y1515381D01*
G02X37205Y1515184I-197J0D01*
G01X35762D01*
Y1514397D01*
X37205D01*
G02X37402Y1514200I0J-197D01*
G01Y1510814D01*
G02X37205Y1510617I-197J0D01*
G01X33819D01*
G02X33622Y1510814I0J197D01*
G01Y1514200D01*
G02X33819Y1514397I197J0D01*
G01X35262D01*
Y1515184D01*
X33819D01*
G02X33622Y1515381I0J197D01*
G01Y1518767D01*
G02X33819Y1518964I197J0D01*
G01X35262D01*
Y1519751D01*
X33819D01*
G02X33622Y1519948I0J197D01*
G01Y1521391D01*
X32835D01*
Y1519948D01*
G02X32638Y1519751I-197J0D01*
G01X31195D01*
Y1518964D01*
X32638D01*
G02X32835Y1518767I0J-197D01*
G01Y1515381D01*
G02X32638Y1515184I-197J0D01*
G01X31195D01*
Y1514397D01*
X32638D01*
G02X32835Y1514200I0J-197D01*
G01Y1510814D01*
G02X32638Y1510617I-197J0D01*
G01X29252D01*
G02X29055Y1510814I0J197D01*
G01Y1514200D01*
G02X29252Y1514397I197J0D01*
G01X30695D01*
Y1515184D01*
X29252D01*
G02X29055Y1515381I0J197D01*
G01Y1518767D01*
G02X29252Y1518964I197J0D01*
G01X30695D01*
Y1519751D01*
X29252D01*
G02X29055Y1519948I0J197D01*
G01Y1523334D01*
G02X29252Y1523531I197J0D01*
G01X30695D01*
Y1524318D01*
X29252D01*
G02X29055Y1524515I0J197D01*
G01Y1527901D01*
G02X29252Y1528098I197J0D01*
G01X30695D01*
Y1528885D01*
X29252D01*
G02X29055Y1529082I0J197D01*
G01Y1532468D01*
G02X29252Y1532665I197J0D01*
G01X32638D01*
G02X32835Y1532468I0J-197D01*
G01Y1529082D01*
G02X32638Y1528885I-197J0D01*
G01X31195D01*
Y1528098D01*
X32638D01*
G02X32835Y1527901I0J-197D01*
G01Y1524515D01*
G02X32638Y1524318I-197J0D01*
G01X31195D01*
Y1523531D01*
X32638D01*
G02X32835Y1523334I0J-197D01*
G01Y1521891D01*
X33622D01*
Y1523334D01*
G02X33819Y1523531I197J0D01*
G01X35262D01*
Y1524318D01*
X33819D01*
G02X33622Y1524515I0J197D01*
G01Y1527901D01*
G02X33819Y1528098I197J0D01*
G01X35262D01*
Y1528885D01*
X33819D01*
G02X33622Y1529082I0J197D01*
G01Y1532468D01*
G02X33819Y1532665I197J0D01*
G01X37205D01*
G02X37402Y1532468I0J-197D01*
G01Y1529082D01*
G02X37205Y1528885I-197J0D01*
G01X35762D01*
Y1528098D01*
X37205D01*
G02X37402Y1527901I0J-197D01*
G01Y1524515D01*
G02X37205Y1524318I-197J0D01*
G01X35762D01*
Y1523531D01*
X37205D01*
G02X37402Y1523334I0J-197D01*
G01Y1521891D01*
X38189D01*
Y1523334D01*
G02X38386Y1523531I197J0D01*
G01X39829D01*
Y1524318D01*
X38386D01*
G02X38189Y1524515I0J197D01*
G01Y1527901D01*
G02X38386Y1528098I197J0D01*
G01X39829D01*
Y1528885D01*
X38386D01*
G02X38189Y1529082I0J197D01*
G01Y1532468D01*
G02X38386Y1532665I197J0D01*
G01X41772D01*
G02X41969Y1532468I0J-197D01*
G01Y1529082D01*
G02X41772Y1528885I-197J0D01*
G01X40329D01*
Y1528098D01*
X41772D01*
G02X41969Y1527901I0J-197D01*
G01Y1524515D01*
G02X41772Y1524318I-197J0D01*
G01X40329D01*
Y1523531D01*
X41772D01*
G02X41969Y1523334I0J-197D01*
G01Y1521891D01*
X42756D01*
Y1523334D01*
G02X42953Y1523531I197J0D01*
G01X44396D01*
Y1524318D01*
X42953D01*
G02X42756Y1524515I0J197D01*
G01Y1527901D01*
G02X42953Y1528098I197J0D01*
G01X44396D01*
Y1528885D01*
X42953D01*
G02X42756Y1529082I0J197D01*
G01Y1532468D01*
G02X42953Y1532665I197J0D01*
G01X46339D01*
G02X46536Y1532468I0J-197D01*
G01Y1529082D01*
G02X46339Y1528885I-197J0D01*
G01X44896D01*
Y1528098D01*
X46339D01*
G02X46536Y1527901I0J-197D01*
G01Y1524515D01*
G02X46339Y1524318I-197J0D01*
G01X44896D01*
Y1523531D01*
X46339D01*
G02X46536Y1523334I0J-197D01*
G01Y1521891D01*
X47323D01*
Y1523334D01*
G02X47520Y1523531I197J0D01*
G01X48963D01*
Y1524318D01*
X47520D01*
G02X47323Y1524515I0J197D01*
G01Y1527901D01*
G02X47520Y1528098I197J0D01*
G01X48963D01*
Y1528885D01*
X47520D01*
G02X47323Y1529082I0J197D01*
G01Y1532468D01*
G02X47520Y1532665I197J0D01*
G01X50906D01*
G02X51103Y1532468I0J-197D01*
G01Y1529082D01*
G02X50906Y1528885I-197J0D01*
G01X49463D01*
Y1528098D01*
X50906D01*
G02X51103Y1527901I0J-197D01*
G01Y1524515D01*
G02X50906Y1524318I-197J0D01*
G01X49463D01*
Y1523531D01*
X50906D01*
G02X51103Y1523334I0J-197D01*
G01Y1519948D01*
G02X50906Y1519751I-197J0D01*
G01X49463D01*
Y1518964D01*
X50906D01*
G02X51103Y1518767I0J-197D01*
G01Y1515381D01*
G02X50906Y1515184I-197J0D01*
G01X49463D01*
Y1514397D01*
X50906D01*
G02X51103Y1514200I0J-197D01*
G01Y1510814D01*
G37*
G54D196*
X911630Y533706D03*
Y540006D03*
X919976D03*
Y533706D03*
G54D67*
X39062Y1200716D03*
X41424D03*
Y1210952D03*
X417631Y881916D03*
X415269Y871680D03*
Y881916D03*
X431394Y627843D03*
X433756Y638079D03*
Y627843D03*
X882752Y1209719D03*
X885114Y1219955D03*
Y1209719D03*
X946729D03*
X949091Y1219955D03*
Y1209719D03*
X1790709Y1210205D03*
X1793071Y1220441D03*
Y1210205D03*
G54D178*
X836701Y758161D03*
Y760720D03*
Y763280D03*
Y765839D03*
Y776161D03*
Y778720D03*
Y781280D03*
Y783839D03*
Y794161D03*
Y796720D03*
Y799280D03*
Y801839D03*
Y812161D03*
Y814720D03*
Y817280D03*
Y819839D03*
X854299Y765839D03*
Y763280D03*
Y760720D03*
Y758161D03*
Y781280D03*
Y778720D03*
Y776161D03*
Y783839D03*
Y799280D03*
Y796720D03*
Y794161D03*
Y801839D03*
Y814720D03*
Y812161D03*
Y819839D03*
Y817280D03*
G54D187*
X894082Y566990D03*
X892114D03*
X890145D03*
X896051D03*
X890145Y591596D03*
X894082D03*
X896051D03*
X892114D03*
X901956Y566990D03*
X898020D03*
X909831D03*
X899988D03*
X905894D03*
X903925D03*
X907862D03*
X899988Y591596D03*
X903925D03*
X905894D03*
X907862D03*
X898020D03*
X909831D03*
X901956D03*
X1024318Y319612D03*
X1020382D03*
X1014476D03*
X1022350D03*
X1016444D03*
X1018413D03*
X1026287D03*
X1012507D03*
Y344218D03*
X1018413D03*
X1022350D03*
X1026287D03*
X1020382D03*
X1016444D03*
X1014476D03*
X1024318D03*
X1032193Y319612D03*
X1028256D03*
X1030224D03*
X1028256Y344218D03*
X1032193D03*
X1030224D03*
G54D169*
X782289Y1623876D03*
X786029Y1614546D03*
X789769Y1623876D03*
G54D85*
X76388Y670837D03*
X74419D03*
X78356Y678711D03*
X74419D03*
X76388D03*
X80325D03*
Y670837D03*
X78356D03*
G54D58*
X51160Y613799D03*
X49192D03*
X47224D03*
X45255D03*
X43286D03*
X41318D03*
X51160Y624823D03*
X47224D03*
X49192D03*
X43286D03*
X45255D03*
X41318D03*
X57066Y613799D03*
X55098D03*
X53129D03*
X55098Y624823D03*
X53129D03*
X425641Y449550D03*
X421705D03*
X506278Y613799D03*
X504310D03*
X502341D03*
X500372D03*
X498404D03*
X504310Y624823D03*
X506278D03*
X500372D03*
X502341D03*
X498404D03*
X514152Y613799D03*
X512184D03*
X510215D03*
X508246D03*
Y624823D03*
X512184D03*
X510215D03*
X920967Y465891D03*
X917031D03*
X961397Y613799D03*
X959428D03*
X957459D03*
X955491D03*
X961397Y624823D03*
X957459D03*
X959428D03*
X955491D03*
X971239Y613799D03*
X969271D03*
X967302D03*
X965333D03*
X963365D03*
X965333Y624823D03*
X969271D03*
X963365D03*
X967302D03*
X1339814Y449550D03*
X1335878D03*
X1416515Y613799D03*
X1414546D03*
X1412578D03*
X1414546Y624823D03*
X1416515D03*
X1412578D03*
X1428326Y613799D03*
X1426358D03*
X1424389D03*
X1422420D03*
X1420452D03*
X1418484D03*
X1422420Y624823D03*
X1418484D03*
X1426358D03*
X1420452D03*
X1424389D03*
X1796901Y449550D03*
X1792965D03*
G54D49*
X22756Y1506877D03*
Y1508846D03*
Y1510814D03*
Y1512783D03*
Y1514751D03*
Y1516720D03*
Y1518688D03*
Y1520657D03*
Y1522625D03*
Y1524594D03*
Y1526562D03*
Y1528531D03*
Y1530499D03*
Y1532468D03*
Y1534436D03*
Y1536405D03*
X57402Y1512783D03*
Y1510814D03*
Y1508846D03*
Y1506877D03*
Y1528531D03*
Y1526562D03*
Y1524594D03*
Y1522625D03*
Y1520657D03*
Y1518688D03*
Y1516720D03*
Y1514751D03*
Y1536405D03*
Y1534436D03*
Y1532468D03*
Y1530499D03*
G54D94*
X112430Y1205118D03*
X109601Y1207947D03*
X103591Y1213957D03*
X115265Y1226217D03*
X123749Y1217733D03*
X132235Y1209248D03*
X349826Y401783D03*
X569517Y1205118D03*
X566688Y1207947D03*
X560678Y1213957D03*
X572352Y1226217D03*
X580836Y1217733D03*
X589322Y1209248D03*
X1026603Y1205118D03*
X1023774Y1207947D03*
X1017764Y1213957D03*
X1037922Y1217733D03*
X1029438Y1226217D03*
X1046408Y1209248D03*
X1263999Y401783D03*
X1480861Y1207947D03*
X1474851Y1213957D03*
X1483690Y1205118D03*
X1495009Y1217733D03*
X1486525Y1226217D03*
X1503495Y1209248D03*
X1721086Y401783D03*
G54D76*
X62549Y833614D03*
X579603Y947703D03*
X1001337Y842261D03*
X1021219Y944718D03*
X1795863Y975556D03*
G54D86*
X77372Y674774D03*
G54D197*
X934878Y1555045D03*
X971690D03*
G54D68*
X45558Y1199141D03*
X411135Y883491D03*
X437890Y626268D03*
X889248Y1208144D03*
X953225D03*
X1797205Y1208630D03*
G54D77*
X59134Y875295D03*
Y870295D03*
Y880295D03*
Y885295D03*
Y890295D03*
Y895295D03*
Y905295D03*
Y900295D03*
X96930Y875295D03*
Y880295D03*
Y870295D03*
Y885295D03*
Y890295D03*
Y895295D03*
Y905295D03*
Y900295D03*
X516074Y875295D03*
Y870295D03*
Y880295D03*
Y885295D03*
Y890295D03*
Y895295D03*
Y905295D03*
Y900295D03*
X553870Y875295D03*
Y880295D03*
Y870295D03*
Y885295D03*
Y890295D03*
Y895295D03*
Y905295D03*
Y900295D03*
X972833Y870295D03*
Y875295D03*
Y880295D03*
Y885295D03*
Y890295D03*
Y895295D03*
Y900295D03*
Y905295D03*
X1010629Y880295D03*
Y875295D03*
Y870295D03*
Y895295D03*
Y890295D03*
Y885295D03*
Y905295D03*
Y900295D03*
X1430247Y875295D03*
Y870295D03*
Y880295D03*
Y885295D03*
Y890295D03*
Y895295D03*
Y905295D03*
Y900295D03*
X1468043Y875295D03*
Y880295D03*
Y870295D03*
Y885295D03*
Y890295D03*
Y895295D03*
Y905295D03*
Y900295D03*
G54D179*
X863687Y1443780D03*
X861718D03*
X859750D03*
Y1461398D03*
X861718D03*
X863687D03*
X869592Y1443780D03*
X867624D03*
X865655D03*
Y1461398D03*
X867624D03*
X869592D03*
X911592Y1443780D03*
X909624D03*
X907655D03*
X905687D03*
X903718D03*
X901750D03*
Y1461398D03*
X903718D03*
X905687D03*
X907655D03*
X909624D03*
X911592D03*
G54D59*
X42893Y619311D03*
X46436D03*
X49979D03*
X53523D03*
X499979D03*
X503522D03*
X507065D03*
X510609D03*
X957066D03*
X960609D03*
X964152D03*
X967696D03*
X1414153D03*
X1417696D03*
X1421239D03*
X1424783D03*
G54D95*
X111700Y1210046D03*
X114529Y1207217D03*
X105690Y1216056D03*
X117364Y1228316D03*
X125848Y1219832D03*
X134334Y1211347D03*
X351925Y403882D03*
X568787Y1210046D03*
X571616Y1207217D03*
X562777Y1216056D03*
X582935Y1219832D03*
X574451Y1228316D03*
X591421Y1211347D03*
X1025873Y1210046D03*
X1019863Y1216056D03*
X1028702Y1207217D03*
X1040021Y1219832D03*
X1031537Y1228316D03*
X1048507Y1211347D03*
X1266098Y403882D03*
X1476950Y1216056D03*
X1497108Y1219832D03*
X1482960Y1210046D03*
X1485789Y1207217D03*
X1488624Y1228316D03*
X1505594Y1211347D03*
X1723185Y403882D03*
G54D188*
X884732Y570435D03*
Y568466D03*
Y566498D03*
Y572403D03*
Y586183D03*
Y584214D03*
Y582246D03*
Y580277D03*
Y578309D03*
Y576340D03*
Y574372D03*
Y592088D03*
Y590120D03*
Y588151D03*
X915244Y566498D03*
Y568466D03*
Y570435D03*
Y572403D03*
Y574372D03*
Y576340D03*
Y578309D03*
Y580277D03*
Y582246D03*
Y584214D03*
Y586183D03*
Y588151D03*
Y590120D03*
Y592088D03*
X1007094Y321088D03*
Y323057D03*
Y325025D03*
Y326994D03*
Y319120D03*
Y332899D03*
Y334868D03*
Y328962D03*
Y330931D03*
Y342742D03*
Y340773D03*
Y338805D03*
Y336836D03*
Y344710D03*
X1037606Y319120D03*
Y321088D03*
Y323057D03*
Y325025D03*
Y326994D03*
Y330931D03*
Y332899D03*
Y334868D03*
Y336836D03*
Y338805D03*
Y340773D03*
Y342742D03*
Y328962D03*
Y344710D03*
G54D78*
X58308Y880295D03*
Y875295D03*
Y870295D03*
Y885295D03*
Y890295D03*
Y895295D03*
Y905295D03*
Y900295D03*
X97126Y875295D03*
Y880295D03*
Y870295D03*
Y895295D03*
Y890295D03*
Y885295D03*
Y905295D03*
Y900295D03*
X515248Y880295D03*
Y875295D03*
Y870295D03*
Y885295D03*
Y890295D03*
Y895295D03*
Y905295D03*
Y900295D03*
X554066Y875295D03*
Y880295D03*
Y870295D03*
Y895295D03*
Y890295D03*
Y885295D03*
Y905295D03*
Y900295D03*
X972637Y880295D03*
Y875295D03*
Y870295D03*
Y885295D03*
Y890295D03*
Y895295D03*
Y905295D03*
Y900295D03*
X1011455Y875295D03*
Y880295D03*
Y870295D03*
Y895295D03*
Y890295D03*
Y885295D03*
Y905295D03*
Y900295D03*
X1429421Y880295D03*
Y875295D03*
Y870295D03*
Y885295D03*
Y890295D03*
Y895295D03*
Y905295D03*
Y900295D03*
X1468239Y875295D03*
Y880295D03*
Y870295D03*
Y895295D03*
Y890295D03*
Y885295D03*
Y905295D03*
Y900295D03*
G54D198*
X938526Y719903D03*
X946086Y712147D03*
Y719903D03*
G54D87*
X76012Y1355193D03*
Y1353093D03*
X79612Y1355193D03*
Y1353093D03*
X76012Y1379391D03*
Y1377291D03*
X79612Y1379391D03*
Y1377291D03*
X100492Y1355193D03*
Y1353093D03*
X91852Y1355193D03*
Y1353093D03*
X88252Y1355193D03*
Y1353093D03*
X100492Y1379391D03*
Y1377291D03*
X91852Y1379391D03*
Y1377291D03*
X88252Y1379391D03*
Y1377291D03*
Y1403589D03*
Y1401489D03*
X91852Y1403589D03*
Y1401489D03*
X100492Y1403589D03*
Y1401489D03*
X103001Y1035088D03*
Y1032988D03*
X106113Y1035102D03*
Y1033002D03*
X110430Y1105228D03*
Y1107328D03*
Y1130428D03*
Y1132528D03*
Y1143028D03*
Y1145128D03*
Y1168228D03*
Y1170328D03*
Y1180828D03*
Y1182928D03*
X104092Y1355193D03*
Y1353093D03*
X116332Y1355193D03*
Y1353093D03*
X112732Y1355193D03*
Y1353093D03*
X116332Y1379391D03*
Y1377291D03*
X104092Y1379391D03*
Y1377291D03*
X112732Y1379391D03*
Y1377291D03*
X116332Y1403589D03*
Y1401489D03*
X112732Y1403589D03*
Y1401489D03*
X104092Y1403589D03*
Y1401489D03*
X122076Y1012491D03*
Y1014591D03*
Y1025091D03*
Y1027191D03*
X124972Y1355193D03*
Y1353093D03*
X128572Y1355193D03*
Y1353093D03*
Y1379391D03*
Y1377291D03*
X124972Y1379391D03*
Y1377291D03*
X128572Y1403589D03*
Y1401489D03*
X124972Y1403589D03*
Y1401489D03*
X149452Y1355193D03*
Y1353093D03*
X137212Y1355193D03*
Y1353093D03*
X140812Y1355193D03*
Y1353093D03*
X149452Y1379391D03*
Y1377291D03*
X137212Y1379391D03*
Y1377291D03*
X140812Y1379391D03*
Y1377291D03*
X149452Y1403589D03*
Y1401489D03*
X137212Y1403589D03*
Y1401489D03*
X140812Y1403589D03*
Y1401489D03*
X165292Y1355193D03*
Y1353093D03*
X161692Y1355193D03*
Y1353093D03*
X153052Y1355193D03*
Y1353093D03*
X165292Y1379391D03*
Y1377291D03*
X161692Y1379391D03*
Y1377291D03*
X153052Y1379391D03*
Y1377291D03*
X161692Y1403589D03*
Y1401489D03*
X165292Y1403589D03*
Y1401489D03*
X153052Y1403589D03*
Y1401489D03*
X173932Y1355193D03*
Y1353093D03*
X177532Y1355193D03*
Y1353093D03*
X173932Y1379391D03*
Y1377291D03*
X177532Y1379391D03*
Y1377291D03*
X173932Y1403589D03*
Y1401489D03*
X177532Y1403589D03*
Y1401489D03*
X198412Y1355193D03*
Y1353093D03*
X189772Y1355193D03*
Y1353093D03*
X186172Y1355193D03*
Y1353093D03*
X198412Y1379391D03*
Y1377291D03*
X189772Y1379391D03*
Y1377291D03*
X186172Y1379391D03*
Y1377291D03*
X198412Y1403589D03*
Y1401489D03*
X189772Y1403589D03*
Y1401489D03*
X186172Y1403589D03*
Y1401489D03*
X202012Y1355193D03*
Y1353093D03*
Y1379391D03*
Y1377291D03*
Y1403589D03*
Y1401489D03*
X245123Y1355193D03*
Y1353093D03*
X241523Y1355193D03*
Y1353093D03*
X245123Y1379391D03*
Y1377291D03*
X241523Y1379391D03*
Y1377291D03*
X253763Y1355193D03*
Y1353093D03*
X257363Y1355193D03*
Y1353093D03*
Y1379391D03*
Y1377291D03*
X253763Y1379391D03*
Y1377291D03*
Y1403589D03*
Y1401489D03*
X257363Y1403589D03*
Y1401489D03*
X266003Y1355193D03*
Y1353093D03*
X269603Y1355193D03*
Y1353093D03*
X278243Y1355193D03*
Y1353093D03*
X266003Y1379391D03*
Y1377291D03*
X269603Y1379391D03*
Y1377291D03*
X278243Y1379391D03*
Y1377291D03*
X269603Y1403589D03*
Y1401489D03*
X266003Y1403589D03*
Y1401489D03*
X278243Y1403589D03*
Y1401489D03*
X281843Y1355193D03*
Y1353093D03*
X290483Y1355193D03*
Y1353093D03*
X294083Y1355193D03*
Y1353093D03*
X281843Y1379391D03*
Y1377291D03*
X290483Y1379391D03*
Y1377291D03*
X294083Y1379391D03*
Y1377291D03*
X281843Y1403589D03*
Y1401489D03*
X290483Y1403589D03*
Y1401489D03*
X294083Y1403589D03*
Y1401489D03*
X306323Y1355193D03*
Y1353093D03*
X302723Y1355193D03*
Y1353093D03*
X306323Y1379391D03*
Y1377291D03*
X302723Y1379391D03*
Y1377291D03*
Y1403589D03*
Y1401489D03*
X306323Y1403589D03*
Y1401489D03*
X327203Y1355193D03*
Y1353093D03*
X314963Y1355193D03*
Y1353093D03*
X318563Y1355193D03*
Y1353093D03*
X327203Y1379391D03*
Y1377291D03*
X318563Y1379391D03*
Y1377291D03*
X314963Y1379391D03*
Y1377291D03*
X327203Y1403589D03*
Y1401489D03*
X318563Y1403589D03*
Y1401489D03*
X314963Y1403589D03*
Y1401489D03*
X343043Y1355193D03*
Y1353093D03*
X339443Y1355193D03*
Y1353093D03*
X330803Y1355193D03*
Y1353093D03*
X339443Y1379391D03*
Y1377291D03*
X343043Y1379391D03*
Y1377291D03*
X330803Y1379391D03*
Y1377291D03*
X343043Y1403589D03*
Y1401489D03*
X339443Y1403589D03*
Y1401489D03*
X330803Y1403589D03*
Y1401489D03*
X355283Y1355193D03*
Y1353093D03*
X351683Y1355193D03*
Y1353093D03*
Y1379391D03*
Y1377291D03*
X355283Y1379391D03*
Y1377291D03*
Y1403589D03*
Y1401489D03*
X351683Y1403589D03*
Y1401489D03*
X367523Y1355193D03*
Y1353093D03*
X363923Y1355193D03*
Y1353093D03*
Y1379391D03*
Y1377291D03*
X367523Y1379391D03*
Y1377291D03*
Y1403589D03*
Y1401489D03*
X363923Y1403589D03*
Y1401489D03*
X440302Y1355193D03*
Y1353093D03*
Y1379391D03*
Y1377291D03*
X452542Y1355193D03*
Y1353093D03*
X456142Y1355193D03*
Y1353093D03*
X443902Y1355193D03*
Y1353093D03*
X452542Y1379391D03*
Y1377291D03*
X456142Y1379391D03*
Y1377291D03*
X443902Y1379391D03*
Y1377291D03*
X452542Y1403589D03*
Y1401489D03*
X456142Y1403589D03*
Y1401489D03*
X468382Y1355193D03*
Y1353093D03*
X464782Y1355193D03*
Y1353093D03*
Y1379391D03*
Y1377291D03*
X468382Y1379391D03*
Y1377291D03*
X464782Y1403589D03*
Y1401489D03*
X468382Y1403589D03*
Y1401489D03*
X477022Y1355193D03*
Y1353093D03*
X480622Y1355193D03*
Y1353093D03*
X489262Y1355193D03*
Y1353093D03*
X477022Y1379391D03*
Y1377291D03*
X489262Y1379391D03*
Y1377291D03*
X480622Y1379391D03*
Y1377291D03*
X489262Y1403589D03*
Y1401489D03*
X477022Y1403589D03*
Y1401489D03*
X480622Y1403589D03*
Y1401489D03*
X505102Y1355193D03*
Y1353093D03*
X501502Y1355193D03*
Y1353093D03*
X492862Y1355193D03*
Y1353093D03*
X505102Y1379391D03*
Y1377291D03*
X501502Y1379391D03*
Y1377291D03*
X492862Y1379391D03*
Y1377291D03*
X505102Y1403589D03*
Y1401489D03*
X501502Y1403589D03*
Y1401489D03*
X492862Y1403589D03*
Y1401489D03*
X517342Y1355193D03*
Y1353093D03*
X513742Y1355193D03*
Y1353093D03*
X517342Y1379391D03*
Y1377291D03*
X513742Y1379391D03*
Y1377291D03*
Y1403589D03*
Y1401489D03*
X517342Y1403589D03*
Y1401489D03*
X529582Y1355193D03*
Y1353093D03*
X538222Y1355193D03*
Y1353093D03*
X525982Y1355193D03*
Y1353093D03*
X538222Y1379391D03*
Y1377291D03*
X525982Y1379391D03*
Y1377291D03*
X529582Y1379391D03*
Y1377291D03*
X538222Y1403589D03*
Y1401489D03*
X529582Y1403589D03*
Y1401489D03*
X525982Y1403589D03*
Y1401489D03*
X555395Y1035088D03*
Y1032988D03*
X554062Y1355193D03*
Y1353093D03*
X550462Y1355193D03*
Y1353093D03*
X541822Y1355193D03*
Y1353093D03*
X550462Y1379391D03*
Y1377291D03*
X554062Y1379391D03*
Y1377291D03*
X541822Y1379391D03*
Y1377291D03*
X554062Y1403589D03*
Y1401489D03*
X550462Y1403589D03*
Y1401489D03*
X541822Y1403589D03*
Y1401489D03*
X563200Y1035102D03*
Y1033002D03*
X560088Y1035088D03*
Y1032988D03*
X567517Y1105228D03*
Y1107328D03*
Y1117828D03*
Y1119928D03*
Y1130428D03*
Y1132528D03*
Y1143028D03*
Y1145128D03*
Y1155628D03*
Y1157728D03*
Y1180828D03*
Y1182928D03*
X566302Y1355193D03*
Y1353093D03*
X562702Y1355193D03*
Y1353093D03*
Y1379391D03*
Y1377291D03*
X566302Y1379391D03*
Y1377291D03*
Y1403589D03*
Y1401489D03*
X562702Y1403589D03*
Y1401489D03*
X579163Y1012491D03*
Y1014591D03*
Y1025091D03*
Y1027191D03*
X629788Y1403589D03*
Y1401489D03*
X626188Y1403589D03*
Y1401489D03*
X650668Y1355193D03*
Y1353093D03*
Y1379391D03*
Y1377291D03*
X642028Y1379391D03*
Y1377291D03*
X638428Y1379391D03*
Y1377291D03*
X650668Y1403589D03*
Y1401489D03*
X642028Y1403589D03*
Y1401489D03*
X638428Y1403589D03*
Y1401489D03*
X666508Y1355193D03*
Y1353093D03*
X662908Y1355193D03*
Y1353093D03*
X654268Y1355193D03*
Y1353093D03*
Y1379391D03*
Y1377291D03*
X662908Y1379391D03*
Y1377291D03*
X666508Y1379391D03*
Y1377291D03*
X654268Y1403589D03*
Y1401489D03*
X666508Y1403589D03*
Y1401489D03*
X662908Y1403589D03*
Y1401489D03*
X678748Y1355193D03*
Y1353093D03*
X675148Y1355193D03*
Y1353093D03*
X678748Y1379391D03*
Y1377291D03*
X675148Y1379391D03*
Y1377291D03*
X678748Y1403589D03*
Y1401489D03*
X675148Y1403589D03*
Y1401489D03*
X699628Y1355193D03*
Y1353093D03*
X690988Y1355193D03*
Y1353093D03*
X687388Y1355193D03*
Y1353093D03*
X699628Y1379391D03*
Y1377291D03*
X690988Y1379391D03*
Y1377291D03*
X687388Y1379391D03*
Y1377291D03*
X699628Y1403589D03*
Y1401489D03*
X690988Y1403589D03*
Y1401489D03*
X687388Y1403589D03*
Y1401489D03*
X715468Y1355193D03*
Y1353093D03*
X711868Y1355193D03*
Y1353093D03*
X703228Y1355193D03*
Y1353093D03*
X711868Y1379391D03*
Y1377291D03*
X715468Y1379391D03*
Y1377291D03*
X703228Y1379391D03*
Y1377291D03*
X715468Y1403589D03*
Y1401489D03*
X711868Y1403589D03*
Y1401489D03*
X703228Y1403589D03*
Y1401489D03*
X727708Y1355193D03*
Y1353093D03*
X724108Y1355193D03*
Y1353093D03*
Y1379391D03*
Y1377291D03*
X727708Y1379391D03*
Y1377291D03*
X724108Y1403495D03*
Y1401395D03*
X727708Y1403495D03*
Y1401395D03*
X748588Y1355193D03*
Y1353093D03*
X739948Y1355193D03*
Y1353093D03*
X736348Y1355193D03*
Y1353093D03*
X748588Y1379391D03*
Y1377291D03*
X736348Y1379391D03*
Y1377291D03*
X739948Y1379391D03*
Y1377291D03*
X736348Y1403495D03*
Y1401395D03*
X739948Y1403495D03*
Y1401395D03*
X752188Y1355193D03*
Y1353093D03*
X760828Y1355193D03*
Y1353093D03*
X764428Y1355193D03*
Y1353093D03*
X760828Y1379391D03*
Y1377291D03*
X764428Y1379391D03*
Y1377291D03*
X752188Y1379391D03*
Y1377291D03*
X776668Y1355193D03*
Y1353093D03*
X773068Y1355193D03*
Y1353093D03*
X896371Y1073980D03*
Y1076080D03*
X899583Y1074008D03*
X906117Y1074004D03*
X902986Y1073977D03*
X899583Y1076108D03*
X906117Y1076104D03*
X902986Y1076077D03*
X1012517Y1035088D03*
Y1032988D03*
X1020286Y1035102D03*
Y1033002D03*
X1017174Y1035088D03*
Y1032988D03*
X1024603Y1105228D03*
Y1107328D03*
Y1117828D03*
Y1119928D03*
Y1130428D03*
Y1132528D03*
Y1143028D03*
Y1145128D03*
Y1155628D03*
Y1157728D03*
Y1180828D03*
Y1182928D03*
X1036249Y1012491D03*
Y1014591D03*
Y1025091D03*
Y1027191D03*
X1058213Y1355193D03*
Y1353093D03*
X1054613Y1355193D03*
Y1353093D03*
X1058213Y1379391D03*
Y1377291D03*
X1054613Y1379391D03*
Y1377291D03*
X1070453Y1355193D03*
Y1353093D03*
X1066853Y1355193D03*
Y1353093D03*
Y1379391D03*
Y1377291D03*
X1070453Y1379391D03*
Y1377291D03*
Y1403589D03*
Y1401489D03*
X1066853Y1403589D03*
Y1401489D03*
X1082693Y1355193D03*
Y1353093D03*
X1079093Y1355193D03*
Y1353093D03*
X1091333Y1355193D03*
Y1353093D03*
X1079093Y1379391D03*
Y1377291D03*
X1082693Y1379391D03*
Y1377291D03*
X1091333Y1379391D03*
Y1377291D03*
X1079093Y1403589D03*
Y1401489D03*
X1082693Y1403589D03*
Y1401489D03*
X1091333Y1403589D03*
Y1401489D03*
X1094933Y1355193D03*
Y1353093D03*
X1103573Y1355193D03*
Y1353093D03*
X1107173Y1355193D03*
Y1353093D03*
X1094933Y1379391D03*
Y1377291D03*
X1103573Y1379391D03*
Y1377291D03*
X1107173Y1379391D03*
Y1377291D03*
X1094933Y1403589D03*
Y1401489D03*
X1107173Y1403589D03*
Y1401489D03*
X1103573Y1403589D03*
Y1401489D03*
X1115813Y1355193D03*
Y1353093D03*
X1119413Y1355193D03*
Y1353093D03*
X1115813Y1379391D03*
Y1377291D03*
X1119413Y1379391D03*
Y1377291D03*
X1115813Y1403589D03*
Y1401489D03*
X1119413Y1403589D03*
Y1401489D03*
X1131653Y1355193D03*
Y1353093D03*
X1128053Y1355193D03*
Y1353093D03*
X1140293Y1355193D03*
Y1353093D03*
X1128053Y1379391D03*
Y1377291D03*
X1131653Y1379391D03*
Y1377291D03*
X1140293Y1379391D03*
Y1377291D03*
X1131653Y1403589D03*
Y1401489D03*
X1128053Y1403589D03*
Y1401489D03*
X1140293Y1403589D03*
Y1401489D03*
X1143893Y1355193D03*
Y1353093D03*
X1156133Y1355193D03*
Y1353093D03*
X1152533Y1355193D03*
Y1353093D03*
X1143893Y1379391D03*
Y1377291D03*
X1152533Y1379391D03*
Y1377291D03*
X1156133Y1379391D03*
Y1377291D03*
X1143893Y1403589D03*
Y1401489D03*
X1152533Y1403589D03*
Y1401489D03*
X1156133Y1403589D03*
Y1401489D03*
X1168373Y1355193D03*
Y1353093D03*
X1164773Y1355193D03*
Y1353093D03*
Y1379391D03*
Y1377291D03*
X1168373Y1379391D03*
Y1377291D03*
X1164773Y1403589D03*
Y1401489D03*
X1168373Y1403589D03*
Y1401489D03*
X1180613Y1355193D03*
Y1353093D03*
X1177013Y1355193D03*
Y1353093D03*
X1180613Y1379391D03*
Y1377291D03*
X1177013Y1379391D03*
Y1377291D03*
X1180613Y1403589D03*
Y1401489D03*
X1177013Y1403589D03*
Y1401489D03*
X1230226Y1355193D03*
Y1353093D03*
X1233826Y1355193D03*
Y1353093D03*
Y1379391D03*
Y1377291D03*
X1230226Y1379391D03*
Y1377291D03*
X1246066Y1355193D03*
Y1353093D03*
X1242466Y1355193D03*
Y1353093D03*
X1246066Y1379391D03*
Y1377291D03*
X1242466Y1379391D03*
Y1377291D03*
X1246066Y1403589D03*
Y1401489D03*
X1242466Y1403589D03*
Y1401489D03*
X1258306Y1355193D03*
Y1353093D03*
X1254706Y1355193D03*
Y1353093D03*
X1270546Y1355193D03*
Y1353093D03*
X1266946Y1355193D03*
Y1353093D03*
X1254706Y1379391D03*
Y1377291D03*
X1258306Y1379391D03*
Y1377291D03*
X1270546Y1379391D03*
Y1377291D03*
X1266946Y1379391D03*
Y1377291D03*
X1258306Y1403589D03*
Y1401489D03*
X1254706Y1403589D03*
Y1401489D03*
X1270546Y1403589D03*
Y1401489D03*
X1266946Y1403589D03*
Y1401489D03*
X1282786Y1355193D03*
Y1353093D03*
X1279186Y1355193D03*
Y1353093D03*
Y1379391D03*
Y1377291D03*
X1282786Y1379391D03*
Y1377291D03*
X1279186Y1403589D03*
Y1401489D03*
X1282786Y1403589D03*
Y1401489D03*
X1295026Y1355193D03*
Y1353093D03*
X1291426Y1355193D03*
Y1353093D03*
X1295026Y1379391D03*
Y1377291D03*
X1291426Y1379391D03*
Y1377291D03*
X1295026Y1403589D03*
Y1401489D03*
X1291426Y1403589D03*
Y1401489D03*
X1303666Y1355193D03*
Y1353093D03*
X1307266Y1355193D03*
Y1353093D03*
X1315906Y1355193D03*
Y1353093D03*
X1303666Y1379391D03*
Y1377291D03*
X1307266Y1379391D03*
Y1377291D03*
X1315906Y1379391D03*
Y1377291D03*
X1303666Y1403589D03*
Y1401489D03*
X1307266Y1403589D03*
Y1401489D03*
X1315906Y1403589D03*
Y1401489D03*
X1319506Y1355193D03*
Y1353093D03*
X1331746Y1355193D03*
Y1353093D03*
X1328146Y1355193D03*
Y1353093D03*
X1319506Y1379391D03*
Y1377291D03*
X1331746Y1379391D03*
Y1377291D03*
X1328146Y1379391D03*
Y1377291D03*
X1319506Y1403589D03*
Y1401489D03*
X1328146Y1403589D03*
Y1401489D03*
X1331746Y1403589D03*
Y1401489D03*
X1343986Y1355193D03*
Y1353093D03*
X1340386Y1355193D03*
Y1353093D03*
Y1379391D03*
Y1377291D03*
X1343986Y1379391D03*
Y1377291D03*
Y1403589D03*
Y1401489D03*
X1340386Y1403589D03*
Y1401489D03*
X1352626Y1355193D03*
Y1353093D03*
X1356226Y1355193D03*
Y1353093D03*
X1352626Y1379391D03*
Y1377291D03*
X1356226Y1379391D03*
Y1377291D03*
X1352626Y1403589D03*
Y1401489D03*
X1356226Y1403589D03*
Y1401489D03*
X1404239Y1545478D03*
Y1543378D03*
X1403747Y1568156D03*
Y1566056D03*
X1461270Y1355193D03*
Y1353093D03*
X1464870Y1355193D03*
Y1353093D03*
X1461270Y1379391D03*
Y1377291D03*
X1464870Y1379391D03*
Y1377291D03*
X1477373Y1035102D03*
Y1033002D03*
X1474261Y1035088D03*
Y1032988D03*
X1481690Y1105228D03*
Y1107328D03*
Y1117828D03*
Y1119928D03*
Y1130428D03*
Y1132528D03*
Y1143028D03*
Y1145128D03*
Y1155628D03*
Y1168228D03*
Y1170328D03*
Y1157728D03*
Y1180828D03*
Y1182928D03*
X1477110Y1355193D03*
Y1353093D03*
X1473510Y1355193D03*
Y1353093D03*
X1477110Y1379391D03*
Y1377291D03*
X1473510Y1379391D03*
Y1377291D03*
Y1403589D03*
Y1401489D03*
X1477110Y1403589D03*
Y1401489D03*
X1493336Y1025091D03*
Y1012491D03*
Y1014591D03*
Y1027191D03*
X1485750Y1355193D03*
Y1353093D03*
X1489350Y1355193D03*
Y1353093D03*
X1497990Y1355193D03*
Y1353093D03*
Y1379391D03*
Y1377291D03*
X1485750Y1379391D03*
Y1377291D03*
X1489350Y1379391D03*
Y1377291D03*
Y1403589D03*
Y1401489D03*
X1485750Y1403589D03*
Y1401489D03*
X1497990Y1403589D03*
Y1401489D03*
X1501590Y1355193D03*
Y1353093D03*
X1510230Y1355193D03*
Y1353093D03*
X1513830Y1355193D03*
Y1353093D03*
X1501590Y1379391D03*
Y1377291D03*
X1510230Y1379391D03*
Y1377291D03*
X1513830Y1379391D03*
Y1377291D03*
X1501590Y1403589D03*
Y1401489D03*
X1510230Y1403589D03*
Y1401489D03*
X1513830Y1403589D03*
Y1401489D03*
X1522470Y1355193D03*
Y1353093D03*
X1526070Y1355193D03*
Y1353093D03*
Y1379391D03*
Y1377291D03*
X1522470Y1379391D03*
Y1377291D03*
Y1403589D03*
Y1401489D03*
X1526070Y1403589D03*
Y1401489D03*
X1534710Y1355193D03*
Y1353093D03*
X1538310Y1355193D03*
Y1353093D03*
X1534710Y1379391D03*
Y1377291D03*
X1538310Y1379391D03*
Y1377291D03*
Y1403589D03*
Y1401489D03*
X1534710Y1403589D03*
Y1401489D03*
X1559190Y1355193D03*
Y1353093D03*
X1562790Y1355193D03*
Y1353093D03*
X1550550Y1355193D03*
Y1353093D03*
X1546950Y1355193D03*
Y1353093D03*
Y1379391D03*
Y1377291D03*
X1550550Y1379391D03*
Y1377291D03*
X1559190Y1379391D03*
Y1377291D03*
X1562790Y1379391D03*
Y1377291D03*
X1546950Y1403589D03*
Y1401489D03*
X1550550Y1403589D03*
Y1401489D03*
X1562790Y1403589D03*
Y1401489D03*
X1559190Y1403589D03*
Y1401489D03*
X1575030Y1355193D03*
Y1353093D03*
X1571430Y1355193D03*
Y1353093D03*
X1575030Y1379391D03*
Y1377291D03*
X1571430Y1379391D03*
Y1377291D03*
Y1403589D03*
Y1401489D03*
X1575030Y1403589D03*
Y1401489D03*
X1583670Y1355193D03*
Y1353093D03*
X1587270Y1355193D03*
Y1353093D03*
X1583670Y1379391D03*
Y1377291D03*
X1587270Y1379391D03*
Y1377291D03*
X1583670Y1403589D03*
Y1401489D03*
X1587270Y1403589D03*
Y1401489D03*
X1593942Y1437014D03*
Y1439114D03*
X1611298Y1355193D03*
Y1353093D03*
Y1379391D03*
Y1377291D03*
X1623538Y1355193D03*
Y1353093D03*
X1627138Y1355193D03*
Y1353093D03*
X1614898Y1355193D03*
Y1353093D03*
X1627138Y1379391D03*
Y1377291D03*
X1623538Y1379391D03*
Y1377291D03*
X1614898Y1379391D03*
Y1377291D03*
X1623538Y1403589D03*
Y1401489D03*
X1627138Y1403589D03*
Y1401489D03*
X1639378Y1355193D03*
Y1353093D03*
X1635778Y1355193D03*
Y1353093D03*
Y1379391D03*
Y1377291D03*
X1639378Y1379391D03*
Y1377291D03*
X1635778Y1403589D03*
Y1401489D03*
X1639378Y1403589D03*
Y1401489D03*
X1660258Y1355193D03*
Y1353093D03*
X1648018Y1355193D03*
Y1353093D03*
X1651618Y1355193D03*
Y1353093D03*
X1660258Y1379391D03*
Y1377291D03*
X1651618Y1379391D03*
Y1377291D03*
X1648018Y1379391D03*
Y1377291D03*
X1651618Y1403589D03*
Y1401489D03*
X1660258Y1403589D03*
Y1401489D03*
X1648018Y1403589D03*
Y1401489D03*
X1672498Y1355193D03*
Y1353093D03*
X1676098Y1355193D03*
Y1353093D03*
X1663858Y1355193D03*
Y1353093D03*
X1676098Y1379391D03*
Y1377291D03*
X1672498Y1379391D03*
Y1377291D03*
X1663858Y1379391D03*
Y1377291D03*
X1672498Y1403589D03*
Y1401489D03*
X1676098Y1403589D03*
Y1401489D03*
X1663858Y1403589D03*
Y1401489D03*
X1684738Y1355193D03*
Y1353093D03*
X1688338Y1355193D03*
Y1353093D03*
Y1379391D03*
Y1377291D03*
X1684738Y1379391D03*
Y1377291D03*
Y1403589D03*
Y1401489D03*
X1688338Y1403589D03*
Y1401489D03*
X1700578Y1355193D03*
Y1353093D03*
X1696978Y1355193D03*
Y1353093D03*
X1709218Y1355193D03*
Y1353093D03*
Y1379391D03*
Y1377291D03*
X1696978Y1379391D03*
Y1377291D03*
X1700578Y1379391D03*
Y1377291D03*
X1709218Y1403589D03*
Y1401489D03*
X1696978Y1403589D03*
Y1401489D03*
X1700578Y1403589D03*
Y1401489D03*
X1721458Y1355193D03*
Y1353093D03*
X1725058Y1355193D03*
Y1353093D03*
X1712818Y1355193D03*
Y1353093D03*
X1725058Y1379391D03*
Y1377291D03*
X1721458Y1379391D03*
Y1377291D03*
X1712818Y1379391D03*
Y1377291D03*
X1725058Y1403589D03*
Y1401489D03*
X1721458Y1403589D03*
Y1401489D03*
X1712818Y1403589D03*
Y1401489D03*
X1733698Y1355193D03*
Y1353093D03*
X1737298Y1355193D03*
Y1353093D03*
Y1379391D03*
Y1377291D03*
X1733698Y1379391D03*
Y1377291D03*
Y1403589D03*
Y1401489D03*
X1737298Y1403589D03*
Y1401489D03*
X1807393Y1438622D03*
Y1440722D03*
X1807270Y1470812D03*
Y1472912D03*
G54D96*
X148818Y1075196D03*
Y1078936D03*
X145078D03*
X148818Y1086417D03*
X145078D03*
X148818Y1090157D03*
X145078D03*
X148818Y1082677D03*
X145078D03*
X148818Y1093897D03*
X145078D03*
X148818Y1097637D03*
X145078D03*
X148818Y1105117D03*
X145078D03*
X148818Y1101377D03*
X145078D03*
X148818Y1112598D03*
X145078D03*
X148818Y1120078D03*
X145078D03*
X148818Y1108858D03*
Y1116338D03*
Y1123818D03*
X145078Y1108858D03*
Y1116338D03*
Y1123818D03*
X148818Y1127558D03*
X145078D03*
X148818Y1135039D03*
X145078D03*
X148818Y1131299D03*
Y1138779D03*
X145078Y1131299D03*
Y1138779D03*
X148818Y1142519D03*
X145078D03*
X148818Y1146259D03*
X145078D03*
X148818Y1153740D03*
X145078D03*
X148818Y1149999D03*
X145078D03*
X148818Y1161220D03*
X145078D03*
X148818Y1168700D03*
X145078D03*
X148818Y1157480D03*
X145078D03*
X148818Y1164960D03*
X145078D03*
X148818Y1172440D03*
X145078D03*
X148818Y1183661D03*
X145078D03*
X148818Y1187401D03*
X145078D03*
X148818Y1176180D03*
X145078D03*
X148818Y1179921D03*
X145078D03*
X148818Y1194881D03*
X145078D03*
X148818Y1202362D03*
X145078D03*
X148818Y1198621D03*
Y1191141D03*
X145078Y1198621D03*
Y1191141D03*
X148818Y1209842D03*
X145078D03*
X148818Y1217322D03*
X145078D03*
X148818Y1221062D03*
Y1213582D03*
Y1206102D03*
X145078Y1221062D03*
Y1213582D03*
Y1206102D03*
X148818Y1224803D03*
X145078D03*
X148818Y1232283D03*
X145078D03*
X148818Y1236023D03*
X145078D03*
X148818Y1228543D03*
X145078D03*
X148818Y1243503D03*
X145078D03*
X148818Y1250984D03*
X145078D03*
X148818Y1239763D03*
X145078D03*
X148818Y1247243D03*
X145078D03*
X148818Y1254724D03*
X163779Y1075196D03*
X156299D03*
X160039D03*
X152559D03*
X163779Y1078936D03*
X156299D03*
X160039Y1082677D03*
X152559D03*
X160039Y1086417D03*
X152559D03*
X163779Y1090157D03*
X160039D03*
X156299D03*
X152559D03*
X163779Y1086417D03*
X160039Y1078936D03*
X156299Y1086417D03*
X152559Y1078936D03*
X163779Y1082677D03*
X156299D03*
X163779Y1093897D03*
X156299D03*
X163779Y1097637D03*
X156299D03*
X160039Y1101377D03*
X152559D03*
X160039Y1105117D03*
X152559D03*
X163779D03*
X160039Y1097637D03*
X156299Y1105117D03*
X152559Y1097637D03*
X163779Y1101377D03*
X160039Y1093897D03*
X156299Y1101377D03*
X152559Y1093897D03*
X163779Y1108858D03*
X160039D03*
X156299D03*
X152559D03*
X160039Y1112598D03*
X163779Y1116338D03*
X160039D03*
X156299D03*
X152559D03*
X160039Y1120078D03*
X163779Y1123818D03*
X160039D03*
X156299D03*
X152559D03*
X163779Y1112598D03*
Y1120078D03*
X156299Y1112598D03*
Y1120078D03*
X152559Y1112598D03*
Y1120078D03*
X160039Y1127558D03*
X163779Y1131299D03*
X160039D03*
X156299D03*
X152559D03*
X160039Y1135039D03*
X163779Y1138779D03*
X160039D03*
X156299D03*
X152559D03*
X163779Y1127558D03*
Y1135039D03*
X156299Y1127558D03*
Y1135039D03*
X152559Y1127558D03*
Y1135039D03*
X163779Y1142519D03*
X160039D03*
X156299D03*
X152559D03*
X163779Y1146259D03*
X152559D03*
X163779Y1149999D03*
X160039D03*
X156299D03*
X152559D03*
X163779Y1153740D03*
X152559D03*
X156299Y1146259D03*
X160039D03*
Y1153740D03*
X156299D03*
X163779Y1157480D03*
X160039D03*
X156299D03*
X152559D03*
X163779Y1161220D03*
X152559D03*
X163779Y1164960D03*
X160039D03*
X156299D03*
X152559D03*
X163779Y1168700D03*
X152559D03*
X163779Y1172440D03*
X160039D03*
X156299D03*
X152559D03*
X160039Y1161220D03*
X156299D03*
X160039Y1168700D03*
X156299D03*
X163779Y1183661D03*
X160039D03*
X156299D03*
X152559D03*
X160039Y1187401D03*
X163779Y1176180D03*
X152559D03*
X163779Y1179921D03*
X160039D03*
X156299D03*
X152559D03*
X160039Y1176180D03*
X156299D03*
X163779Y1187401D03*
X156299D03*
X152559D03*
X163779Y1191141D03*
X160039D03*
X156299D03*
X152559D03*
X160039Y1194881D03*
X163779Y1198621D03*
X160039D03*
X156299D03*
X152559D03*
X160039Y1202362D03*
X163779D03*
Y1194881D03*
X156299Y1202362D03*
Y1194881D03*
X152559Y1202362D03*
Y1194881D03*
X163779Y1206102D03*
X160039D03*
X156299D03*
X152559D03*
X160039Y1209842D03*
X163779Y1213582D03*
X160039D03*
X156299D03*
X152559D03*
X160039Y1217322D03*
X163779Y1221062D03*
X160039D03*
X156299D03*
X152559D03*
X163779Y1217322D03*
Y1209842D03*
X156299Y1217322D03*
Y1209842D03*
X152559Y1217322D03*
Y1209842D03*
X160039Y1224803D03*
X152559D03*
X160039Y1228543D03*
X152559D03*
X163779Y1232283D03*
X156299D03*
X163779Y1236023D03*
X156299D03*
X163779Y1224803D03*
X160039Y1232283D03*
X156299Y1224803D03*
X152559Y1232283D03*
X163779Y1228543D03*
X160039Y1236023D03*
X156299Y1228543D03*
X152559Y1236023D03*
X163779Y1239763D03*
X160039D03*
X156299D03*
X152559D03*
X160039Y1243503D03*
X152559D03*
X160039Y1247243D03*
X152559D03*
X163779Y1250984D03*
X156299D03*
X163779Y1243503D03*
X160039Y1250984D03*
X156299Y1243503D03*
X152559Y1250984D03*
X163779Y1247243D03*
X156299D03*
X163779Y1254724D03*
X156299D03*
X160039D03*
X152559D03*
X171259Y1075196D03*
X178740D03*
X167519D03*
X174999D03*
X182480D03*
X171259Y1078936D03*
X178740D03*
X174999Y1082677D03*
X167519D03*
X182480D03*
X174999Y1086417D03*
X167519D03*
X182480D03*
X174999Y1090157D03*
X171259D03*
X167519D03*
X182480D03*
X178740D03*
X171259Y1086417D03*
X167519Y1078936D03*
X171259Y1082677D03*
X174999Y1078936D03*
X178740Y1086417D03*
X182480Y1078936D03*
X178740Y1082677D03*
X171259Y1093897D03*
X178740D03*
X171259Y1097637D03*
X178740D03*
X174999Y1101377D03*
X167519D03*
X182480D03*
X174999Y1105117D03*
X167519D03*
X182480D03*
X171259D03*
X167519Y1097637D03*
X171259Y1101377D03*
X167519Y1093897D03*
X174999Y1097637D03*
X178740Y1105117D03*
X182480Y1097637D03*
X174999Y1093897D03*
X178740Y1101377D03*
X182480Y1093897D03*
X174999Y1108858D03*
X171259D03*
X167519D03*
X182480D03*
X178740D03*
X174999Y1112598D03*
X171259D03*
X182480D03*
X178740D03*
X167519Y1116338D03*
X182480D03*
X178740D03*
X174999Y1120078D03*
X171259D03*
X182480D03*
X178740D03*
X167519Y1123818D03*
X182480D03*
X178740D03*
X167519Y1112598D03*
X174999Y1116338D03*
X167519Y1120078D03*
X174999Y1123818D03*
X171259Y1116338D03*
Y1123818D03*
X174999Y1127558D03*
X171259D03*
X182480D03*
X178740D03*
X167519Y1131299D03*
X182480D03*
X178740D03*
X174999Y1135039D03*
X171259D03*
X182480D03*
X178740D03*
X167519Y1138779D03*
X182480D03*
X178740D03*
X167519Y1127558D03*
X174999Y1131299D03*
X167519Y1135039D03*
X174999Y1138779D03*
X171259Y1131299D03*
Y1138779D03*
X174999Y1142519D03*
X171259D03*
X167519D03*
X182480D03*
X178740D03*
X174999Y1146259D03*
X171259D03*
X182480D03*
X174999Y1149999D03*
X182480D03*
X174999Y1153740D03*
X182480D03*
X178740Y1146259D03*
Y1149999D03*
Y1153740D03*
X171259D03*
X167519Y1149999D03*
X171259D03*
X167519Y1146259D03*
Y1153740D03*
X174999Y1157480D03*
X182480D03*
X178740D03*
X174999Y1161220D03*
X182480D03*
X174999Y1164960D03*
X182480D03*
X174999Y1168700D03*
X182480D03*
X178740D03*
X174999Y1172440D03*
X182480D03*
X178740D03*
Y1161220D03*
Y1164960D03*
X171259D03*
Y1172440D03*
Y1168700D03*
X167519Y1172440D03*
Y1168700D03*
Y1164960D03*
X171259Y1157480D03*
Y1161220D03*
X167519D03*
Y1157480D03*
X174999Y1183661D03*
X171259D03*
X167519D03*
X182480D03*
X178740D03*
X174999Y1187401D03*
X171259D03*
X182480D03*
X178740D03*
X174999Y1176180D03*
X182480D03*
X174999Y1179921D03*
X171259D03*
X167519D03*
X182480D03*
X178740Y1176180D03*
Y1179921D03*
X167519Y1176180D03*
X171259D03*
X167519Y1187401D03*
Y1191141D03*
X182480D03*
X178740D03*
X174999Y1194881D03*
X171259D03*
X182480D03*
X178740D03*
X167519Y1198621D03*
X182480D03*
X178740D03*
X174999Y1202362D03*
X171259D03*
X182480D03*
X178740D03*
X167519D03*
X174999Y1198621D03*
X167519Y1194881D03*
X174999Y1191141D03*
X171259Y1198621D03*
Y1191141D03*
X167519Y1206102D03*
X182480D03*
X178740D03*
X174999Y1209842D03*
X171259D03*
X182480D03*
X178740D03*
X167519Y1213582D03*
X182480D03*
X178740D03*
X174999Y1217322D03*
X171259D03*
X182480D03*
X178740D03*
X174999Y1221062D03*
X171259D03*
X167519D03*
X182480D03*
X178740D03*
X167519Y1217322D03*
X174999Y1213582D03*
X167519Y1209842D03*
X174999Y1206102D03*
X171259Y1213582D03*
Y1206102D03*
X174999Y1224803D03*
X167519D03*
X182480D03*
X174999Y1228543D03*
X167519D03*
X182480D03*
X171259Y1232283D03*
X178740D03*
X171259Y1236023D03*
X178740D03*
X167519Y1232283D03*
Y1236023D03*
X171259Y1224803D03*
X174999Y1232283D03*
X178740Y1224803D03*
X182480Y1232283D03*
X171259Y1228543D03*
X174999Y1236023D03*
X178740Y1228543D03*
X182480Y1236023D03*
X174999Y1239763D03*
X171259D03*
X167519D03*
X182480D03*
X178740D03*
X174999Y1243503D03*
X167519D03*
X182480D03*
X174999Y1247243D03*
X167519D03*
X182480D03*
X171259Y1250984D03*
X178740D03*
X167519D03*
X171259Y1243503D03*
X174999Y1250984D03*
X178740Y1243503D03*
X182480Y1250984D03*
X171259Y1247243D03*
X178740D03*
X171259Y1254724D03*
X178740D03*
X167519D03*
X174999D03*
X182480D03*
X193700Y1075196D03*
X186220D03*
X189960D03*
X197440D03*
X193700Y1078936D03*
X186220D03*
X197440Y1082677D03*
X189960D03*
X197440Y1086417D03*
X189960D03*
X197440Y1090157D03*
X193700D03*
X189960D03*
X186220D03*
Y1086417D03*
X189960Y1078936D03*
X193700Y1086417D03*
X197440Y1078936D03*
X186220Y1082677D03*
X193700D03*
Y1093897D03*
X186220D03*
X193700Y1097637D03*
X186220D03*
X197440Y1101377D03*
X189960D03*
X197440Y1105117D03*
X189960D03*
X186220D03*
X189960Y1097637D03*
X193700Y1105117D03*
X197440Y1097637D03*
X186220Y1101377D03*
X189960Y1093897D03*
X193700Y1101377D03*
X197440Y1093897D03*
Y1108858D03*
X193700D03*
X189960D03*
X186220D03*
X197440Y1120078D03*
X193700D03*
X189960D03*
X186220D03*
X197440Y1123818D03*
X193700D03*
X189960D03*
X186220D03*
X189960Y1116338D03*
X186220D03*
Y1112598D03*
X189960D03*
X193700Y1116338D03*
Y1112598D03*
X197440Y1116338D03*
Y1112598D03*
Y1127558D03*
X193700D03*
X189960D03*
X186220D03*
X197440Y1131299D03*
X189960D03*
X186220D03*
X197440Y1135039D03*
X189960D03*
X186220D03*
X197440Y1138779D03*
X189960D03*
X186220D03*
X193700D03*
Y1131299D03*
Y1135039D03*
X186220Y1149999D03*
X189960Y1153740D03*
Y1142519D03*
X186220D03*
X197440Y1146259D03*
X189960D03*
X193700Y1149999D03*
X197440Y1153740D03*
X193700Y1142519D03*
X197440D03*
X186220Y1146259D03*
X189960Y1149999D03*
X186220Y1153740D03*
X193700Y1146259D03*
X197440Y1149999D03*
X193700Y1153740D03*
X186220Y1157480D03*
X189960Y1161220D03*
X186220Y1164960D03*
X189960Y1168700D03*
X186220Y1172440D03*
X193700Y1157480D03*
X197440Y1161220D03*
X193700Y1164960D03*
X197440Y1168700D03*
X193700Y1172440D03*
X189960D03*
Y1157480D03*
X186220Y1161220D03*
X189960Y1164960D03*
X186220Y1168700D03*
X197440Y1157480D03*
X193700Y1161220D03*
X197440Y1164960D03*
X193700Y1168700D03*
X197440Y1172440D03*
X189960Y1176180D03*
X186220Y1179921D03*
X197440Y1183661D03*
X189960D03*
X197440Y1187401D03*
X193700D03*
X189960D03*
X186220D03*
X197440Y1176180D03*
X193700Y1179921D03*
X186220Y1183661D03*
Y1176180D03*
X189960Y1179921D03*
X193700Y1183661D03*
Y1176180D03*
X197440Y1179921D03*
Y1191141D03*
X189960D03*
X186220D03*
X197440Y1194881D03*
X189960D03*
X186220D03*
X197440Y1198621D03*
X189960D03*
X186220D03*
X197440Y1202362D03*
X193700D03*
X189960D03*
X186220D03*
X193700Y1191141D03*
Y1198621D03*
Y1194881D03*
X197440Y1206102D03*
X193700D03*
X189960D03*
X186220D03*
X197440Y1209842D03*
X193700D03*
X189960D03*
X186220D03*
X193700Y1213582D03*
X186220D03*
X193700Y1217322D03*
X197440Y1221062D03*
X193700D03*
X189960D03*
X186220D03*
X189960Y1217322D03*
X186220D03*
X197440Y1213582D03*
Y1217322D03*
X189960Y1213582D03*
X197440Y1224803D03*
X189960D03*
X197440Y1228543D03*
X189960D03*
X193700Y1232283D03*
X186220D03*
X193700Y1236023D03*
X186220D03*
Y1224803D03*
X189960Y1232283D03*
X193700Y1224803D03*
X197440Y1232283D03*
X186220Y1228543D03*
X189960Y1236023D03*
X193700Y1228543D03*
X197440Y1236023D03*
Y1239763D03*
X193700D03*
X189960D03*
X186220D03*
X197440Y1243503D03*
X189960D03*
X197440Y1247243D03*
X189960D03*
X193700Y1250984D03*
X186220D03*
Y1243503D03*
X189960Y1250984D03*
X193700Y1243503D03*
X197440Y1250984D03*
X186220Y1247243D03*
X193700D03*
Y1254724D03*
X186220D03*
X189960D03*
X197440D03*
X208661Y1075196D03*
X201181D03*
X204921D03*
X212401D03*
X208661Y1078936D03*
X201181D03*
X212401Y1082677D03*
X204921D03*
X212401Y1086417D03*
X204921D03*
X212401Y1090157D03*
X208661D03*
X204921D03*
X201181D03*
Y1086417D03*
X204921Y1078936D03*
X208661Y1086417D03*
X212401Y1078936D03*
X201181Y1082677D03*
X208661D03*
Y1093897D03*
X201181D03*
X208661Y1097637D03*
X201181D03*
X212401Y1101377D03*
X204921D03*
X212401Y1105117D03*
X204921D03*
X201181D03*
X204921Y1097637D03*
X208661Y1105117D03*
X212401Y1097637D03*
X201181Y1101377D03*
X204921Y1093897D03*
X208661Y1101377D03*
X212401Y1093897D03*
Y1108858D03*
X208661D03*
X204921D03*
X201181D03*
X212401Y1120078D03*
X208661D03*
X204921D03*
X201181D03*
X212401Y1123818D03*
X208661D03*
X204921D03*
X201181D03*
Y1112598D03*
X204921Y1116338D03*
X201181D03*
X204921Y1112598D03*
X208661Y1116338D03*
Y1112598D03*
X212401Y1116338D03*
Y1112598D03*
Y1127558D03*
X208661D03*
X204921D03*
X201181D03*
X212401Y1135039D03*
X208661D03*
X204921D03*
X201181D03*
X212401Y1131299D03*
X208661D03*
X204921D03*
X201181D03*
X212401Y1138779D03*
X208661D03*
X204921D03*
X201181D03*
X212401Y1142519D03*
X208661D03*
X204921D03*
X201181D03*
X212401Y1149999D03*
X208661D03*
X204921D03*
X201181D03*
X212401Y1146259D03*
X208661D03*
X204921D03*
X201181D03*
X212401Y1153740D03*
X208661D03*
X204921D03*
X201181D03*
X208661Y1157480D03*
X201181D03*
X212401Y1161220D03*
X204921D03*
X208661Y1164960D03*
X201181D03*
X212401Y1168700D03*
X204921D03*
X208661Y1172440D03*
X201181D03*
X212401Y1157480D03*
X204921D03*
X208661Y1161220D03*
X201181D03*
X212401Y1164960D03*
X204921D03*
X208661Y1168700D03*
X201181D03*
X212401Y1172440D03*
X204921D03*
X212401Y1187401D03*
X208661D03*
X204921D03*
X201181D03*
X212401Y1179921D03*
X208661D03*
X204921D03*
X201181D03*
X212401Y1183661D03*
X208661D03*
X204921D03*
X201181D03*
X212401Y1176180D03*
X208661D03*
X204921D03*
X201181D03*
X212401Y1194881D03*
X208661D03*
X204921D03*
X201181D03*
X212401Y1202362D03*
X208661D03*
X204921D03*
X201181D03*
X212401Y1198621D03*
X208661D03*
X204921D03*
X201181D03*
X212401Y1191141D03*
X208661D03*
X204921D03*
X201181D03*
X212401Y1206102D03*
X208661D03*
X204921D03*
X201181D03*
X212401Y1209842D03*
X208661D03*
X204921D03*
X201181D03*
X212401Y1221062D03*
X208661D03*
X204921D03*
X201181D03*
X204921Y1213582D03*
X201181D03*
X212401D03*
X208661Y1217322D03*
Y1213582D03*
X212401Y1217322D03*
X204921D03*
X201181D03*
X212401Y1224803D03*
X204921D03*
X212401Y1228543D03*
X204921D03*
X208661Y1232283D03*
X201181D03*
X208661Y1236023D03*
X201181D03*
Y1224803D03*
X204921Y1232283D03*
X208661Y1224803D03*
X212401Y1232283D03*
X201181Y1228543D03*
X204921Y1236023D03*
X208661Y1228543D03*
X212401Y1236023D03*
Y1239763D03*
X208661D03*
X204921D03*
X201181D03*
X212401Y1243503D03*
X204921D03*
X212401Y1247243D03*
X204921D03*
X208661Y1250984D03*
X201181D03*
Y1243503D03*
X204921Y1250984D03*
X208661Y1243503D03*
X212401Y1250984D03*
X201181Y1247243D03*
X208661D03*
Y1254724D03*
X201181D03*
X204921D03*
X212401D03*
X231102Y1075196D03*
X223622D03*
X216141D03*
X219881D03*
X227362D03*
X231102Y1078936D03*
X223622D03*
X216141D03*
X227362Y1082677D03*
X219881D03*
X227362Y1086417D03*
X219881D03*
X231102Y1090157D03*
X227362D03*
X223622D03*
X219881D03*
X216141D03*
Y1086417D03*
X219881Y1078936D03*
X223622Y1086417D03*
X227362Y1078936D03*
X231102Y1086417D03*
X216141Y1082677D03*
X223622D03*
X231102D03*
Y1093897D03*
X223622D03*
X216141D03*
X231102Y1097637D03*
X223622D03*
X216141D03*
X227362Y1101377D03*
X219881D03*
X227362Y1105117D03*
X219881D03*
X216141D03*
X219881Y1097637D03*
X223622Y1105117D03*
X227362Y1097637D03*
X231102Y1105117D03*
X216141Y1101377D03*
X219881Y1093897D03*
X223622Y1101377D03*
X227362Y1093897D03*
X231102Y1101377D03*
Y1108858D03*
X227362D03*
X223622D03*
X219881D03*
X216141D03*
X231102Y1112598D03*
X216141D03*
X231102Y1116338D03*
X216141D03*
X231102Y1120078D03*
X227362D03*
X223622D03*
X219881D03*
X216141D03*
X231102Y1123818D03*
X227362D03*
X223622D03*
X219881D03*
X216141D03*
X227362Y1116338D03*
X223622Y1112598D03*
Y1116338D03*
X219881D03*
Y1112598D03*
X227362D03*
X231102Y1127558D03*
X227362D03*
X223622D03*
X219881D03*
X216141D03*
X231102Y1135039D03*
X227362D03*
X223622D03*
X219881D03*
X216141D03*
X231102Y1131299D03*
X227362D03*
X223622D03*
X219881D03*
X216141D03*
X231102Y1138779D03*
X227362D03*
X223622D03*
X219881D03*
X216141D03*
X231102Y1142519D03*
X227362D03*
X223622D03*
X219881D03*
X216141D03*
X231102Y1149999D03*
X227362D03*
X223622D03*
X219881D03*
X216141D03*
X231102Y1146259D03*
X227362D03*
X223622D03*
X219881D03*
X216141D03*
X231102Y1153740D03*
X227362D03*
X223622D03*
X219881D03*
X216141D03*
X231102Y1157480D03*
X223622D03*
X216141D03*
X227362Y1161220D03*
X219881D03*
X231102Y1164960D03*
X223622D03*
X216141D03*
X227362Y1168700D03*
X219881D03*
X231102Y1172440D03*
X223622D03*
X216141D03*
X227362Y1157480D03*
X219881D03*
X231102Y1161220D03*
X223622D03*
X216141D03*
X227362Y1164960D03*
X219881D03*
X231102Y1168700D03*
X223622D03*
X216141D03*
X227362Y1172440D03*
X219881D03*
X231102Y1187401D03*
X227362D03*
X223622D03*
X219881D03*
X216141D03*
X231102Y1179921D03*
X227362D03*
X223622D03*
X219881D03*
X216141D03*
X231102Y1183661D03*
X227362D03*
X223622D03*
X219881D03*
X216141D03*
X231102Y1176180D03*
X227362D03*
X223622D03*
X219881D03*
X216141D03*
X231102Y1194881D03*
X227362D03*
X223622D03*
X219881D03*
X216141D03*
X231102Y1202362D03*
X227362D03*
X223622D03*
X219881D03*
X216141D03*
X231102Y1198621D03*
X227362D03*
X223622D03*
X219881D03*
X216141D03*
X231102Y1191141D03*
X227362D03*
X223622D03*
X219881D03*
X216141D03*
X231102Y1206102D03*
X227362D03*
X223622D03*
X219881D03*
X216141D03*
X231102Y1209842D03*
X227362D03*
X223622D03*
X219881D03*
X216141D03*
X219881Y1213582D03*
Y1217322D03*
X231102Y1221062D03*
X227362D03*
X223622D03*
X219881D03*
X216141D03*
X231102Y1213582D03*
X227362Y1217322D03*
Y1213582D03*
X223622D03*
Y1217322D03*
X231102D03*
X216141D03*
Y1213582D03*
X227362Y1224803D03*
X219881D03*
X227362Y1228543D03*
X219881D03*
X231102Y1232283D03*
X223622D03*
X216141D03*
X231102Y1236023D03*
X223622D03*
X216141D03*
Y1224803D03*
X219881Y1232283D03*
X223622Y1224803D03*
X227362Y1232283D03*
X216141Y1228543D03*
X219881Y1236023D03*
X223622Y1228543D03*
X227362Y1236023D03*
X231102Y1224803D03*
Y1228543D03*
Y1239763D03*
X227362D03*
X223622D03*
X219881D03*
X216141D03*
X227362Y1243503D03*
X219881D03*
X227362Y1247243D03*
X219881D03*
X231102Y1250984D03*
X223622D03*
X216141D03*
Y1243503D03*
X219881Y1250984D03*
X223622Y1243503D03*
X227362Y1250984D03*
X216141Y1247243D03*
X223622D03*
X231102Y1243503D03*
Y1247243D03*
Y1254724D03*
X223622D03*
X216141D03*
X219881D03*
X227362D03*
X246062Y1075196D03*
X238582D03*
X242322D03*
X234842D03*
X246062Y1078936D03*
X238582D03*
X242322Y1082677D03*
X234842D03*
X242322Y1086417D03*
X234842D03*
X246062Y1090157D03*
X242322D03*
X238582D03*
X234842D03*
X246062Y1086417D03*
X242322Y1078936D03*
X238582Y1086417D03*
X234842Y1078936D03*
X246062Y1082677D03*
X238582D03*
X246062Y1093897D03*
X238582D03*
X246062Y1097637D03*
X238582D03*
X242322Y1101377D03*
X234842D03*
X242322Y1105117D03*
X234842D03*
X246062D03*
X242322Y1097637D03*
X238582Y1105117D03*
X234842Y1097637D03*
X246062Y1101377D03*
X242322Y1093897D03*
X238582Y1101377D03*
X234842Y1093897D03*
X246062Y1108858D03*
X242322D03*
X238582D03*
X234842D03*
X246062Y1120078D03*
X242322D03*
X238582D03*
X234842D03*
X246062Y1123818D03*
X242322D03*
X238582D03*
X234842D03*
X246062Y1116338D03*
X238582D03*
X234842Y1112598D03*
X246062D03*
X242322Y1116338D03*
X234842D03*
X242322Y1112598D03*
X238582D03*
X246062Y1127558D03*
X242322D03*
X238582D03*
X234842D03*
X246062Y1135039D03*
X242322D03*
X238582D03*
X234842D03*
X246062Y1131299D03*
X242322D03*
X238582D03*
X234842D03*
X246062Y1138779D03*
X242322D03*
X238582D03*
X234842D03*
X246062Y1142519D03*
X242322D03*
X238582D03*
X234842D03*
X246062Y1149999D03*
X242322D03*
X238582D03*
X234842D03*
X246062Y1146259D03*
X242322D03*
X238582D03*
X234842D03*
X246062Y1153740D03*
X242322D03*
X238582D03*
X234842D03*
X246062Y1157480D03*
X238582D03*
X242322Y1161220D03*
X234842D03*
X246062Y1164960D03*
X238582D03*
X242322Y1168700D03*
X234842D03*
X246062Y1172440D03*
X238582D03*
X242322Y1157480D03*
X234842D03*
X246062Y1161220D03*
X238582D03*
X242322Y1164960D03*
X234842D03*
X246062Y1168700D03*
X238582D03*
X242322Y1172440D03*
X234842D03*
X246062Y1187401D03*
X242322D03*
X238582D03*
X234842D03*
X246062Y1179921D03*
X242322D03*
X238582D03*
X234842D03*
X246062Y1183661D03*
X242322D03*
X238582D03*
X234842D03*
X246062Y1176180D03*
X242322D03*
X238582D03*
X234842D03*
X246062Y1194881D03*
X242322D03*
X238582D03*
X234842D03*
X246062Y1202362D03*
X242322D03*
X238582D03*
X234842D03*
X246062Y1198621D03*
X242322D03*
X238582D03*
X234842D03*
X246062Y1191141D03*
X242322D03*
X238582D03*
X234842D03*
X246062Y1206102D03*
X242322D03*
X238582D03*
X234842D03*
X246062Y1209842D03*
X242322D03*
X238582D03*
X234842D03*
X246062Y1221062D03*
X242322D03*
X238582D03*
X234842D03*
X238582Y1217322D03*
X246062Y1213582D03*
X242322D03*
X246062Y1217322D03*
X234842D03*
Y1213582D03*
X242322Y1217322D03*
X238582Y1213582D03*
X242322Y1224803D03*
X234842D03*
X242322Y1228543D03*
X234842D03*
X246062Y1232283D03*
X238582D03*
X246062Y1236023D03*
X238582D03*
X246062Y1224803D03*
X242322Y1232283D03*
X238582Y1224803D03*
X234842Y1232283D03*
X246062Y1228543D03*
X242322Y1236023D03*
X238582Y1228543D03*
X234842Y1236023D03*
X246062Y1239763D03*
X242322D03*
X238582D03*
X234842D03*
X242322Y1243503D03*
X234842D03*
X242322Y1247243D03*
X234842D03*
X246062Y1250984D03*
X238582D03*
X246062Y1243503D03*
X242322Y1250984D03*
X238582Y1243503D03*
X234842Y1250984D03*
X246062Y1247243D03*
X238582D03*
X246062Y1254724D03*
X238582D03*
X242322D03*
X234842D03*
X261023Y1075196D03*
X253543D03*
X257283D03*
X249803D03*
X261023Y1078936D03*
X253543D03*
X257283Y1082677D03*
X249803D03*
X257283Y1086417D03*
X249803D03*
X261023Y1090157D03*
X257283D03*
X253543D03*
X249803D03*
X261023Y1086417D03*
X257283Y1078936D03*
X253543Y1086417D03*
X249803Y1078936D03*
X261023Y1082677D03*
X253543D03*
X261023Y1093897D03*
X253543D03*
X261023Y1097637D03*
X253543D03*
X257283Y1101377D03*
X249803D03*
X257283Y1105117D03*
X249803D03*
X261023D03*
X257283Y1097637D03*
X253543Y1105117D03*
X249803Y1097637D03*
X261023Y1101377D03*
X257283Y1093897D03*
X253543Y1101377D03*
X249803Y1093897D03*
X261023Y1108858D03*
X257283D03*
X253543D03*
X249803D03*
X261023Y1120078D03*
X257283D03*
X253543D03*
X249803D03*
X261023Y1123818D03*
X257283D03*
X253543D03*
X249803D03*
X253543Y1116338D03*
X249803D03*
Y1112598D03*
X257283Y1116338D03*
X261023Y1112598D03*
X257283D03*
X261023Y1116338D03*
X253543Y1112598D03*
X261023Y1127558D03*
X257283D03*
X253543D03*
X249803D03*
X261023Y1135039D03*
X257283D03*
X253543D03*
X249803D03*
X261023Y1131299D03*
X257283D03*
X253543D03*
X249803D03*
X261023Y1138779D03*
X257283D03*
X253543D03*
X249803D03*
X261023Y1142519D03*
X257283D03*
X253543D03*
X249803D03*
X261023Y1149999D03*
X257283D03*
X253543D03*
X249803D03*
X261023Y1146259D03*
X257283D03*
X253543D03*
X249803D03*
X261023Y1153740D03*
X257283D03*
X253543D03*
X249803D03*
X261023Y1157480D03*
X253543D03*
X257283Y1161220D03*
X249803D03*
X261023Y1164960D03*
X253543D03*
X257283Y1168700D03*
X249803D03*
X261023Y1172440D03*
X253543D03*
X261023Y1161220D03*
Y1168700D03*
X257283Y1157480D03*
X249803D03*
X253543Y1161220D03*
X257283Y1164960D03*
X249803D03*
X253543Y1168700D03*
X257283Y1172440D03*
X249803D03*
X261023Y1187401D03*
X257283D03*
X253543D03*
X249803D03*
X261023Y1179921D03*
X257283D03*
X253543D03*
X249803D03*
X261023Y1183661D03*
X257283D03*
X253543D03*
X249803D03*
X261023Y1176180D03*
X257283D03*
X253543D03*
X249803D03*
X261023Y1194881D03*
X257283D03*
X253543D03*
X249803D03*
X261023Y1202362D03*
X257283D03*
X253543D03*
X249803D03*
X261023Y1198621D03*
X257283D03*
X253543D03*
X249803D03*
X261023Y1191141D03*
X257283D03*
X253543D03*
X249803D03*
X261023Y1206102D03*
X257283D03*
X253543D03*
X249803D03*
X261023Y1209842D03*
X257283D03*
X253543D03*
X249803D03*
X261023Y1221062D03*
X257283D03*
X253543D03*
X249803D03*
Y1213582D03*
X261023D03*
X257283Y1217322D03*
X249803D03*
X257283Y1213582D03*
X253543D03*
X261023Y1217322D03*
X253543D03*
X257283Y1224803D03*
X249803D03*
X257283Y1228543D03*
X249803D03*
X261023Y1232283D03*
X253543D03*
X261023Y1236023D03*
X253543D03*
X261023Y1224803D03*
X257283Y1232283D03*
X253543Y1224803D03*
X249803Y1232283D03*
X261023Y1228543D03*
X257283Y1236023D03*
X253543Y1228543D03*
X249803Y1236023D03*
X261023Y1239763D03*
X257283D03*
X253543D03*
X249803D03*
X257283Y1243503D03*
X249803D03*
X257283Y1247243D03*
X249803D03*
X261023Y1250984D03*
X253543D03*
X261023Y1243503D03*
X257283Y1250984D03*
X253543Y1243503D03*
X249803Y1250984D03*
X261023Y1247243D03*
X253543D03*
X261023Y1254724D03*
X253543D03*
X257283D03*
X249803D03*
X275984Y1075196D03*
X268503D03*
X279724D03*
X272244D03*
X264763D03*
X275984Y1078936D03*
X268503D03*
X279724Y1082677D03*
X272244D03*
X264763D03*
X279724Y1086417D03*
X272244D03*
X264763D03*
X279724Y1090157D03*
X275984D03*
X272244D03*
X268503D03*
X264763D03*
X279724Y1078936D03*
X275984Y1086417D03*
X272244Y1078936D03*
X268503Y1086417D03*
X264763Y1078936D03*
X275984Y1082677D03*
X268503D03*
X275984Y1093897D03*
X268503D03*
X275984Y1097637D03*
X268503D03*
X279724Y1101377D03*
X272244D03*
X264763D03*
X279724Y1105117D03*
X272244D03*
X264763D03*
X279724Y1097637D03*
X275984Y1105117D03*
X272244Y1097637D03*
X268503Y1105117D03*
X264763Y1097637D03*
X279724Y1093897D03*
X275984Y1101377D03*
X272244Y1093897D03*
X268503Y1101377D03*
X264763Y1093897D03*
X279724Y1108858D03*
X275984D03*
X272244D03*
X268503D03*
X264763D03*
X279724Y1120078D03*
X275984D03*
X272244D03*
X268503D03*
X264763D03*
X279724Y1123818D03*
X272244D03*
X268503D03*
X264763D03*
X275984D03*
X279724Y1112598D03*
Y1116338D03*
X272244D03*
X275984Y1112598D03*
X264763Y1116338D03*
Y1112598D03*
X275984Y1116338D03*
X272244Y1112598D03*
X268503Y1116338D03*
Y1112598D03*
X279724Y1127558D03*
X272244D03*
X268503D03*
X264763D03*
X279724Y1131299D03*
X268503D03*
X279724Y1135039D03*
X272244D03*
X268503D03*
X264763D03*
X279724Y1138779D03*
X275984D03*
X268503D03*
X272244Y1131299D03*
Y1138779D03*
X264763Y1131299D03*
Y1138779D03*
X275984Y1127558D03*
Y1135039D03*
Y1131299D03*
X279724Y1142519D03*
X275984D03*
X268503D03*
X264763D03*
X279724Y1146259D03*
X275984D03*
X268503D03*
X279724Y1149999D03*
X275984D03*
X272244D03*
X268503D03*
X264763D03*
X279724Y1153740D03*
X275984D03*
X272244D03*
X268503D03*
X264763Y1146259D03*
Y1153740D03*
X272244Y1142519D03*
Y1146259D03*
X279724Y1157480D03*
X272244D03*
X268503D03*
X279724Y1161220D03*
X272244D03*
X279724Y1164960D03*
X272244D03*
X279724Y1168700D03*
X272244D03*
X279724Y1172440D03*
X272244D03*
X268503D03*
Y1161220D03*
X264763D03*
X268503Y1164960D03*
X264763D03*
X268503Y1168700D03*
X264763D03*
Y1157480D03*
Y1172440D03*
X275984Y1157480D03*
Y1161220D03*
Y1164960D03*
Y1168700D03*
Y1172440D03*
X279724Y1183661D03*
X275984D03*
X268503D03*
X279724Y1187401D03*
X275984D03*
X268503D03*
X264763D03*
X279724Y1176180D03*
X275984D03*
X268503D03*
X275984Y1179921D03*
X264763D03*
Y1183661D03*
Y1176180D03*
X279724Y1179921D03*
X268503D03*
X272244Y1183661D03*
Y1187401D03*
Y1179921D03*
Y1176180D03*
X279724Y1191141D03*
X275984D03*
X268503D03*
X279724Y1194881D03*
X272244D03*
X268503D03*
X264763D03*
X279724Y1198621D03*
X268503D03*
X279724Y1202362D03*
X272244D03*
X268503D03*
X264763D03*
X272244Y1198621D03*
Y1191141D03*
X264763Y1198621D03*
Y1191141D03*
X275984Y1198621D03*
Y1202362D03*
Y1194881D03*
X279724Y1206102D03*
X272244D03*
X268503D03*
X264763D03*
X279724Y1209842D03*
X275984D03*
X272244D03*
X268503D03*
X264763D03*
X279724Y1221062D03*
X275984D03*
X272244D03*
X268503D03*
X264763D03*
X275984Y1206102D03*
X268503Y1217322D03*
X275984D03*
Y1213582D03*
X279724D03*
X272244D03*
X268503D03*
X264763D03*
Y1217322D03*
X272244D03*
X279724D03*
Y1224803D03*
X272244D03*
X264763D03*
X279724Y1228543D03*
X272244D03*
X264763D03*
X275984Y1232283D03*
X268503D03*
X275984Y1236023D03*
X268503D03*
X279724Y1232283D03*
X275984Y1224803D03*
X272244Y1232283D03*
X268503Y1224803D03*
X264763Y1232283D03*
X279724Y1236023D03*
X275984Y1228543D03*
X272244Y1236023D03*
X268503Y1228543D03*
X264763Y1236023D03*
X279724Y1239763D03*
X275984D03*
X272244D03*
X268503D03*
X264763D03*
X279724Y1243503D03*
X272244D03*
X264763D03*
X279724Y1247243D03*
X272244D03*
X264763D03*
X275984Y1250984D03*
X268503D03*
X279724D03*
X275984Y1243503D03*
X272244Y1250984D03*
X268503Y1243503D03*
X264763Y1250984D03*
X275984Y1247243D03*
X268503D03*
X275984Y1254724D03*
X268503D03*
X279724D03*
X272244D03*
X264763D03*
X290944Y1075196D03*
X283464D03*
X287204D03*
X294685D03*
X290944Y1078936D03*
X283464D03*
X294685Y1082677D03*
X287204D03*
X294685Y1086417D03*
X287204D03*
X294685Y1090157D03*
X290944D03*
X287204D03*
X283464D03*
X290944Y1086417D03*
X287204Y1078936D03*
X283464Y1086417D03*
X290944Y1082677D03*
X283464D03*
X294685Y1078936D03*
X290944Y1093897D03*
X283464D03*
X290944Y1097637D03*
X283464D03*
X294685Y1101377D03*
X287204D03*
X294685Y1105117D03*
X287204D03*
X290944D03*
X287204Y1097637D03*
X283464Y1105117D03*
X290944Y1101377D03*
X287204Y1093897D03*
X283464Y1101377D03*
X294685Y1097637D03*
Y1093897D03*
Y1108858D03*
X290944D03*
X287204D03*
X283464D03*
X294685Y1112598D03*
X290944D03*
Y1116338D03*
X294685Y1120078D03*
X290944D03*
Y1123818D03*
X283464Y1120078D03*
Y1116338D03*
Y1123818D03*
X287204Y1116338D03*
Y1123818D03*
Y1120078D03*
Y1112598D03*
X283464D03*
X294685Y1116338D03*
Y1123818D03*
Y1127558D03*
X290944D03*
Y1131299D03*
X294685Y1135039D03*
X290944D03*
Y1138779D03*
X287204Y1127558D03*
Y1131299D03*
X283464Y1127558D03*
Y1131299D03*
X287204Y1138779D03*
X283464Y1135039D03*
X287204D03*
X283464Y1138779D03*
X294685D03*
Y1131299D03*
Y1142519D03*
X290944D03*
Y1146259D03*
X294685Y1149999D03*
X290944D03*
Y1153740D03*
X287204D03*
X283464D03*
Y1142519D03*
X287204Y1149999D03*
X283464D03*
Y1146259D03*
X287204Y1142519D03*
Y1146259D03*
X294685D03*
Y1153740D03*
Y1157480D03*
X290944D03*
X287204D03*
X290944Y1161220D03*
X287204D03*
X294685Y1164960D03*
X290944D03*
X287204D03*
X290944Y1168700D03*
X287204D03*
X294685Y1172440D03*
X290944D03*
X287204D03*
X283464Y1157480D03*
Y1161220D03*
Y1164960D03*
Y1168700D03*
Y1172440D03*
X294685Y1161220D03*
Y1168700D03*
X290944Y1183661D03*
X283464D03*
X294685Y1187401D03*
X290944D03*
Y1176180D03*
X287204D03*
X283464D03*
X294685Y1179921D03*
X290944D03*
X283464D03*
X287204Y1187401D03*
X283464D03*
X287204Y1179921D03*
Y1183661D03*
X294685Y1176180D03*
Y1183661D03*
X290944Y1191141D03*
X283464D03*
X294685Y1194881D03*
X290944D03*
Y1198621D03*
X294685Y1202362D03*
X290944D03*
X287204Y1191141D03*
X283464Y1194881D03*
Y1202362D03*
X287204Y1194881D03*
Y1202362D03*
Y1198621D03*
X283464D03*
X294685Y1191141D03*
Y1198621D03*
X290944Y1206102D03*
X294685Y1209842D03*
X290944D03*
Y1213582D03*
X294685Y1217322D03*
X290944D03*
X294685Y1221062D03*
X290944D03*
X287204D03*
X283464D03*
X287204Y1217322D03*
X283464Y1209842D03*
Y1213582D03*
Y1217322D03*
X287204Y1213582D03*
Y1209842D03*
X283464Y1206102D03*
X287204D03*
X294685Y1213582D03*
Y1206102D03*
Y1224803D03*
X287204D03*
X294685Y1228543D03*
X287204D03*
X290944Y1232283D03*
X283464D03*
X290944Y1236023D03*
X283464D03*
X287204Y1232283D03*
X283464Y1224803D03*
X287204Y1236023D03*
X283464Y1228543D03*
X290944Y1224803D03*
X294685Y1232283D03*
X290944Y1228543D03*
X294685Y1236023D03*
Y1239763D03*
X290944D03*
X287204D03*
X283464D03*
X294685Y1243503D03*
X287204D03*
X294685Y1247243D03*
X287204D03*
X290944Y1250984D03*
X283464D03*
X287204D03*
X283464Y1243503D03*
Y1247243D03*
X290944Y1243503D03*
X294685Y1250984D03*
X290944Y1247243D03*
Y1254724D03*
X283464D03*
X287204D03*
X294685D03*
X305905Y1075196D03*
X298425D03*
X302165D03*
X309645D03*
X305905Y1078936D03*
X298425D03*
X309645Y1082677D03*
X302165D03*
X309645Y1086417D03*
X302165D03*
X309645Y1090157D03*
X305905D03*
X302165D03*
X298425D03*
Y1086417D03*
X302165Y1078936D03*
X305905Y1086417D03*
X309645Y1078936D03*
X298425Y1082677D03*
X305905D03*
Y1093897D03*
X298425D03*
X305905Y1097637D03*
X298425D03*
X309645Y1101377D03*
X302165D03*
X309645Y1105117D03*
X302165D03*
X298425D03*
X302165Y1097637D03*
X305905Y1105117D03*
X309645Y1097637D03*
X298425Y1101377D03*
X302165Y1093897D03*
X305905Y1101377D03*
X309645Y1093897D03*
Y1108858D03*
X305905D03*
X302165D03*
X298425D03*
X309645Y1112598D03*
X298425D03*
X309645Y1116338D03*
X305905D03*
X302165D03*
X309645Y1120078D03*
X298425D03*
X309645Y1123818D03*
X305905D03*
X302165D03*
Y1112598D03*
Y1120078D03*
X305905Y1112598D03*
X298425Y1116338D03*
X305905Y1120078D03*
X298425Y1123818D03*
X309645Y1127558D03*
X298425D03*
X309645Y1131299D03*
X305905D03*
X302165D03*
X309645Y1135039D03*
X298425D03*
X309645Y1138779D03*
X305905D03*
X302165D03*
X298425D03*
X302165Y1127558D03*
Y1135039D03*
X305905Y1127558D03*
X298425Y1131299D03*
X305905Y1135039D03*
X309645Y1142519D03*
X298425D03*
X309645Y1146259D03*
X305905D03*
X302165D03*
X309645Y1149999D03*
X298425D03*
X309645Y1153740D03*
X305905D03*
X302165D03*
Y1142519D03*
Y1149999D03*
X305905Y1142519D03*
X298425Y1146259D03*
X305905Y1149999D03*
X298425Y1153740D03*
X309645Y1157480D03*
X298425D03*
X309645Y1161220D03*
X305905D03*
X302165D03*
X309645Y1164960D03*
X298425D03*
X309645Y1168700D03*
X305905D03*
X302165D03*
X309645Y1172440D03*
X298425D03*
X302165Y1157480D03*
Y1164960D03*
Y1172440D03*
X305905Y1157480D03*
X298425Y1161220D03*
X305905Y1164960D03*
X298425Y1168700D03*
X305905Y1172440D03*
X309645Y1183661D03*
X305905D03*
X302165D03*
X309645Y1187401D03*
X298425D03*
X309645Y1176180D03*
X305905D03*
X302165D03*
X309645Y1179921D03*
X298425D03*
X302165D03*
Y1187401D03*
X298425Y1176180D03*
X305905Y1179921D03*
X298425Y1183661D03*
X305905Y1187401D03*
X309645Y1191141D03*
X305905D03*
X302165D03*
X309645Y1194881D03*
X298425D03*
X309645Y1198621D03*
X305905D03*
X302165D03*
X309645Y1202362D03*
X298425D03*
X302165Y1194881D03*
X298425Y1191141D03*
X305905Y1194881D03*
X302165Y1202362D03*
X305905D03*
X298425Y1198621D03*
X309645Y1206102D03*
X305905D03*
X302165D03*
X309645Y1209842D03*
X298425D03*
X309645Y1213582D03*
X305905D03*
X302165D03*
X309645Y1217322D03*
X298425D03*
X309645Y1221062D03*
X305905D03*
X302165D03*
X298425D03*
X302165Y1217322D03*
Y1209842D03*
X305905Y1217322D03*
X298425Y1213582D03*
X305905Y1209842D03*
X298425Y1206102D03*
X309645Y1224803D03*
X302165D03*
X309645Y1228543D03*
X302165D03*
X305905Y1232283D03*
X298425D03*
X305905Y1236023D03*
X298425D03*
Y1224803D03*
X302165Y1232283D03*
X305905Y1224803D03*
X309645Y1232283D03*
X298425Y1228543D03*
X302165Y1236023D03*
X305905Y1228543D03*
X309645Y1236023D03*
Y1239763D03*
X305905D03*
X302165D03*
X298425D03*
X309645Y1243503D03*
X302165D03*
X309645Y1247243D03*
X302165D03*
X305905Y1250984D03*
X298425D03*
Y1243503D03*
X302165Y1250984D03*
X305905Y1243503D03*
X309645Y1250984D03*
X298425Y1247243D03*
X305905D03*
Y1254724D03*
X298425D03*
X302165D03*
X309645D03*
X320866Y1075196D03*
X313385D03*
X317125D03*
X324606Y1078936D03*
X320866D03*
X313385D03*
X317125Y1082677D03*
X324606Y1086417D03*
X320866D03*
X317125D03*
Y1090157D03*
X313385D03*
X320866D03*
X324606D03*
X317125Y1078936D03*
X320866Y1082677D03*
X313385Y1086417D03*
X324606Y1082677D03*
X313385D03*
X324606Y1093897D03*
X320866D03*
X313385D03*
X324606Y1097637D03*
X320866D03*
X313385D03*
X317125Y1101377D03*
X324606Y1105117D03*
X320866D03*
X317125D03*
Y1097637D03*
X320866Y1101377D03*
X313385Y1105117D03*
X317125Y1093897D03*
X324606Y1101377D03*
X313385D03*
X317125Y1108858D03*
X313385D03*
X324606Y1112598D03*
X320866D03*
X317125Y1116338D03*
X313385D03*
X324606Y1120078D03*
X320866D03*
X317125Y1123818D03*
X313385D03*
X320866Y1108858D03*
X313385Y1112598D03*
X320866Y1116338D03*
X313385Y1120078D03*
X320866Y1123818D03*
X324606Y1108858D03*
X317125Y1112598D03*
X324606Y1116338D03*
X317125Y1120078D03*
X324606Y1123818D03*
Y1127558D03*
X320866D03*
X317125Y1131299D03*
X313385D03*
X324606Y1135039D03*
X320866D03*
X317125Y1138779D03*
X313385D03*
X320866D03*
X324606D03*
X313385Y1127558D03*
X320866Y1131299D03*
X313385Y1135039D03*
X317125Y1127558D03*
X324606Y1131299D03*
X317125Y1135039D03*
X324606Y1142519D03*
X320866D03*
X317125Y1146259D03*
X313385D03*
X324606Y1149999D03*
X320866D03*
X317125Y1153740D03*
X313385D03*
Y1142519D03*
X320866Y1146259D03*
X313385Y1149999D03*
X320866Y1153740D03*
X317125Y1142519D03*
X324606Y1146259D03*
X317125Y1149999D03*
X324606Y1153740D03*
Y1157480D03*
X320866D03*
X317125Y1161220D03*
X313385D03*
X324606Y1164960D03*
X320866D03*
X317125Y1168700D03*
X313385D03*
X324606Y1172440D03*
X320866D03*
X313385Y1157480D03*
X320866Y1161220D03*
X313385Y1164960D03*
X320866Y1168700D03*
X313385Y1172440D03*
X317125Y1157480D03*
X324606Y1161220D03*
X317125Y1164960D03*
X324606Y1168700D03*
X317125Y1172440D03*
Y1183661D03*
X313385D03*
X324606Y1187401D03*
X320866D03*
X317125Y1176180D03*
X313385D03*
X324606Y1179921D03*
X320866D03*
Y1176180D03*
X313385Y1179921D03*
X320866Y1183661D03*
X313385Y1187401D03*
X324606Y1176180D03*
X317125Y1179921D03*
X324606Y1183661D03*
X317125Y1187401D03*
Y1191141D03*
X313385D03*
X324606Y1194881D03*
X320866D03*
X317125Y1198621D03*
X313385D03*
X324606Y1202362D03*
X320866D03*
Y1191141D03*
X313385Y1194881D03*
X324606Y1191141D03*
X317125Y1194881D03*
X313385Y1202362D03*
X320866Y1198621D03*
X317125Y1202362D03*
X324606Y1198621D03*
X317125Y1206102D03*
X313385D03*
X324606Y1209842D03*
X320866D03*
X317125Y1213582D03*
X313385D03*
X324606Y1217322D03*
X320866D03*
X317125Y1221062D03*
X313385D03*
X320866D03*
X313385Y1217322D03*
X320866Y1213582D03*
X313385Y1209842D03*
X320866Y1206102D03*
X324606Y1221062D03*
X317125Y1217322D03*
X324606Y1213582D03*
X317125Y1209842D03*
X324606Y1206102D03*
Y1224803D03*
X320866D03*
X317125D03*
Y1228543D03*
X324606Y1232283D03*
X320866D03*
X313385D03*
X324606Y1236023D03*
X320866D03*
X313385D03*
Y1224803D03*
X317125Y1232283D03*
X320866Y1228543D03*
X313385D03*
X317125Y1236023D03*
X324606Y1228543D03*
X317125Y1239763D03*
X313385D03*
X324606Y1243503D03*
X320866D03*
X317125D03*
Y1247243D03*
X324606Y1250984D03*
X320866D03*
X313385D03*
X320866Y1239763D03*
X324606D03*
X313385Y1243503D03*
X317125Y1250984D03*
X320866Y1247243D03*
X313385D03*
X324606D03*
X320866Y1254724D03*
X313385D03*
X317125D03*
X602165Y1078936D03*
Y1086417D03*
Y1090157D03*
Y1082677D03*
Y1093897D03*
Y1097637D03*
Y1105117D03*
Y1101377D03*
Y1112598D03*
Y1120078D03*
Y1108858D03*
Y1116338D03*
Y1123818D03*
Y1127558D03*
Y1135039D03*
Y1131299D03*
Y1138779D03*
Y1142519D03*
Y1146259D03*
Y1153740D03*
Y1149999D03*
Y1161220D03*
Y1168700D03*
Y1157480D03*
Y1164960D03*
Y1172440D03*
Y1183661D03*
Y1187401D03*
Y1176180D03*
Y1179921D03*
Y1194881D03*
Y1202362D03*
Y1198621D03*
Y1191141D03*
Y1209842D03*
Y1217322D03*
Y1221062D03*
Y1213582D03*
Y1206102D03*
Y1224803D03*
Y1232283D03*
Y1236023D03*
Y1228543D03*
Y1243503D03*
Y1250984D03*
Y1239763D03*
Y1247243D03*
X620866Y1075196D03*
X613386D03*
X605905D03*
X617126D03*
X609646D03*
X620866Y1078936D03*
X613386D03*
X605905D03*
X617126Y1082677D03*
X609646D03*
X617126Y1086417D03*
X609646D03*
X605905D03*
X620866Y1090157D03*
X617126D03*
X613386D03*
X609646D03*
X605905D03*
X620866Y1086417D03*
X617126Y1078936D03*
X613386Y1086417D03*
X609646Y1078936D03*
X605905Y1082677D03*
X620866D03*
X613386D03*
X620866Y1093897D03*
X613386D03*
X605905D03*
X620866Y1097637D03*
X613386D03*
X605905D03*
X617126Y1101377D03*
X609646D03*
X617126Y1105117D03*
X609646D03*
X605905D03*
X620866D03*
X617126Y1097637D03*
X613386Y1105117D03*
X609646Y1097637D03*
X605905Y1101377D03*
X620866D03*
X617126Y1093897D03*
X613386Y1101377D03*
X609646Y1093897D03*
X620866Y1108858D03*
X617126D03*
X613386D03*
X609646D03*
X617126Y1112598D03*
X605905D03*
X620866Y1116338D03*
X617126D03*
X613386D03*
X609646D03*
X617126Y1120078D03*
X605905D03*
X620866Y1123818D03*
X617126D03*
X613386D03*
X609646D03*
X620866Y1112598D03*
Y1120078D03*
X605905Y1108858D03*
X613386Y1112598D03*
X605905Y1116338D03*
X613386Y1120078D03*
X605905Y1123818D03*
X609646Y1112598D03*
Y1120078D03*
X617126Y1127558D03*
X605905D03*
X620866Y1131299D03*
X617126D03*
X613386D03*
X609646D03*
X617126Y1135039D03*
X605905D03*
X620866Y1138779D03*
X617126D03*
X613386D03*
X609646D03*
X620866Y1127558D03*
Y1135039D03*
X613386Y1127558D03*
X605905Y1131299D03*
X613386Y1135039D03*
X605905Y1138779D03*
X609646Y1127558D03*
Y1135039D03*
X620866Y1142519D03*
X617126D03*
X613386D03*
X609646D03*
X605905D03*
X620866Y1146259D03*
X609646D03*
X605905D03*
X620866Y1149999D03*
X617126D03*
X613386D03*
X609646D03*
X620866Y1153740D03*
X609646D03*
X605905D03*
X613386Y1146259D03*
X617126D03*
X605905Y1149999D03*
X617126Y1153740D03*
X613386D03*
X620866Y1157480D03*
X617126D03*
X613386D03*
X609646D03*
X620866Y1161220D03*
X609646D03*
X605905D03*
X620866Y1164960D03*
X617126D03*
X613386D03*
X609646D03*
X620866Y1168700D03*
X609646D03*
X605905D03*
X620866Y1172440D03*
X617126D03*
X613386D03*
X609646D03*
X605905Y1157480D03*
X617126Y1161220D03*
X613386D03*
X605905Y1164960D03*
X617126Y1168700D03*
X613386D03*
X605905Y1172440D03*
X620866Y1183661D03*
X617126D03*
X613386D03*
X609646D03*
X605905D03*
X617126Y1187401D03*
X605905D03*
X620866Y1176180D03*
X609646D03*
X605905D03*
X620866Y1179921D03*
X617126D03*
X613386D03*
X609646D03*
X605905D03*
X617126Y1176180D03*
X613386D03*
X620866Y1187401D03*
X613386D03*
X609646D03*
X620866Y1191141D03*
X617126D03*
X613386D03*
X609646D03*
X617126Y1194881D03*
X605905D03*
X620866Y1198621D03*
X617126D03*
X613386D03*
X609646D03*
X617126Y1202362D03*
X605905D03*
X620866D03*
Y1194881D03*
X613386Y1202362D03*
X605905Y1198621D03*
X613386Y1194881D03*
X605905Y1191141D03*
X609646Y1202362D03*
Y1194881D03*
X620866Y1206102D03*
X617126D03*
X613386D03*
X609646D03*
X617126Y1209842D03*
X605905D03*
X620866Y1213582D03*
X617126D03*
X613386D03*
X609646D03*
X617126Y1217322D03*
X605905D03*
X620866Y1221062D03*
X617126D03*
X613386D03*
X609646D03*
X620866Y1217322D03*
Y1209842D03*
X605905Y1221062D03*
X613386Y1217322D03*
X605905Y1213582D03*
X613386Y1209842D03*
X605905Y1206102D03*
X609646Y1217322D03*
Y1209842D03*
X617126Y1224803D03*
X609646D03*
X605905D03*
X617126Y1228543D03*
X609646D03*
X620866Y1232283D03*
X613386D03*
X605905D03*
X620866Y1236023D03*
X613386D03*
X605905D03*
X620866Y1224803D03*
X617126Y1232283D03*
X613386Y1224803D03*
X609646Y1232283D03*
X605905Y1228543D03*
X620866D03*
X617126Y1236023D03*
X613386Y1228543D03*
X609646Y1236023D03*
X620866Y1239763D03*
X617126D03*
X613386D03*
X609646D03*
X617126Y1243503D03*
X609646D03*
X605905D03*
X617126Y1247243D03*
X609646D03*
X620866Y1250984D03*
X613386D03*
X605905D03*
Y1239763D03*
X620866Y1243503D03*
X617126Y1250984D03*
X613386Y1243503D03*
X609646Y1250984D03*
X605905Y1247243D03*
X620866D03*
X613386D03*
X620866Y1254724D03*
X613386D03*
X605905D03*
X617126D03*
X609646D03*
X628346Y1075196D03*
X635827D03*
X624606D03*
X632086D03*
X628346Y1078936D03*
X635827D03*
X632086Y1082677D03*
X624606D03*
X632086Y1086417D03*
X624606D03*
X632086Y1090157D03*
X628346D03*
X624606D03*
X635827D03*
X628346Y1086417D03*
X624606Y1078936D03*
X628346Y1082677D03*
X632086Y1078936D03*
X635827Y1086417D03*
Y1082677D03*
X628346Y1093897D03*
X635827D03*
X628346Y1097637D03*
X635827D03*
X632086Y1101377D03*
X624606D03*
X632086Y1105117D03*
X624606D03*
X628346D03*
X624606Y1097637D03*
X628346Y1101377D03*
X624606Y1093897D03*
X632086Y1097637D03*
X635827Y1105117D03*
X632086Y1093897D03*
X635827Y1101377D03*
X632086Y1108858D03*
X628346D03*
X624606D03*
X635827D03*
X632086Y1112598D03*
X628346D03*
X635827D03*
X624606Y1116338D03*
X635827D03*
X632086Y1120078D03*
X628346D03*
X635827D03*
X624606Y1123818D03*
X635827D03*
X624606Y1112598D03*
X632086Y1116338D03*
X624606Y1120078D03*
X632086Y1123818D03*
X628346Y1116338D03*
Y1123818D03*
X632086Y1127558D03*
X628346D03*
X635827D03*
X624606Y1131299D03*
X635827D03*
X632086Y1135039D03*
X628346D03*
X635827D03*
X624606Y1138779D03*
X635827D03*
X624606Y1127558D03*
X632086Y1131299D03*
X624606Y1135039D03*
X632086Y1138779D03*
X628346Y1131299D03*
Y1138779D03*
X632086Y1142519D03*
X628346D03*
X624606D03*
X635827D03*
X632086Y1146259D03*
X628346D03*
X632086Y1149999D03*
Y1153740D03*
X635827Y1146259D03*
Y1149999D03*
Y1153740D03*
X628346D03*
X624606Y1149999D03*
X628346D03*
X624606Y1146259D03*
Y1153740D03*
X632086Y1157480D03*
X635827D03*
X632086Y1161220D03*
Y1164960D03*
Y1168700D03*
X635827D03*
X632086Y1172440D03*
X635827D03*
Y1161220D03*
Y1164960D03*
X628346D03*
Y1172440D03*
Y1168700D03*
X624606Y1172440D03*
Y1168700D03*
Y1164960D03*
X628346Y1157480D03*
Y1161220D03*
X624606D03*
Y1157480D03*
X632086Y1183661D03*
X628346D03*
X624606D03*
X635827D03*
X632086Y1187401D03*
X628346D03*
X635827D03*
X632086Y1176180D03*
Y1179921D03*
X628346D03*
X624606D03*
X635827Y1176180D03*
Y1179921D03*
X624606Y1176180D03*
X628346D03*
X624606Y1187401D03*
Y1191141D03*
X635827D03*
X632086Y1194881D03*
X628346D03*
X635827D03*
X624606Y1198621D03*
X635827D03*
X632086Y1202362D03*
X628346D03*
X635827D03*
X624606D03*
X632086Y1198621D03*
X624606Y1194881D03*
X632086Y1191141D03*
X628346Y1198621D03*
Y1191141D03*
X624606Y1206102D03*
X635827D03*
X632086Y1209842D03*
X628346D03*
X635827D03*
X624606Y1213582D03*
X635827D03*
X632086Y1217322D03*
X628346D03*
X635827D03*
X632086Y1221062D03*
X628346D03*
X624606D03*
X635827D03*
X624606Y1217322D03*
X632086Y1213582D03*
X624606Y1209842D03*
X632086Y1206102D03*
X628346Y1213582D03*
Y1206102D03*
X632086Y1224803D03*
X624606D03*
X632086Y1228543D03*
X624606D03*
X628346Y1232283D03*
X635827D03*
X628346Y1236023D03*
X635827D03*
X624606Y1232283D03*
Y1236023D03*
X628346Y1224803D03*
X632086Y1232283D03*
X635827Y1224803D03*
X628346Y1228543D03*
X632086Y1236023D03*
X635827Y1228543D03*
X632086Y1239763D03*
X628346D03*
X624606D03*
X635827D03*
X632086Y1243503D03*
X624606D03*
X632086Y1247243D03*
X624606D03*
X628346Y1250984D03*
X635827D03*
X624606D03*
X628346Y1243503D03*
X632086Y1250984D03*
X635827Y1243503D03*
X628346Y1247243D03*
X635827D03*
X628346Y1254724D03*
X635827D03*
X624606D03*
X632086D03*
X650787Y1075196D03*
X643307D03*
X639567D03*
X647047D03*
X650787Y1078936D03*
X643307D03*
X647047Y1082677D03*
X639567D03*
X647047Y1086417D03*
X639567D03*
X650787Y1090157D03*
X647047D03*
X643307D03*
X639567D03*
Y1078936D03*
X643307Y1086417D03*
X647047Y1078936D03*
X650787Y1086417D03*
X643307Y1082677D03*
X650787D03*
Y1093897D03*
X643307D03*
X650787Y1097637D03*
X643307D03*
X647047Y1101377D03*
X639567D03*
X647047Y1105117D03*
X639567D03*
Y1097637D03*
X643307Y1105117D03*
X647047Y1097637D03*
X650787Y1105117D03*
X639567Y1093897D03*
X643307Y1101377D03*
X647047Y1093897D03*
X650787Y1101377D03*
Y1108858D03*
X647047D03*
X643307D03*
X639567D03*
Y1112598D03*
Y1116338D03*
X650787Y1120078D03*
X647047D03*
X643307D03*
X639567D03*
X650787Y1123818D03*
X647047D03*
X643307D03*
X639567D03*
X647047Y1116338D03*
X643307D03*
Y1112598D03*
X647047D03*
X650787Y1116338D03*
Y1112598D03*
Y1127558D03*
X647047D03*
X643307D03*
X639567D03*
X647047Y1131299D03*
X643307D03*
X639567D03*
X647047Y1135039D03*
X643307D03*
X639567D03*
X647047Y1138779D03*
X639567D03*
X643307D03*
X650787D03*
Y1131299D03*
Y1135039D03*
X643307Y1149999D03*
X647047Y1153740D03*
Y1142519D03*
X643307D03*
X639567D03*
X647047Y1146259D03*
X639567D03*
X650787Y1149999D03*
X639567D03*
Y1153740D03*
X650787Y1142519D03*
X643307Y1146259D03*
X647047Y1149999D03*
X643307Y1153740D03*
X650787Y1146259D03*
Y1153740D03*
X643307Y1157480D03*
X647047Y1161220D03*
X643307Y1164960D03*
X647047Y1168700D03*
X643307Y1172440D03*
X650787Y1157480D03*
X639567D03*
Y1161220D03*
X650787Y1164960D03*
X639567D03*
Y1168700D03*
X650787Y1172440D03*
X639567D03*
X647047D03*
Y1157480D03*
X643307Y1161220D03*
X647047Y1164960D03*
X643307Y1168700D03*
X650787Y1161220D03*
Y1168700D03*
X647047Y1176180D03*
X643307Y1179921D03*
X647047Y1183661D03*
X639567D03*
X650787Y1187401D03*
X647047D03*
X643307D03*
X639567D03*
Y1176180D03*
X650787Y1179921D03*
X639567D03*
X643307Y1183661D03*
Y1176180D03*
X647047Y1179921D03*
X650787Y1183661D03*
Y1176180D03*
X647047Y1191141D03*
X643307D03*
X639567D03*
X647047Y1194881D03*
X643307D03*
X639567D03*
X647047Y1198621D03*
X643307D03*
X639567D03*
X650787Y1202362D03*
X647047D03*
X643307D03*
X639567D03*
X650787Y1191141D03*
Y1198621D03*
Y1194881D03*
Y1206102D03*
X647047D03*
X643307D03*
X639567D03*
X650787Y1209842D03*
X647047D03*
X643307D03*
X639567D03*
X650787Y1213582D03*
X643307D03*
X639567D03*
X650787Y1217322D03*
X639567D03*
X650787Y1221062D03*
X647047D03*
X643307D03*
X639567D03*
X647047Y1217322D03*
X643307D03*
X647047Y1213582D03*
Y1224803D03*
X639567D03*
X647047Y1228543D03*
X639567D03*
X650787Y1232283D03*
X643307D03*
X650787Y1236023D03*
X643307D03*
X639567Y1232283D03*
X643307Y1224803D03*
X647047Y1232283D03*
X650787Y1224803D03*
X639567Y1236023D03*
X643307Y1228543D03*
X647047Y1236023D03*
X650787Y1228543D03*
Y1239763D03*
X647047D03*
X643307D03*
X639567D03*
X647047Y1243503D03*
X639567D03*
X647047Y1247243D03*
X639567D03*
X650787Y1250984D03*
X643307D03*
X639567D03*
X643307Y1243503D03*
X647047Y1250984D03*
X650787Y1243503D03*
X643307Y1247243D03*
X650787D03*
Y1254724D03*
X643307D03*
X639567D03*
X647047D03*
X665748Y1075196D03*
X658268D03*
X654527D03*
X662008D03*
X669488D03*
X665748Y1078936D03*
X658268D03*
X669488Y1082677D03*
X662008D03*
X654527D03*
X669488Y1086417D03*
X662008D03*
X654527D03*
X669488Y1090157D03*
X665748D03*
X662008D03*
X658268D03*
X654527D03*
Y1078936D03*
X658268Y1086417D03*
X662008Y1078936D03*
X665748Y1086417D03*
X669488Y1078936D03*
X658268Y1082677D03*
X665748D03*
Y1093897D03*
X658268D03*
X665748Y1097637D03*
X658268D03*
X669488Y1101377D03*
X662008D03*
X654527D03*
X669488Y1105117D03*
X662008D03*
X654527D03*
Y1097637D03*
X658268Y1105117D03*
X662008Y1097637D03*
X665748Y1105117D03*
X669488Y1097637D03*
X654527Y1093897D03*
X658268Y1101377D03*
X662008Y1093897D03*
X665748Y1101377D03*
X669488Y1093897D03*
Y1108858D03*
X665748D03*
X662008D03*
X658268D03*
X654527D03*
X669488Y1120078D03*
X665748D03*
X662008D03*
X658268D03*
X654527D03*
X669488Y1123818D03*
X665748D03*
X662008D03*
X658268D03*
X654527D03*
X658268Y1112598D03*
X662008Y1116338D03*
X658268D03*
X662008Y1112598D03*
X665748Y1116338D03*
Y1112598D03*
X669488Y1116338D03*
X654527D03*
Y1112598D03*
X669488D03*
Y1127558D03*
X665748D03*
X662008D03*
X658268D03*
X654527D03*
Y1131299D03*
X669488Y1135039D03*
X665748D03*
X662008D03*
X658268D03*
X654527D03*
Y1138779D03*
X669488Y1131299D03*
X665748D03*
X662008D03*
X658268D03*
X669488Y1138779D03*
X665748D03*
X662008D03*
X658268D03*
X669488Y1142519D03*
X665748D03*
X662008D03*
X658268D03*
X654527Y1146259D03*
X669488Y1149999D03*
X665748D03*
X662008D03*
X658268D03*
X654527Y1153740D03*
X669488Y1146259D03*
X665748D03*
X662008D03*
X658268D03*
X669488Y1153740D03*
X665748D03*
X662008D03*
X658268D03*
X654527Y1142519D03*
Y1149999D03*
X665748Y1157480D03*
X658268D03*
X669488Y1161220D03*
X662008D03*
X654527D03*
X665748Y1164960D03*
X658268D03*
X669488Y1168700D03*
X662008D03*
X654527D03*
X665748Y1172440D03*
X658268D03*
X669488Y1157480D03*
X662008D03*
X654527D03*
X665748Y1161220D03*
X658268D03*
X669488Y1164960D03*
X662008D03*
X654527D03*
X665748Y1168700D03*
X658268D03*
X669488Y1172440D03*
X662008D03*
X654527D03*
Y1183661D03*
X669488Y1187401D03*
X665748D03*
X662008D03*
X658268D03*
X654527D03*
Y1176180D03*
X669488Y1179921D03*
X665748D03*
X662008D03*
X658268D03*
X669488Y1183661D03*
X665748D03*
X662008D03*
X658268D03*
X669488Y1176180D03*
X665748D03*
X662008D03*
X658268D03*
X654527Y1179921D03*
Y1191141D03*
X669488Y1194881D03*
X665748D03*
X662008D03*
X658268D03*
X654527D03*
Y1198621D03*
X669488Y1202362D03*
X665748D03*
X662008D03*
X658268D03*
X654527D03*
X669488Y1198621D03*
X665748D03*
X662008D03*
X658268D03*
X669488Y1191141D03*
X665748D03*
X662008D03*
X658268D03*
X669488Y1206102D03*
X665748D03*
X662008D03*
X658268D03*
X654527D03*
X669488Y1209842D03*
X665748D03*
X662008D03*
X658268D03*
X654527D03*
X669488Y1221062D03*
X665748D03*
X662008D03*
X658268D03*
X654527D03*
X662008Y1213582D03*
X658268D03*
X669488D03*
X665748Y1217322D03*
Y1213582D03*
X669488Y1217322D03*
X662008D03*
X654527Y1213582D03*
X658268Y1217322D03*
X654527D03*
X669488Y1224803D03*
X662008D03*
X654527D03*
X669488Y1228543D03*
X662008D03*
X654527D03*
X665748Y1232283D03*
X658268D03*
X665748Y1236023D03*
X658268D03*
X654527Y1232283D03*
X658268Y1224803D03*
X662008Y1232283D03*
X665748Y1224803D03*
X669488Y1232283D03*
X654527Y1236023D03*
X658268Y1228543D03*
X662008Y1236023D03*
X665748Y1228543D03*
X669488Y1236023D03*
Y1239763D03*
X665748D03*
X662008D03*
X658268D03*
X654527D03*
X669488Y1243503D03*
X662008D03*
X654527D03*
X669488Y1247243D03*
X662008D03*
X654527D03*
X665748Y1250984D03*
X658268D03*
X654527D03*
X658268Y1243503D03*
X662008Y1250984D03*
X665748Y1243503D03*
X669488Y1250984D03*
X658268Y1247243D03*
X665748D03*
Y1254724D03*
X658268D03*
X654527D03*
X662008D03*
X669488D03*
X680709Y1075196D03*
X673228D03*
X676968D03*
X684449D03*
X680709Y1078936D03*
X673228D03*
X684449Y1082677D03*
X676968D03*
X684449Y1086417D03*
X676968D03*
X684449Y1090157D03*
X680709D03*
X676968D03*
X673228D03*
Y1086417D03*
X676968Y1078936D03*
X680709Y1086417D03*
X684449Y1078936D03*
X673228Y1082677D03*
X680709D03*
Y1093897D03*
X673228D03*
X680709Y1097637D03*
X673228D03*
X684449Y1101377D03*
X676968D03*
X684449Y1105117D03*
X676968D03*
X673228D03*
X676968Y1097637D03*
X680709Y1105117D03*
X684449Y1097637D03*
X673228Y1101377D03*
X676968Y1093897D03*
X680709Y1101377D03*
X684449Y1093897D03*
Y1108858D03*
X680709D03*
X676968D03*
X673228D03*
Y1112598D03*
Y1116338D03*
X684449Y1120078D03*
X680709D03*
X676968D03*
X673228D03*
X684449Y1123818D03*
X680709D03*
X676968D03*
X673228D03*
X684449Y1116338D03*
X680709Y1112598D03*
Y1116338D03*
X676968D03*
Y1112598D03*
X684449D03*
Y1127558D03*
X680709D03*
X676968D03*
X673228D03*
X684449Y1135039D03*
X680709D03*
X676968D03*
X673228D03*
X684449Y1131299D03*
X680709D03*
X676968D03*
X673228D03*
X684449Y1138779D03*
X680709D03*
X676968D03*
X673228D03*
X684449Y1142519D03*
X680709D03*
X676968D03*
X673228D03*
X684449Y1149999D03*
X680709D03*
X676968D03*
X673228D03*
X684449Y1146259D03*
X680709D03*
X676968D03*
X673228D03*
X684449Y1153740D03*
X680709D03*
X676968D03*
X673228D03*
X680709Y1157480D03*
X673228D03*
X684449Y1161220D03*
X676968D03*
X680709Y1164960D03*
X673228D03*
X684449Y1168700D03*
X676968D03*
X680709Y1172440D03*
X673228D03*
X684449Y1157480D03*
X676968D03*
X680709Y1161220D03*
X673228D03*
X684449Y1164960D03*
X676968D03*
X680709Y1168700D03*
X673228D03*
X684449Y1172440D03*
X676968D03*
X684449Y1187401D03*
X680709D03*
X676968D03*
X673228D03*
X684449Y1179921D03*
X680709D03*
X676968D03*
X673228D03*
X684449Y1183661D03*
X680709D03*
X676968D03*
X673228D03*
X684449Y1176180D03*
X680709D03*
X676968D03*
X673228D03*
X684449Y1194881D03*
X680709D03*
X676968D03*
X673228D03*
X684449Y1202362D03*
X680709D03*
X676968D03*
X673228D03*
X684449Y1198621D03*
X680709D03*
X676968D03*
X673228D03*
X684449Y1191141D03*
X680709D03*
X676968D03*
X673228D03*
X684449Y1206102D03*
X680709D03*
X676968D03*
X673228D03*
X684449Y1209842D03*
X680709D03*
X676968D03*
X673228D03*
X676968Y1213582D03*
Y1217322D03*
X684449Y1221062D03*
X680709D03*
X676968D03*
X673228D03*
X684449Y1217322D03*
Y1213582D03*
X680709D03*
Y1217322D03*
X673228D03*
Y1213582D03*
X684449Y1224803D03*
X676968D03*
X684449Y1228543D03*
X676968D03*
X680709Y1232283D03*
X673228D03*
X680709Y1236023D03*
X673228D03*
Y1224803D03*
X676968Y1232283D03*
X680709Y1224803D03*
X684449Y1232283D03*
X673228Y1228543D03*
X676968Y1236023D03*
X680709Y1228543D03*
X684449Y1236023D03*
Y1239763D03*
X680709D03*
X676968D03*
X673228D03*
X684449Y1243503D03*
X676968D03*
X684449Y1247243D03*
X676968D03*
X680709Y1250984D03*
X673228D03*
Y1243503D03*
X676968Y1250984D03*
X680709Y1243503D03*
X684449Y1250984D03*
X673228Y1247243D03*
X680709D03*
Y1254724D03*
X673228D03*
X676968D03*
X684449D03*
X695669Y1075196D03*
X688189D03*
X699409D03*
X691929D03*
X695669Y1078936D03*
X688189D03*
X699409Y1082677D03*
X691929D03*
X699409Y1086417D03*
X691929D03*
X699409Y1090157D03*
X695669D03*
X691929D03*
X688189D03*
Y1086417D03*
Y1082677D03*
X699409Y1078936D03*
X695669Y1086417D03*
X691929Y1078936D03*
X695669Y1082677D03*
Y1093897D03*
X688189D03*
X695669Y1097637D03*
X688189D03*
X699409Y1101377D03*
X691929D03*
X699409Y1105117D03*
X691929D03*
X688189D03*
Y1101377D03*
X699409Y1097637D03*
X695669Y1105117D03*
X691929Y1097637D03*
X699409Y1093897D03*
X695669Y1101377D03*
X691929Y1093897D03*
X699409Y1108858D03*
X695669D03*
X691929D03*
X688189D03*
Y1112598D03*
Y1116338D03*
X699409Y1120078D03*
X695669D03*
X691929D03*
X688189D03*
X699409Y1123818D03*
X695669D03*
X691929D03*
X688189D03*
X695669Y1116338D03*
X691929Y1112598D03*
X699409Y1116338D03*
X691929D03*
X699409Y1112598D03*
X695669D03*
X699409Y1127558D03*
X695669D03*
X691929D03*
X688189D03*
X699409Y1135039D03*
X695669D03*
X691929D03*
X688189D03*
X699409Y1131299D03*
X695669D03*
X691929D03*
X688189D03*
X699409Y1138779D03*
X695669D03*
X691929D03*
X688189D03*
X699409Y1142519D03*
X695669D03*
X691929D03*
X688189D03*
X699409Y1149999D03*
X695669D03*
X691929D03*
X688189D03*
X699409Y1146259D03*
X695669D03*
X691929D03*
X688189D03*
X699409Y1153740D03*
X695669D03*
X691929D03*
X688189D03*
X695669Y1157480D03*
X688189D03*
X699409Y1161220D03*
X691929D03*
X695669Y1164960D03*
X688189D03*
X699409Y1168700D03*
X691929D03*
X695669Y1172440D03*
X688189D03*
X699409Y1157480D03*
X691929D03*
X695669Y1161220D03*
X688189D03*
X699409Y1164960D03*
X691929D03*
X695669Y1168700D03*
X688189D03*
X699409Y1172440D03*
X691929D03*
X699409Y1187401D03*
X695669D03*
X691929D03*
X688189D03*
X699409Y1179921D03*
X695669D03*
X691929D03*
X688189D03*
X699409Y1183661D03*
X695669D03*
X691929D03*
X688189D03*
X699409Y1176180D03*
X695669D03*
X691929D03*
X688189D03*
X699409Y1194881D03*
X695669D03*
X691929D03*
X688189D03*
X699409Y1202362D03*
X695669D03*
X691929D03*
X688189D03*
X699409Y1198621D03*
X695669D03*
X691929D03*
X688189D03*
X699409Y1191141D03*
X695669D03*
X691929D03*
X688189D03*
X699409Y1206102D03*
X695669D03*
X691929D03*
X688189D03*
X699409Y1209842D03*
X695669D03*
X691929D03*
X688189D03*
X699409Y1221062D03*
X695669D03*
X691929D03*
X688189D03*
X695669Y1217322D03*
X688189Y1213582D03*
Y1217322D03*
X699409Y1213582D03*
X691929Y1217322D03*
Y1213582D03*
X699409Y1217322D03*
X695669Y1213582D03*
X699409Y1224803D03*
X691929D03*
X699409Y1228543D03*
X691929D03*
X695669Y1232283D03*
X688189D03*
X695669Y1236023D03*
X688189D03*
X699409Y1232283D03*
X695669Y1224803D03*
X691929Y1232283D03*
X688189Y1224803D03*
X699409Y1236023D03*
X695669Y1228543D03*
X691929Y1236023D03*
X688189Y1228543D03*
X699409Y1239763D03*
X695669D03*
X691929D03*
X688189D03*
X699409Y1243503D03*
X691929D03*
X699409Y1247243D03*
X691929D03*
X695669Y1250984D03*
X688189D03*
X699409D03*
X695669Y1243503D03*
X691929Y1250984D03*
X688189Y1243503D03*
X695669Y1247243D03*
X688189D03*
X695669Y1254724D03*
X688189D03*
X699409D03*
X691929D03*
X718110Y1075196D03*
X710630D03*
X703149D03*
X714370D03*
X706890D03*
X718110Y1078936D03*
X710630D03*
X703149D03*
X714370Y1082677D03*
X706890D03*
X714370Y1086417D03*
X706890D03*
X718110Y1090157D03*
X714370D03*
X710630D03*
X706890D03*
X703149D03*
X718110Y1086417D03*
X714370Y1078936D03*
X710630Y1086417D03*
X706890Y1078936D03*
X703149Y1086417D03*
X718110Y1082677D03*
X710630D03*
X703149D03*
X718110Y1093897D03*
X710630D03*
X703149D03*
X718110Y1097637D03*
X710630D03*
X703149D03*
X714370Y1101377D03*
X706890D03*
X714370Y1105117D03*
X706890D03*
X718110D03*
X714370Y1097637D03*
X710630Y1105117D03*
X706890Y1097637D03*
X703149Y1105117D03*
X718110Y1101377D03*
X714370Y1093897D03*
X710630Y1101377D03*
X706890Y1093897D03*
X703149Y1101377D03*
X718110Y1108858D03*
X714370D03*
X710630D03*
X706890D03*
X703149D03*
X718110Y1120078D03*
X714370D03*
X710630D03*
X706890D03*
X703149D03*
X718110Y1123818D03*
X714370D03*
X710630D03*
X706890D03*
X703149D03*
X710630Y1116338D03*
X706890D03*
X703149D03*
X706890Y1112598D03*
X714370Y1116338D03*
X703149Y1112598D03*
X718110D03*
X714370D03*
X718110Y1116338D03*
X710630Y1112598D03*
X718110Y1127558D03*
X714370D03*
X710630D03*
X706890D03*
X703149D03*
X718110Y1135039D03*
X714370D03*
X710630D03*
X706890D03*
X703149D03*
X718110Y1131299D03*
X714370D03*
X710630D03*
X706890D03*
X703149D03*
X718110Y1138779D03*
X714370D03*
X710630D03*
X706890D03*
X703149D03*
X718110Y1142519D03*
X714370D03*
X710630D03*
X706890D03*
X703149D03*
X718110Y1149999D03*
X714370D03*
X710630D03*
X706890D03*
X703149D03*
X718110Y1146259D03*
X714370D03*
X710630D03*
X706890D03*
X703149D03*
X718110Y1153740D03*
X714370D03*
X710630D03*
X706890D03*
X703149D03*
X718110Y1157480D03*
X710630D03*
X703149D03*
X714370Y1161220D03*
X706890D03*
X718110Y1164960D03*
X710630D03*
X703149D03*
X714370Y1168700D03*
X706890D03*
X718110Y1172440D03*
X710630D03*
X703149D03*
X718110Y1161220D03*
Y1168700D03*
X714370Y1157480D03*
X706890D03*
X710630Y1161220D03*
X703149D03*
X714370Y1164960D03*
X706890D03*
X710630Y1168700D03*
X703149D03*
X714370Y1172440D03*
X706890D03*
X718110Y1187401D03*
X714370D03*
X710630D03*
X706890D03*
X703149D03*
X718110Y1179921D03*
X714370D03*
X710630D03*
X706890D03*
X703149D03*
X718110Y1183661D03*
X714370D03*
X710630D03*
X706890D03*
X703149D03*
X718110Y1176180D03*
X714370D03*
X710630D03*
X706890D03*
X703149D03*
X718110Y1194881D03*
X714370D03*
X710630D03*
X706890D03*
X703149D03*
X718110Y1202362D03*
X714370D03*
X710630D03*
X706890D03*
X703149D03*
X718110Y1198621D03*
X714370D03*
X710630D03*
X706890D03*
X703149D03*
X718110Y1191141D03*
X714370D03*
X710630D03*
X706890D03*
X703149D03*
X718110Y1206102D03*
X714370D03*
X710630D03*
X706890D03*
X703149D03*
X718110Y1209842D03*
X714370D03*
X710630D03*
X706890D03*
X703149D03*
X718110Y1221062D03*
X714370D03*
X710630D03*
X706890D03*
X703149D03*
Y1213582D03*
X706890D03*
X718110D03*
X714370Y1217322D03*
X706890D03*
X714370Y1213582D03*
X710630D03*
X703149Y1217322D03*
X718110D03*
X710630D03*
X714370Y1224803D03*
X706890D03*
X714370Y1228543D03*
X706890D03*
X718110Y1232283D03*
X710630D03*
X703149D03*
X718110Y1236023D03*
X710630D03*
X703149D03*
X718110Y1224803D03*
X714370Y1232283D03*
X710630Y1224803D03*
X706890Y1232283D03*
X703149Y1224803D03*
X718110Y1228543D03*
X714370Y1236023D03*
X710630Y1228543D03*
X706890Y1236023D03*
X703149Y1228543D03*
X718110Y1239763D03*
X714370D03*
X710630D03*
X706890D03*
X703149D03*
X714370Y1243503D03*
X706890D03*
X714370Y1247243D03*
X706890D03*
X718110Y1250984D03*
X710630D03*
X703149D03*
X718110Y1243503D03*
X714370Y1250984D03*
X710630Y1243503D03*
X706890Y1250984D03*
X703149Y1243503D03*
X718110Y1247243D03*
X710630D03*
X703149D03*
X718110Y1254724D03*
X710630D03*
X703149D03*
X714370D03*
X706890D03*
X733071Y1075196D03*
X725590D03*
X729331D03*
X721850D03*
X733071Y1078936D03*
X725590D03*
X729331Y1082677D03*
X721850D03*
X729331Y1086417D03*
X721850D03*
X733071Y1090157D03*
X729331D03*
X725590D03*
X721850D03*
X733071Y1086417D03*
X729331Y1078936D03*
X725590Y1086417D03*
X721850Y1078936D03*
X733071Y1082677D03*
X725590D03*
X733071Y1093897D03*
X725590D03*
X733071Y1097637D03*
X725590D03*
X729331Y1101377D03*
X721850D03*
X729331Y1105117D03*
X721850D03*
X733071D03*
X729331Y1097637D03*
X725590Y1105117D03*
X721850Y1097637D03*
X733071Y1101377D03*
X729331Y1093897D03*
X725590Y1101377D03*
X721850Y1093897D03*
X733071Y1108858D03*
X729331D03*
X725590D03*
X721850D03*
X733071Y1120078D03*
X729331D03*
X725590D03*
X721850D03*
X729331Y1123818D03*
X725590D03*
X721850D03*
X733071D03*
X729331Y1116338D03*
X733071Y1112598D03*
X721850Y1116338D03*
Y1112598D03*
X733071Y1116338D03*
X729331Y1112598D03*
X725590Y1116338D03*
Y1112598D03*
X729331Y1127558D03*
X725590D03*
X721850D03*
X725590Y1131299D03*
X729331Y1135039D03*
X725590D03*
X721850D03*
X733071Y1138779D03*
X725590D03*
X729331Y1131299D03*
Y1138779D03*
X721850Y1131299D03*
Y1138779D03*
X733071Y1127558D03*
Y1135039D03*
Y1131299D03*
Y1142519D03*
X725590D03*
X721850D03*
X733071Y1146259D03*
X725590D03*
X733071Y1149999D03*
X729331D03*
X725590D03*
X721850D03*
X733071Y1153740D03*
X729331D03*
X725590D03*
X721850Y1146259D03*
Y1153740D03*
X729331Y1142519D03*
Y1146259D03*
Y1157480D03*
X725590D03*
X729331Y1161220D03*
Y1164960D03*
Y1168700D03*
Y1172440D03*
X725590D03*
Y1161220D03*
X721850D03*
X725590Y1164960D03*
X721850D03*
X725590Y1168700D03*
X721850D03*
Y1157480D03*
Y1172440D03*
X733071Y1157480D03*
Y1161220D03*
Y1164960D03*
Y1168700D03*
Y1172440D03*
Y1183661D03*
X725590D03*
X733071Y1187401D03*
X725590D03*
X721850D03*
X733071Y1176180D03*
X725590D03*
X733071Y1179921D03*
X721850D03*
Y1183661D03*
Y1176180D03*
X725590Y1179921D03*
X729331Y1183661D03*
Y1187401D03*
Y1179921D03*
Y1176180D03*
X733071Y1191141D03*
X725590D03*
X729331Y1194881D03*
X725590D03*
X721850D03*
X725590Y1198621D03*
X729331Y1202362D03*
X725590D03*
X721850D03*
X729331Y1198621D03*
Y1191141D03*
X721850Y1198621D03*
Y1191141D03*
X733071Y1198621D03*
Y1202362D03*
Y1194881D03*
X729331Y1206102D03*
X725590D03*
X721850D03*
X733071Y1209842D03*
X729331D03*
X725590D03*
X721850D03*
X733071Y1221062D03*
X729331D03*
X725590D03*
X721850D03*
X733071Y1206102D03*
X725590Y1217322D03*
X733071D03*
Y1213582D03*
X729331D03*
X725590D03*
X721850D03*
Y1217322D03*
X729331D03*
Y1224803D03*
X721850D03*
X729331Y1228543D03*
X721850D03*
X733071Y1232283D03*
X725590D03*
X733071Y1236023D03*
X725590D03*
X733071Y1224803D03*
X729331Y1232283D03*
X725590Y1224803D03*
X721850Y1232283D03*
X733071Y1228543D03*
X729331Y1236023D03*
X725590Y1228543D03*
X721850Y1236023D03*
X733071Y1239763D03*
X729331D03*
X725590D03*
X721850D03*
X729331Y1243503D03*
X721850D03*
X729331Y1247243D03*
X721850D03*
X733071Y1250984D03*
X725590D03*
X733071Y1243503D03*
X729331Y1250984D03*
X725590Y1243503D03*
X721850Y1250984D03*
X733071Y1247243D03*
X725590D03*
X733071Y1254724D03*
X725590D03*
X729331D03*
X721850D03*
X748031Y1075196D03*
X740551D03*
X744291D03*
X736811D03*
X748031Y1078936D03*
X740551D03*
X744291Y1082677D03*
X736811D03*
X744291Y1086417D03*
X736811D03*
X748031Y1090157D03*
X744291D03*
X740551D03*
X736811D03*
X748031Y1086417D03*
X744291Y1078936D03*
X740551Y1086417D03*
X736811Y1078936D03*
X748031Y1082677D03*
X740551D03*
X748031Y1093897D03*
X740551D03*
X748031Y1097637D03*
X740551D03*
X744291Y1101377D03*
X736811D03*
X744291Y1105117D03*
X736811D03*
X748031D03*
X744291Y1097637D03*
X740551Y1105117D03*
X736811Y1097637D03*
X748031Y1101377D03*
X744291Y1093897D03*
X740551Y1101377D03*
X736811Y1093897D03*
X748031Y1108858D03*
X744291D03*
X740551D03*
X736811D03*
X748031Y1112598D03*
Y1116338D03*
Y1120078D03*
X736811D03*
X748031Y1123818D03*
X736811D03*
X740551Y1120078D03*
X736811Y1112598D03*
Y1116338D03*
X740551D03*
Y1123818D03*
X744291Y1116338D03*
Y1123818D03*
Y1120078D03*
Y1112598D03*
X740551D03*
X748031Y1127558D03*
X736811D03*
X748031Y1131299D03*
X736811D03*
X748031Y1135039D03*
X736811D03*
X748031Y1138779D03*
X736811D03*
X744291Y1127558D03*
Y1131299D03*
X740551Y1127558D03*
Y1131299D03*
X744291Y1138779D03*
X740551Y1135039D03*
X744291D03*
X740551Y1138779D03*
X748031Y1142519D03*
X736811D03*
X748031Y1146259D03*
X736811D03*
X748031Y1149999D03*
X736811D03*
X748031Y1153740D03*
X744291D03*
X740551D03*
X736811D03*
X740551Y1142519D03*
X744291Y1149999D03*
X740551D03*
Y1146259D03*
X744291Y1142519D03*
Y1146259D03*
X748031Y1157480D03*
X744291D03*
X736811D03*
X748031Y1161220D03*
X744291D03*
X736811D03*
X748031Y1164960D03*
X744291D03*
X736811D03*
X748031Y1168700D03*
X744291D03*
X736811D03*
X748031Y1172440D03*
X744291D03*
X736811D03*
X740551Y1157480D03*
Y1161220D03*
Y1164960D03*
Y1168700D03*
Y1172440D03*
X748031Y1183661D03*
X740551D03*
X736811D03*
X748031Y1187401D03*
X736811D03*
X748031Y1176180D03*
X744291D03*
X740551D03*
X736811D03*
X748031Y1179921D03*
X740551D03*
X744291Y1187401D03*
X736811Y1179921D03*
X740551Y1187401D03*
X744291Y1179921D03*
Y1183661D03*
X748031Y1191141D03*
X740551D03*
X736811D03*
X748031Y1194881D03*
X736811D03*
X748031Y1198621D03*
X736811D03*
X748031Y1202362D03*
X736811D03*
X744291Y1191141D03*
X740551Y1194881D03*
Y1202362D03*
X744291Y1194881D03*
Y1202362D03*
Y1198621D03*
X740551D03*
X748031Y1206102D03*
X736811D03*
X748031Y1209842D03*
X736811D03*
X748031Y1213582D03*
Y1217322D03*
Y1221062D03*
X744291D03*
X740551D03*
X736811D03*
X744291Y1217322D03*
X740551Y1209842D03*
Y1213582D03*
X736811D03*
X740551Y1217322D03*
X744291Y1213582D03*
Y1209842D03*
X736811Y1217322D03*
X740551Y1206102D03*
X744291D03*
Y1224803D03*
X736811D03*
X744291Y1228543D03*
X736811D03*
X748031Y1232283D03*
X740551D03*
X748031Y1236023D03*
X740551D03*
X744291Y1232283D03*
X740551Y1224803D03*
X736811Y1232283D03*
X744291Y1236023D03*
X740551Y1228543D03*
X736811Y1236023D03*
X748031Y1224803D03*
Y1228543D03*
Y1239763D03*
X744291D03*
X740551D03*
X736811D03*
X744291Y1243503D03*
X736811D03*
X744291Y1247243D03*
X736811D03*
X748031Y1250984D03*
X740551D03*
X744291D03*
X740551Y1243503D03*
X736811Y1250984D03*
X740551Y1247243D03*
X748031Y1243503D03*
Y1247243D03*
Y1254724D03*
X740551D03*
X744291D03*
X736811D03*
X762992Y1075196D03*
X755512D03*
X751772D03*
X759252D03*
X766732D03*
X762992Y1078936D03*
X755512D03*
X766732Y1082677D03*
X759252D03*
X751772D03*
X766732Y1086417D03*
X759252D03*
X751772D03*
X766732Y1090157D03*
X762992D03*
X759252D03*
X755512D03*
X751772D03*
Y1078936D03*
X755512Y1086417D03*
X759252Y1078936D03*
X762992Y1086417D03*
X766732Y1078936D03*
X755512Y1082677D03*
X762992D03*
Y1093897D03*
X755512D03*
X762992Y1097637D03*
X755512D03*
X766732Y1101377D03*
X759252D03*
X751772D03*
X766732Y1105117D03*
X759252D03*
X751772D03*
Y1097637D03*
X755512Y1105117D03*
X759252Y1097637D03*
X762992Y1105117D03*
X766732Y1097637D03*
X751772Y1093897D03*
X755512Y1101377D03*
X759252Y1093897D03*
X762992Y1101377D03*
X766732Y1093897D03*
Y1108858D03*
X762992D03*
X759252D03*
X755512D03*
X751772D03*
X766732Y1112598D03*
X755512D03*
X751772D03*
X766732Y1116338D03*
X762992D03*
X759252D03*
X766732Y1120078D03*
X755512D03*
X751772D03*
X766732Y1123818D03*
X762992D03*
X759252D03*
Y1112598D03*
X751772Y1116338D03*
X759252Y1120078D03*
X751772Y1123818D03*
X762992Y1112598D03*
X755512Y1116338D03*
X762992Y1120078D03*
X755512Y1123818D03*
X766732Y1127558D03*
X755512D03*
X751772D03*
X766732Y1131299D03*
X762992D03*
X759252D03*
X766732Y1135039D03*
X755512D03*
X751772D03*
X766732Y1138779D03*
X762992D03*
X759252D03*
X751772D03*
X755512D03*
X759252Y1127558D03*
X751772Y1131299D03*
X759252Y1135039D03*
X762992Y1127558D03*
X755512Y1131299D03*
X762992Y1135039D03*
X766732Y1142519D03*
X755512D03*
X751772D03*
X766732Y1146259D03*
X762992D03*
X759252D03*
X766732Y1149999D03*
X755512D03*
X751772D03*
X766732Y1153740D03*
X762992D03*
X759252D03*
Y1142519D03*
X751772Y1146259D03*
X759252Y1149999D03*
X751772Y1153740D03*
X762992Y1142519D03*
X755512Y1146259D03*
X762992Y1149999D03*
X755512Y1153740D03*
X766732Y1157480D03*
X755512D03*
X751772D03*
X766732Y1161220D03*
X762992D03*
X759252D03*
X766732Y1164960D03*
X755512D03*
X751772D03*
X766732Y1168700D03*
X762992D03*
X759252D03*
X766732Y1172440D03*
X755512D03*
X751772D03*
X759252Y1157480D03*
X751772Y1161220D03*
X759252Y1164960D03*
X751772Y1168700D03*
X759252Y1172440D03*
X762992Y1157480D03*
X755512Y1161220D03*
X762992Y1164960D03*
X755512Y1168700D03*
X762992Y1172440D03*
X766732Y1183661D03*
X762992D03*
X759252D03*
X766732Y1187401D03*
X755512D03*
X751772D03*
X766732Y1176180D03*
X762992D03*
X759252D03*
X766732Y1179921D03*
X755512D03*
X751772D03*
Y1176180D03*
X759252Y1179921D03*
X751772Y1183661D03*
X759252Y1187401D03*
X755512Y1176180D03*
X762992Y1179921D03*
X755512Y1183661D03*
X762992Y1187401D03*
X766732Y1191141D03*
X762992D03*
X759252D03*
X766732Y1194881D03*
X755512D03*
X751772D03*
X766732Y1198621D03*
X762992D03*
X759252D03*
X766732Y1202362D03*
X755512D03*
X751772D03*
Y1191141D03*
X759252Y1194881D03*
X755512Y1191141D03*
X762992Y1194881D03*
X759252Y1202362D03*
X751772Y1198621D03*
X762992Y1202362D03*
X755512Y1198621D03*
X766732Y1206102D03*
X762992D03*
X759252D03*
X766732Y1209842D03*
X755512D03*
X751772D03*
X766732Y1213582D03*
X762992D03*
X759252D03*
X766732Y1217322D03*
X755512D03*
X751772D03*
X766732Y1221062D03*
X762992D03*
X759252D03*
X755512D03*
X751772D03*
X759252Y1217322D03*
X751772Y1213582D03*
X759252Y1209842D03*
X751772Y1206102D03*
X762992Y1217322D03*
X755512Y1213582D03*
X762992Y1209842D03*
X755512Y1206102D03*
X766732Y1224803D03*
X759252D03*
X751772D03*
X766732Y1228543D03*
X759252D03*
X751772D03*
X762992Y1232283D03*
X755512D03*
X762992Y1236023D03*
X755512D03*
X751772Y1232283D03*
X755512Y1224803D03*
X759252Y1232283D03*
X762992Y1224803D03*
X766732Y1232283D03*
X751772Y1236023D03*
X755512Y1228543D03*
X759252Y1236023D03*
X762992Y1228543D03*
X766732Y1236023D03*
Y1239763D03*
X762992D03*
X759252D03*
X755512D03*
X751772D03*
X766732Y1243503D03*
X759252D03*
X751772D03*
X766732Y1247243D03*
X759252D03*
X751772D03*
X762992Y1250984D03*
X755512D03*
X751772D03*
X755512Y1243503D03*
X759252Y1250984D03*
X762992Y1243503D03*
X766732Y1250984D03*
X755512Y1247243D03*
X762992D03*
Y1254724D03*
X755512D03*
X751772D03*
X759252D03*
X766732D03*
X777953Y1075196D03*
X770472D03*
X774212D03*
X781693Y1078936D03*
X777953D03*
X770472D03*
X774212Y1082677D03*
X781693Y1086417D03*
X777953D03*
X774212D03*
Y1090157D03*
X770472D03*
X777953D03*
X781693D03*
X774212Y1078936D03*
X777953Y1082677D03*
X770472Y1086417D03*
X781693Y1082677D03*
X770472D03*
X781693Y1093897D03*
X777953D03*
X770472D03*
X781693Y1097637D03*
X777953D03*
X770472D03*
X774212Y1101377D03*
X781693Y1105117D03*
X777953D03*
X774212D03*
Y1097637D03*
X777953Y1101377D03*
X770472Y1105117D03*
X774212Y1093897D03*
X781693Y1101377D03*
X770472D03*
X774212Y1108858D03*
X770472D03*
X781693Y1112598D03*
X777953D03*
X774212Y1116338D03*
X770472D03*
X781693Y1120078D03*
X777953D03*
X774212Y1123818D03*
X770472D03*
X777953Y1108858D03*
X770472Y1112598D03*
X777953Y1116338D03*
X770472Y1120078D03*
X777953Y1123818D03*
X781693Y1108858D03*
X774212Y1112598D03*
X781693Y1116338D03*
X774212Y1120078D03*
X781693Y1123818D03*
Y1127558D03*
X777953D03*
X774212Y1131299D03*
X770472D03*
X781693Y1135039D03*
X777953D03*
X774212Y1138779D03*
X770472D03*
X777953D03*
X781693D03*
X770472Y1127558D03*
X777953Y1131299D03*
X770472Y1135039D03*
X774212Y1127558D03*
X781693Y1131299D03*
X774212Y1135039D03*
X781693Y1142519D03*
X777953D03*
X774212Y1146259D03*
X770472D03*
X781693Y1149999D03*
X777953D03*
X774212Y1153740D03*
X770472D03*
Y1142519D03*
X777953Y1146259D03*
X770472Y1149999D03*
X777953Y1153740D03*
X774212Y1142519D03*
X781693Y1146259D03*
X774212Y1149999D03*
X781693Y1153740D03*
Y1157480D03*
X777953D03*
X774212Y1161220D03*
X770472D03*
X781693Y1164960D03*
X777953D03*
X774212Y1168700D03*
X770472D03*
X781693Y1172440D03*
X777953D03*
X770472Y1157480D03*
X777953Y1161220D03*
X770472Y1164960D03*
X777953Y1168700D03*
X770472Y1172440D03*
X774212Y1157480D03*
X781693Y1161220D03*
X774212Y1164960D03*
X781693Y1168700D03*
X774212Y1172440D03*
Y1183661D03*
X770472D03*
X781693Y1187401D03*
X777953D03*
X774212Y1176180D03*
X770472D03*
X781693Y1179921D03*
X777953D03*
Y1176180D03*
X770472Y1179921D03*
X777953Y1183661D03*
X770472Y1187401D03*
X781693Y1176180D03*
X774212Y1179921D03*
X781693Y1183661D03*
X774212Y1187401D03*
Y1191141D03*
X770472D03*
X781693Y1194881D03*
X777953D03*
X774212Y1198621D03*
X770472D03*
X781693Y1202362D03*
X777953D03*
Y1191141D03*
X770472Y1194881D03*
X781693Y1191141D03*
X774212Y1194881D03*
X770472Y1202362D03*
X777953Y1198621D03*
X774212Y1202362D03*
X781693Y1198621D03*
X774212Y1206102D03*
X770472D03*
X781693Y1209842D03*
X777953D03*
X774212Y1213582D03*
X770472D03*
X781693Y1217322D03*
X777953D03*
X774212Y1221062D03*
X770472D03*
X777953D03*
X770472Y1217322D03*
X777953Y1213582D03*
X770472Y1209842D03*
X777953Y1206102D03*
X781693Y1221062D03*
X774212Y1217322D03*
X781693Y1213582D03*
X774212Y1209842D03*
X781693Y1206102D03*
Y1224803D03*
X777953D03*
X774212D03*
Y1228543D03*
X781693Y1232283D03*
X777953D03*
X770472D03*
X781693Y1236023D03*
X777953D03*
X770472D03*
Y1224803D03*
X774212Y1232283D03*
X777953Y1228543D03*
X770472D03*
X774212Y1236023D03*
X781693Y1228543D03*
X774212Y1239763D03*
X770472D03*
X781693Y1243503D03*
X777953D03*
X774212D03*
Y1247243D03*
X781693Y1250984D03*
X777953D03*
X770472D03*
X777953Y1239763D03*
X781693D03*
X770472Y1243503D03*
X774212Y1250984D03*
X777953Y1247243D03*
X770472D03*
X781693D03*
X777953Y1254724D03*
X770472D03*
X774212D03*
X1059251Y1078936D03*
Y1086417D03*
Y1090157D03*
Y1082677D03*
Y1093897D03*
Y1097637D03*
Y1105117D03*
Y1101377D03*
Y1112598D03*
Y1120078D03*
Y1108858D03*
Y1116338D03*
Y1123818D03*
Y1127558D03*
Y1135039D03*
Y1131299D03*
Y1138779D03*
Y1142519D03*
Y1146259D03*
Y1153740D03*
Y1149999D03*
Y1161220D03*
Y1168700D03*
Y1157480D03*
Y1164960D03*
Y1172440D03*
Y1183661D03*
Y1187401D03*
Y1176180D03*
Y1179921D03*
Y1194881D03*
Y1202362D03*
Y1198621D03*
Y1191141D03*
Y1209842D03*
Y1217322D03*
Y1221062D03*
Y1213582D03*
Y1206102D03*
Y1224803D03*
Y1232283D03*
Y1236023D03*
Y1228543D03*
Y1243503D03*
Y1250984D03*
Y1239763D03*
Y1247243D03*
X1070472Y1075196D03*
X1062991D03*
X1074212D03*
X1066732D03*
X1070472Y1078936D03*
X1062991D03*
X1074212Y1082677D03*
X1066732D03*
X1074212Y1086417D03*
X1066732D03*
X1062991D03*
X1074212Y1090157D03*
X1070472D03*
X1066732D03*
X1062991D03*
X1074212Y1078936D03*
X1070472Y1086417D03*
X1066732Y1078936D03*
X1062991Y1082677D03*
X1070472D03*
Y1093897D03*
X1062991D03*
X1070472Y1097637D03*
X1062991D03*
X1074212Y1101377D03*
X1066732D03*
X1074212Y1105117D03*
X1066732D03*
X1062991D03*
X1074212Y1097637D03*
X1070472Y1105117D03*
X1066732Y1097637D03*
X1062991Y1101377D03*
X1074212Y1093897D03*
X1070472Y1101377D03*
X1066732Y1093897D03*
X1074212Y1108858D03*
X1070472D03*
X1066732D03*
X1074212Y1112598D03*
X1062991D03*
X1074212Y1116338D03*
X1070472D03*
X1066732D03*
X1074212Y1120078D03*
X1062991D03*
X1074212Y1123818D03*
X1070472D03*
X1066732D03*
X1062991Y1108858D03*
X1070472Y1112598D03*
X1062991Y1116338D03*
X1070472Y1120078D03*
X1062991Y1123818D03*
X1066732Y1112598D03*
Y1120078D03*
X1074212Y1127558D03*
X1062991D03*
X1074212Y1131299D03*
X1070472D03*
X1066732D03*
X1074212Y1135039D03*
X1062991D03*
X1074212Y1138779D03*
X1070472D03*
X1066732D03*
X1070472Y1127558D03*
X1062991Y1131299D03*
X1070472Y1135039D03*
X1062991Y1138779D03*
X1066732Y1127558D03*
Y1135039D03*
X1074212Y1142519D03*
X1070472D03*
X1066732D03*
X1062991D03*
X1066732Y1146259D03*
X1062991D03*
X1074212Y1149999D03*
X1070472D03*
X1066732D03*
Y1153740D03*
X1062991D03*
X1070472Y1146259D03*
X1074212D03*
X1062991Y1149999D03*
X1074212Y1153740D03*
X1070472D03*
X1074212Y1157480D03*
X1070472D03*
X1066732D03*
Y1161220D03*
X1062991D03*
X1074212Y1164960D03*
X1070472D03*
X1066732D03*
Y1168700D03*
X1062991D03*
X1074212Y1172440D03*
X1070472D03*
X1066732D03*
X1062991Y1157480D03*
X1074212Y1161220D03*
X1070472D03*
X1062991Y1164960D03*
X1074212Y1168700D03*
X1070472D03*
X1062991Y1172440D03*
X1074212Y1183661D03*
X1070472D03*
X1066732D03*
X1062991D03*
X1074212Y1187401D03*
X1062991D03*
X1066732Y1176180D03*
X1062991D03*
X1074212Y1179921D03*
X1070472D03*
X1066732D03*
X1062991D03*
X1074212Y1176180D03*
X1070472D03*
Y1187401D03*
X1066732D03*
X1074212Y1191141D03*
X1070472D03*
X1066732D03*
X1074212Y1194881D03*
X1062991D03*
X1074212Y1198621D03*
X1070472D03*
X1066732D03*
X1074212Y1202362D03*
X1062991D03*
X1070472D03*
X1062991Y1198621D03*
X1070472Y1194881D03*
X1062991Y1191141D03*
X1066732Y1202362D03*
Y1194881D03*
X1074212Y1206102D03*
X1070472D03*
X1066732D03*
X1074212Y1209842D03*
X1062991D03*
X1074212Y1213582D03*
X1070472D03*
X1066732D03*
X1074212Y1217322D03*
X1062991D03*
X1074212Y1221062D03*
X1070472D03*
X1066732D03*
X1062991D03*
X1070472Y1217322D03*
X1062991Y1213582D03*
X1070472Y1209842D03*
X1062991Y1206102D03*
X1066732Y1217322D03*
Y1209842D03*
X1074212Y1224803D03*
X1066732D03*
X1062991D03*
X1074212Y1228543D03*
X1066732D03*
X1070472Y1232283D03*
X1062991D03*
X1070472Y1236023D03*
X1062991D03*
X1074212Y1232283D03*
X1070472Y1224803D03*
X1066732Y1232283D03*
X1062991Y1228543D03*
X1074212Y1236023D03*
X1070472Y1228543D03*
X1066732Y1236023D03*
X1074212Y1239763D03*
X1070472D03*
X1066732D03*
X1074212Y1243503D03*
X1066732D03*
X1062991D03*
X1074212Y1247243D03*
X1066732D03*
X1070472Y1250984D03*
X1062991D03*
Y1239763D03*
X1074212Y1250984D03*
X1070472Y1243503D03*
X1066732Y1250984D03*
X1062991Y1247243D03*
X1070472D03*
Y1254724D03*
X1062991D03*
X1074212D03*
X1066732D03*
X1085432Y1075196D03*
X1077952D03*
X1081692D03*
X1089172D03*
X1085432Y1078936D03*
X1077952D03*
X1089172Y1082677D03*
X1081692D03*
X1089172Y1086417D03*
X1081692D03*
X1089172Y1090157D03*
X1085432D03*
X1081692D03*
X1077952D03*
X1085432Y1086417D03*
X1081692Y1078936D03*
X1077952Y1086417D03*
X1085432Y1082677D03*
X1077952D03*
X1089172Y1078936D03*
X1085432Y1093897D03*
X1077952D03*
X1085432Y1097637D03*
X1077952D03*
X1089172Y1101377D03*
X1081692D03*
X1089172Y1105117D03*
X1081692D03*
X1085432D03*
X1081692Y1097637D03*
X1077952Y1105117D03*
X1085432Y1101377D03*
X1081692Y1093897D03*
X1077952Y1101377D03*
X1089172Y1097637D03*
Y1093897D03*
Y1108858D03*
X1085432D03*
X1081692D03*
X1077952D03*
X1089172Y1112598D03*
X1085432D03*
X1081692Y1116338D03*
X1077952D03*
X1089172Y1120078D03*
X1085432D03*
X1081692Y1123818D03*
X1077952D03*
X1081692Y1112598D03*
X1089172Y1116338D03*
X1081692Y1120078D03*
X1089172Y1123818D03*
X1077952Y1112598D03*
X1085432Y1116338D03*
X1077952Y1120078D03*
X1085432Y1123818D03*
X1089172Y1127558D03*
X1085432D03*
X1081692Y1131299D03*
X1077952D03*
X1089172Y1135039D03*
X1085432D03*
X1081692Y1138779D03*
X1077952D03*
X1081692Y1127558D03*
X1089172Y1131299D03*
X1081692Y1135039D03*
X1089172Y1138779D03*
X1077952Y1127558D03*
X1085432Y1131299D03*
X1077952Y1135039D03*
X1085432Y1138779D03*
X1089172Y1142519D03*
X1085432D03*
X1081692D03*
X1077952D03*
X1089172Y1146259D03*
X1085432D03*
X1077952D03*
X1089172Y1149999D03*
X1077952D03*
X1089172Y1153740D03*
X1077952D03*
X1085432D03*
X1081692Y1149999D03*
X1085432D03*
X1081692Y1146259D03*
Y1153740D03*
X1089172Y1157480D03*
X1077952D03*
X1089172Y1161220D03*
X1077952D03*
X1089172Y1164960D03*
X1077952D03*
X1089172Y1168700D03*
X1077952D03*
X1089172Y1172440D03*
X1077952D03*
X1085432Y1164960D03*
Y1172440D03*
Y1168700D03*
X1081692Y1172440D03*
Y1168700D03*
Y1164960D03*
X1085432Y1157480D03*
Y1161220D03*
X1081692D03*
Y1157480D03*
X1089172Y1183661D03*
X1085432D03*
X1081692D03*
X1077952D03*
X1089172Y1187401D03*
X1085432D03*
X1089172Y1176180D03*
X1077952D03*
X1089172Y1179921D03*
X1085432D03*
X1081692D03*
X1077952D03*
X1081692Y1176180D03*
X1085432D03*
X1081692Y1187401D03*
X1077952D03*
X1081692Y1191141D03*
X1077952D03*
X1089172Y1194881D03*
X1085432D03*
X1081692Y1198621D03*
X1077952D03*
X1089172Y1202362D03*
X1085432D03*
X1081692D03*
X1089172Y1198621D03*
X1081692Y1194881D03*
X1089172Y1191141D03*
X1077952Y1202362D03*
X1085432Y1198621D03*
X1077952Y1194881D03*
X1085432Y1191141D03*
X1081692Y1206102D03*
X1077952D03*
X1089172Y1209842D03*
X1085432D03*
X1081692Y1213582D03*
X1077952D03*
X1089172Y1217322D03*
X1085432D03*
X1089172Y1221062D03*
X1085432D03*
X1081692D03*
X1077952D03*
X1081692Y1217322D03*
X1089172Y1213582D03*
X1081692Y1209842D03*
X1089172Y1206102D03*
X1077952Y1217322D03*
X1085432Y1213582D03*
X1077952Y1209842D03*
X1085432Y1206102D03*
X1089172Y1224803D03*
X1081692D03*
X1089172Y1228543D03*
X1081692D03*
X1085432Y1232283D03*
X1077952D03*
X1085432Y1236023D03*
X1077952D03*
X1081692Y1232283D03*
X1077952Y1224803D03*
X1081692Y1236023D03*
X1077952Y1228543D03*
X1085432Y1224803D03*
X1089172Y1232283D03*
X1085432Y1228543D03*
X1089172Y1236023D03*
Y1239763D03*
X1085432D03*
X1081692D03*
X1077952D03*
X1089172Y1243503D03*
X1081692D03*
X1089172Y1247243D03*
X1081692D03*
X1085432Y1250984D03*
X1077952D03*
X1081692D03*
X1077952Y1243503D03*
Y1247243D03*
X1085432Y1243503D03*
X1089172Y1250984D03*
X1085432Y1247243D03*
Y1254724D03*
X1077952D03*
X1081692D03*
X1089172D03*
X1107873Y1075196D03*
X1100393D03*
X1092913D03*
X1096653D03*
X1104133D03*
X1107873Y1078936D03*
X1100393D03*
X1092913D03*
X1104133Y1082677D03*
X1096653D03*
X1104133Y1086417D03*
X1096653D03*
X1107873Y1090157D03*
X1104133D03*
X1100393D03*
X1096653D03*
X1092913D03*
Y1086417D03*
X1096653Y1078936D03*
X1100393Y1086417D03*
X1104133Y1078936D03*
X1107873Y1086417D03*
X1092913Y1082677D03*
X1100393D03*
X1107873D03*
Y1093897D03*
X1100393D03*
X1092913D03*
X1107873Y1097637D03*
X1100393D03*
X1092913D03*
X1104133Y1101377D03*
X1096653D03*
X1104133Y1105117D03*
X1096653D03*
X1092913D03*
X1096653Y1097637D03*
X1100393Y1105117D03*
X1104133Y1097637D03*
X1107873Y1105117D03*
X1092913Y1101377D03*
X1096653Y1093897D03*
X1100393Y1101377D03*
X1104133Y1093897D03*
X1107873Y1101377D03*
Y1108858D03*
X1104133D03*
X1100393D03*
X1096653D03*
X1092913D03*
X1096653Y1112598D03*
X1092913D03*
X1096653Y1116338D03*
X1092913D03*
X1107873Y1120078D03*
X1104133D03*
X1100393D03*
X1096653D03*
X1092913D03*
X1107873Y1123818D03*
X1104133D03*
X1100393D03*
X1096653D03*
X1092913D03*
X1104133Y1116338D03*
X1100393D03*
Y1112598D03*
X1104133D03*
X1107873Y1116338D03*
Y1112598D03*
Y1127558D03*
X1104133D03*
X1100393D03*
X1096653D03*
X1092913D03*
X1104133Y1131299D03*
X1100393D03*
X1096653D03*
X1092913D03*
X1104133Y1135039D03*
X1100393D03*
X1096653D03*
X1092913D03*
X1104133Y1138779D03*
X1096653D03*
X1092913D03*
X1100393D03*
X1107873D03*
Y1131299D03*
Y1135039D03*
X1100393Y1149999D03*
X1104133Y1153740D03*
Y1142519D03*
X1100393D03*
X1096653D03*
X1092913D03*
X1104133Y1146259D03*
X1096653D03*
X1107873Y1149999D03*
X1096653D03*
Y1153740D03*
X1107873Y1142519D03*
X1100393Y1146259D03*
X1092913D03*
Y1149999D03*
Y1153740D03*
X1104133Y1149999D03*
X1100393Y1153740D03*
X1107873Y1146259D03*
Y1153740D03*
X1100393Y1157480D03*
X1104133Y1161220D03*
X1100393Y1164960D03*
X1104133Y1168700D03*
X1100393Y1172440D03*
X1107873Y1157480D03*
X1096653D03*
X1092913D03*
X1096653Y1161220D03*
X1107873Y1164960D03*
X1096653D03*
Y1168700D03*
X1092913D03*
X1107873Y1172440D03*
X1096653D03*
X1092913D03*
Y1161220D03*
Y1164960D03*
X1104133Y1172440D03*
Y1157480D03*
X1100393Y1161220D03*
X1104133Y1164960D03*
X1100393Y1168700D03*
X1107873Y1161220D03*
Y1168700D03*
X1104133Y1176180D03*
X1100393Y1179921D03*
X1104133Y1183661D03*
X1096653D03*
X1092913D03*
X1107873Y1187401D03*
X1104133D03*
X1100393D03*
X1096653D03*
X1092913D03*
X1096653Y1176180D03*
X1107873Y1179921D03*
X1096653D03*
X1092913Y1176180D03*
Y1179921D03*
X1100393Y1183661D03*
Y1176180D03*
X1104133Y1179921D03*
X1107873Y1183661D03*
Y1176180D03*
X1104133Y1191141D03*
X1100393D03*
X1096653D03*
X1092913D03*
X1104133Y1194881D03*
X1100393D03*
X1096653D03*
X1092913D03*
X1104133Y1198621D03*
X1100393D03*
X1096653D03*
X1092913D03*
X1107873Y1202362D03*
X1104133D03*
X1100393D03*
X1096653D03*
X1092913D03*
X1107873Y1191141D03*
Y1198621D03*
Y1194881D03*
Y1206102D03*
X1104133D03*
X1100393D03*
X1096653D03*
X1092913D03*
X1107873Y1209842D03*
X1104133D03*
X1100393D03*
X1096653D03*
X1092913D03*
X1107873Y1213582D03*
X1100393D03*
X1096653D03*
X1092913D03*
X1107873Y1217322D03*
X1096653D03*
X1092913D03*
X1107873Y1221062D03*
X1104133D03*
X1100393D03*
X1096653D03*
X1092913D03*
X1104133Y1217322D03*
X1100393D03*
X1104133Y1213582D03*
Y1224803D03*
X1096653D03*
X1104133Y1228543D03*
X1096653D03*
X1107873Y1232283D03*
X1100393D03*
X1092913D03*
X1107873Y1236023D03*
X1100393D03*
X1092913D03*
Y1224803D03*
X1096653Y1232283D03*
X1100393Y1224803D03*
X1104133Y1232283D03*
X1107873Y1224803D03*
X1092913Y1228543D03*
X1096653Y1236023D03*
X1100393Y1228543D03*
X1104133Y1236023D03*
X1107873Y1228543D03*
Y1239763D03*
X1104133D03*
X1100393D03*
X1096653D03*
X1092913D03*
X1104133Y1243503D03*
X1096653D03*
X1104133Y1247243D03*
X1096653D03*
X1107873Y1250984D03*
X1100393D03*
X1092913D03*
Y1243503D03*
X1096653Y1250984D03*
X1100393Y1243503D03*
X1104133Y1250984D03*
X1107873Y1243503D03*
X1092913Y1247243D03*
X1100393D03*
X1107873D03*
Y1254724D03*
X1100393D03*
X1092913D03*
X1096653D03*
X1104133D03*
X1122834Y1075196D03*
X1115354D03*
X1111613D03*
X1119094D03*
X1122834Y1078936D03*
X1115354D03*
X1119094Y1082677D03*
X1111613D03*
X1119094Y1086417D03*
X1111613D03*
X1122834Y1090157D03*
X1119094D03*
X1115354D03*
X1111613D03*
Y1078936D03*
X1115354Y1086417D03*
X1119094Y1078936D03*
X1122834Y1086417D03*
X1115354Y1082677D03*
X1122834D03*
Y1093897D03*
X1115354D03*
X1122834Y1097637D03*
X1115354D03*
X1119094Y1101377D03*
X1111613D03*
X1119094Y1105117D03*
X1111613D03*
Y1097637D03*
X1115354Y1105117D03*
X1119094Y1097637D03*
X1122834Y1105117D03*
X1111613Y1093897D03*
X1115354Y1101377D03*
X1119094Y1093897D03*
X1122834Y1101377D03*
Y1108858D03*
X1119094D03*
X1115354D03*
X1111613D03*
X1122834Y1120078D03*
X1119094D03*
X1115354D03*
X1111613D03*
X1122834Y1123818D03*
X1119094D03*
X1115354D03*
X1111613D03*
X1115354Y1112598D03*
X1119094Y1116338D03*
X1115354D03*
X1119094Y1112598D03*
X1122834Y1116338D03*
Y1112598D03*
X1111613Y1116338D03*
Y1112598D03*
X1122834Y1127558D03*
X1119094D03*
X1115354D03*
X1111613D03*
Y1131299D03*
X1122834Y1135039D03*
X1119094D03*
X1115354D03*
X1111613D03*
Y1138779D03*
X1122834Y1131299D03*
X1119094D03*
X1115354D03*
X1122834Y1138779D03*
X1119094D03*
X1115354D03*
X1122834Y1142519D03*
X1119094D03*
X1115354D03*
X1111613Y1146259D03*
X1122834Y1149999D03*
X1119094D03*
X1115354D03*
X1111613Y1153740D03*
X1122834Y1146259D03*
X1119094D03*
X1115354D03*
X1122834Y1153740D03*
X1119094D03*
X1115354D03*
X1111613Y1142519D03*
Y1149999D03*
X1122834Y1157480D03*
X1115354D03*
X1119094Y1161220D03*
X1111613D03*
X1122834Y1164960D03*
X1115354D03*
X1119094Y1168700D03*
X1111613D03*
X1122834Y1172440D03*
X1115354D03*
X1119094Y1157480D03*
X1111613D03*
X1122834Y1161220D03*
X1115354D03*
X1119094Y1164960D03*
X1111613D03*
X1122834Y1168700D03*
X1115354D03*
X1119094Y1172440D03*
X1111613D03*
Y1183661D03*
X1122834Y1187401D03*
X1119094D03*
X1115354D03*
X1111613D03*
Y1176180D03*
X1122834Y1179921D03*
X1119094D03*
X1115354D03*
X1122834Y1183661D03*
X1119094D03*
X1115354D03*
X1122834Y1176180D03*
X1119094D03*
X1115354D03*
X1111613Y1179921D03*
Y1191141D03*
X1122834Y1194881D03*
X1119094D03*
X1115354D03*
X1111613D03*
Y1198621D03*
X1122834Y1202362D03*
X1119094D03*
X1115354D03*
X1111613D03*
X1122834Y1198621D03*
X1119094D03*
X1115354D03*
X1122834Y1191141D03*
X1119094D03*
X1115354D03*
X1122834Y1206102D03*
X1119094D03*
X1115354D03*
X1111613D03*
X1122834Y1209842D03*
X1119094D03*
X1115354D03*
X1111613D03*
X1122834Y1221062D03*
X1119094D03*
X1115354D03*
X1111613D03*
X1119094Y1213582D03*
X1115354D03*
X1122834Y1217322D03*
Y1213582D03*
X1119094Y1217322D03*
X1111613Y1213582D03*
X1115354Y1217322D03*
X1111613D03*
X1119094Y1224803D03*
X1111613D03*
X1119094Y1228543D03*
X1111613D03*
X1122834Y1232283D03*
X1115354D03*
X1122834Y1236023D03*
X1115354D03*
X1111613Y1232283D03*
X1115354Y1224803D03*
X1119094Y1232283D03*
X1122834Y1224803D03*
X1111613Y1236023D03*
X1115354Y1228543D03*
X1119094Y1236023D03*
X1122834Y1228543D03*
Y1239763D03*
X1119094D03*
X1115354D03*
X1111613D03*
X1119094Y1243503D03*
X1111613D03*
X1119094Y1247243D03*
X1111613D03*
X1122834Y1250984D03*
X1115354D03*
X1111613D03*
X1115354Y1243503D03*
X1119094Y1250984D03*
X1122834Y1243503D03*
X1115354Y1247243D03*
X1122834D03*
Y1254724D03*
X1115354D03*
X1111613D03*
X1119094D03*
X1137795Y1075196D03*
X1130314D03*
X1126574D03*
X1134054D03*
X1137795Y1078936D03*
X1130314D03*
X1134054Y1082677D03*
X1126574D03*
X1134054Y1086417D03*
X1126574D03*
X1137795Y1090157D03*
X1134054D03*
X1130314D03*
X1126574D03*
Y1078936D03*
X1130314Y1086417D03*
X1134054Y1078936D03*
X1137795Y1086417D03*
X1130314Y1082677D03*
X1137795D03*
Y1093897D03*
X1130314D03*
X1137795Y1097637D03*
X1130314D03*
X1134054Y1101377D03*
X1126574D03*
X1134054Y1105117D03*
X1126574D03*
Y1097637D03*
X1130314Y1105117D03*
X1134054Y1097637D03*
X1137795Y1105117D03*
X1126574Y1093897D03*
X1130314Y1101377D03*
X1134054Y1093897D03*
X1137795Y1101377D03*
Y1108858D03*
X1134054D03*
X1130314D03*
X1126574D03*
X1130314Y1112598D03*
Y1116338D03*
X1137795Y1120078D03*
X1134054D03*
X1130314D03*
X1126574D03*
X1137795Y1123818D03*
X1134054D03*
X1130314D03*
X1126574D03*
X1137795Y1112598D03*
Y1116338D03*
X1134054D03*
Y1112598D03*
X1126574Y1116338D03*
Y1112598D03*
X1137795Y1127558D03*
X1134054D03*
X1130314D03*
X1126574D03*
X1137795Y1135039D03*
X1134054D03*
X1130314D03*
X1126574D03*
X1137795Y1131299D03*
X1134054D03*
X1130314D03*
X1126574D03*
X1137795Y1138779D03*
X1134054D03*
X1130314D03*
X1126574D03*
X1137795Y1142519D03*
X1134054D03*
X1130314D03*
X1126574D03*
X1137795Y1149999D03*
X1134054D03*
X1130314D03*
X1126574D03*
X1137795Y1146259D03*
X1134054D03*
X1130314D03*
X1126574D03*
X1137795Y1153740D03*
X1134054D03*
X1130314D03*
X1126574D03*
X1137795Y1157480D03*
X1130314D03*
X1134054Y1161220D03*
X1126574D03*
X1137795Y1164960D03*
X1130314D03*
X1134054Y1168700D03*
X1126574D03*
X1137795Y1172440D03*
X1130314D03*
X1134054Y1157480D03*
X1126574D03*
X1137795Y1161220D03*
X1130314D03*
X1134054Y1164960D03*
X1126574D03*
X1137795Y1168700D03*
X1130314D03*
X1134054Y1172440D03*
X1126574D03*
X1137795Y1187401D03*
X1134054D03*
X1130314D03*
X1126574D03*
X1137795Y1179921D03*
X1134054D03*
X1130314D03*
X1126574D03*
X1137795Y1183661D03*
X1134054D03*
X1130314D03*
X1126574D03*
X1137795Y1176180D03*
X1134054D03*
X1130314D03*
X1126574D03*
X1137795Y1194881D03*
X1134054D03*
X1130314D03*
X1126574D03*
X1137795Y1202362D03*
X1134054D03*
X1130314D03*
X1126574D03*
X1137795Y1198621D03*
X1134054D03*
X1130314D03*
X1126574D03*
X1137795Y1191141D03*
X1134054D03*
X1130314D03*
X1126574D03*
X1137795Y1206102D03*
X1134054D03*
X1130314D03*
X1126574D03*
X1137795Y1209842D03*
X1134054D03*
X1130314D03*
X1126574D03*
X1134054Y1213582D03*
Y1217322D03*
X1137795Y1221062D03*
X1134054D03*
X1130314D03*
X1126574D03*
X1137795Y1213582D03*
Y1217322D03*
X1126574Y1213582D03*
X1130314Y1217322D03*
Y1213582D03*
X1126574Y1217322D03*
X1134054Y1224803D03*
X1126574D03*
X1134054Y1228543D03*
X1126574D03*
X1137795Y1232283D03*
X1130314D03*
X1137795Y1236023D03*
X1130314D03*
Y1224803D03*
X1134054Y1232283D03*
X1137795Y1224803D03*
X1126574Y1232283D03*
X1130314Y1228543D03*
X1134054Y1236023D03*
X1137795Y1228543D03*
X1126574Y1236023D03*
X1137795Y1239763D03*
X1134054D03*
X1130314D03*
X1126574D03*
X1134054Y1243503D03*
X1126574D03*
X1134054Y1247243D03*
X1126574D03*
X1137795Y1250984D03*
X1130314D03*
Y1243503D03*
X1134054Y1250984D03*
X1137795Y1243503D03*
X1126574Y1250984D03*
X1130314Y1247243D03*
X1137795D03*
Y1254724D03*
X1130314D03*
X1134054D03*
X1126574D03*
X1152755Y1075196D03*
X1145275D03*
X1141535D03*
X1156495D03*
X1149015D03*
X1152755Y1078936D03*
X1145275D03*
X1156495Y1082677D03*
X1149015D03*
X1141535D03*
X1156495Y1086417D03*
X1149015D03*
X1141535D03*
X1156495Y1090157D03*
X1152755D03*
X1149015D03*
X1145275D03*
X1141535D03*
Y1078936D03*
X1145275Y1086417D03*
Y1082677D03*
X1156495Y1078936D03*
X1152755Y1086417D03*
X1149015Y1078936D03*
X1152755Y1082677D03*
Y1093897D03*
X1145275D03*
X1152755Y1097637D03*
X1145275D03*
X1156495Y1101377D03*
X1149015D03*
X1141535D03*
X1156495Y1105117D03*
X1149015D03*
X1141535D03*
Y1097637D03*
X1145275Y1105117D03*
X1141535Y1093897D03*
X1145275Y1101377D03*
X1156495Y1097637D03*
X1152755Y1105117D03*
X1149015Y1097637D03*
X1156495Y1093897D03*
X1152755Y1101377D03*
X1149015Y1093897D03*
X1156495Y1108858D03*
X1152755D03*
X1149015D03*
X1145275D03*
X1141535D03*
X1145275Y1112598D03*
Y1116338D03*
X1156495Y1120078D03*
X1152755D03*
X1149015D03*
X1145275D03*
X1141535D03*
X1156495Y1123818D03*
X1152755D03*
X1149015D03*
X1145275D03*
X1141535D03*
Y1116338D03*
Y1112598D03*
X1152755Y1116338D03*
X1149015Y1112598D03*
X1156495Y1116338D03*
X1149015D03*
X1156495Y1112598D03*
X1152755D03*
X1156495Y1127558D03*
X1152755D03*
X1149015D03*
X1145275D03*
X1141535D03*
X1156495Y1135039D03*
X1152755D03*
X1149015D03*
X1145275D03*
X1141535D03*
X1156495Y1131299D03*
X1152755D03*
X1149015D03*
X1145275D03*
X1141535D03*
X1156495Y1138779D03*
X1152755D03*
X1149015D03*
X1145275D03*
X1141535D03*
X1156495Y1142519D03*
X1152755D03*
X1149015D03*
X1145275D03*
X1141535D03*
X1156495Y1149999D03*
X1152755D03*
X1149015D03*
X1145275D03*
X1141535D03*
X1156495Y1146259D03*
X1152755D03*
X1149015D03*
X1145275D03*
X1141535D03*
X1156495Y1153740D03*
X1152755D03*
X1149015D03*
X1145275D03*
X1141535D03*
X1152755Y1157480D03*
X1145275D03*
X1156495Y1161220D03*
X1149015D03*
X1141535D03*
X1152755Y1164960D03*
X1145275D03*
X1156495Y1168700D03*
X1149015D03*
X1141535D03*
X1152755Y1172440D03*
X1145275D03*
X1156495Y1157480D03*
X1149015D03*
X1141535D03*
X1152755Y1161220D03*
X1145275D03*
X1156495Y1164960D03*
X1149015D03*
X1141535D03*
X1152755Y1168700D03*
X1145275D03*
X1156495Y1172440D03*
X1149015D03*
X1141535D03*
X1156495Y1187401D03*
X1152755D03*
X1149015D03*
X1145275D03*
X1141535D03*
X1156495Y1179921D03*
X1152755D03*
X1149015D03*
X1145275D03*
X1141535D03*
X1156495Y1183661D03*
X1152755D03*
X1149015D03*
X1145275D03*
X1141535D03*
X1156495Y1176180D03*
X1152755D03*
X1149015D03*
X1145275D03*
X1141535D03*
X1156495Y1194881D03*
X1152755D03*
X1149015D03*
X1145275D03*
X1141535D03*
X1156495Y1202362D03*
X1152755D03*
X1149015D03*
X1145275D03*
X1141535D03*
X1156495Y1198621D03*
X1152755D03*
X1149015D03*
X1145275D03*
X1141535D03*
X1156495Y1191141D03*
X1152755D03*
X1149015D03*
X1145275D03*
X1141535D03*
X1156495Y1206102D03*
X1152755D03*
X1149015D03*
X1145275D03*
X1141535D03*
X1156495Y1209842D03*
X1152755D03*
X1149015D03*
X1145275D03*
X1141535D03*
X1156495Y1221062D03*
X1152755D03*
X1149015D03*
X1145275D03*
X1141535D03*
X1152755Y1217322D03*
X1145275Y1213582D03*
X1141535Y1217322D03*
Y1213582D03*
X1145275Y1217322D03*
X1156495Y1213582D03*
X1149015Y1217322D03*
Y1213582D03*
X1156495Y1217322D03*
X1152755Y1213582D03*
X1156495Y1224803D03*
X1149015D03*
X1141535D03*
X1156495Y1228543D03*
X1149015D03*
X1141535D03*
X1152755Y1232283D03*
X1145275D03*
X1152755Y1236023D03*
X1145275D03*
X1141535Y1232283D03*
Y1236023D03*
X1156495Y1232283D03*
X1152755Y1224803D03*
X1149015Y1232283D03*
X1145275Y1224803D03*
X1156495Y1236023D03*
X1152755Y1228543D03*
X1149015Y1236023D03*
X1145275Y1228543D03*
X1156495Y1239763D03*
X1152755D03*
X1149015D03*
X1145275D03*
X1141535D03*
X1156495Y1243503D03*
X1149015D03*
X1141535D03*
X1156495Y1247243D03*
X1149015D03*
X1141535D03*
X1152755Y1250984D03*
X1145275D03*
X1141535D03*
X1156495D03*
X1152755Y1243503D03*
X1149015Y1250984D03*
X1145275Y1243503D03*
X1152755Y1247243D03*
X1145275D03*
X1152755Y1254724D03*
X1145275D03*
X1141535D03*
X1156495D03*
X1149015D03*
X1167716Y1075196D03*
X1160235D03*
X1171456D03*
X1163976D03*
X1167716Y1078936D03*
X1160235D03*
X1171456Y1082677D03*
X1163976D03*
X1171456Y1086417D03*
X1163976D03*
X1171456Y1090157D03*
X1167716D03*
X1163976D03*
X1160235D03*
X1171456Y1078936D03*
X1167716Y1086417D03*
X1163976Y1078936D03*
X1160235Y1086417D03*
X1167716Y1082677D03*
X1160235D03*
X1167716Y1093897D03*
X1160235D03*
X1167716Y1097637D03*
X1160235D03*
X1171456Y1101377D03*
X1163976D03*
X1171456Y1105117D03*
X1163976D03*
X1171456Y1097637D03*
X1167716Y1105117D03*
X1163976Y1097637D03*
X1160235Y1105117D03*
X1171456Y1093897D03*
X1167716Y1101377D03*
X1163976Y1093897D03*
X1160235Y1101377D03*
X1171456Y1108858D03*
X1167716D03*
X1163976D03*
X1160235D03*
X1171456Y1120078D03*
X1167716D03*
X1163976D03*
X1160235D03*
X1171456Y1123818D03*
X1167716D03*
X1163976D03*
X1160235D03*
X1167716Y1116338D03*
X1163976D03*
X1160235D03*
X1163976Y1112598D03*
X1171456Y1116338D03*
X1160235Y1112598D03*
X1171456D03*
X1167716D03*
X1171456Y1127558D03*
X1167716D03*
X1163976D03*
X1160235D03*
X1171456Y1135039D03*
X1167716D03*
X1163976D03*
X1160235D03*
X1171456Y1131299D03*
X1167716D03*
X1163976D03*
X1160235D03*
X1171456Y1138779D03*
X1167716D03*
X1163976D03*
X1160235D03*
X1171456Y1142519D03*
X1167716D03*
X1163976D03*
X1160235D03*
X1171456Y1149999D03*
X1167716D03*
X1163976D03*
X1160235D03*
X1171456Y1146259D03*
X1167716D03*
X1163976D03*
X1160235D03*
X1171456Y1153740D03*
X1167716D03*
X1163976D03*
X1160235D03*
X1167716Y1157480D03*
X1160235D03*
X1171456Y1161220D03*
X1163976D03*
X1167716Y1164960D03*
X1160235D03*
X1171456Y1168700D03*
X1163976D03*
X1167716Y1172440D03*
X1160235D03*
X1171456Y1157480D03*
X1163976D03*
X1167716Y1161220D03*
X1160235D03*
X1171456Y1164960D03*
X1163976D03*
X1167716Y1168700D03*
X1160235D03*
X1171456Y1172440D03*
X1163976D03*
X1171456Y1187401D03*
X1167716D03*
X1163976D03*
X1160235D03*
X1171456Y1179921D03*
X1167716D03*
X1163976D03*
X1160235D03*
X1171456Y1183661D03*
X1167716D03*
X1163976D03*
X1160235D03*
X1171456Y1176180D03*
X1167716D03*
X1163976D03*
X1160235D03*
X1171456Y1194881D03*
X1167716D03*
X1163976D03*
X1160235D03*
X1171456Y1202362D03*
X1167716D03*
X1163976D03*
X1160235D03*
X1171456Y1198621D03*
X1167716D03*
X1163976D03*
X1160235D03*
X1171456Y1191141D03*
X1167716D03*
X1163976D03*
X1160235D03*
X1171456Y1206102D03*
X1167716D03*
X1163976D03*
X1160235D03*
X1171456Y1209842D03*
X1167716D03*
X1163976D03*
X1160235D03*
X1171456Y1221062D03*
X1167716D03*
X1163976D03*
X1160235D03*
Y1213582D03*
X1163976D03*
X1171456Y1217322D03*
X1163976D03*
X1171456Y1213582D03*
X1167716D03*
X1160235Y1217322D03*
X1167716D03*
X1171456Y1224803D03*
X1163976D03*
X1171456Y1228543D03*
X1163976D03*
X1167716Y1232283D03*
X1160235D03*
X1167716Y1236023D03*
X1160235D03*
X1171456Y1232283D03*
X1167716Y1224803D03*
X1163976Y1232283D03*
X1160235Y1224803D03*
X1171456Y1236023D03*
X1167716Y1228543D03*
X1163976Y1236023D03*
X1160235Y1228543D03*
X1171456Y1239763D03*
X1167716D03*
X1163976D03*
X1160235D03*
X1171456Y1243503D03*
X1163976D03*
X1171456Y1247243D03*
X1163976D03*
X1167716Y1250984D03*
X1160235D03*
X1171456D03*
X1167716Y1243503D03*
X1163976Y1250984D03*
X1160235Y1243503D03*
X1167716Y1247243D03*
X1160235D03*
X1167716Y1254724D03*
X1160235D03*
X1171456D03*
X1163976D03*
X1182676Y1075196D03*
X1175196D03*
X1186417D03*
X1178936D03*
X1182676Y1078936D03*
X1175196D03*
X1186417Y1082677D03*
X1178936D03*
X1186417Y1086417D03*
X1178936D03*
X1186417Y1090157D03*
X1182676D03*
X1178936D03*
X1175196D03*
X1186417Y1078936D03*
X1182676Y1086417D03*
X1178936Y1078936D03*
X1175196Y1086417D03*
X1182676Y1082677D03*
X1175196D03*
X1182676Y1093897D03*
X1175196D03*
X1182676Y1097637D03*
X1175196D03*
X1186417Y1101377D03*
X1178936D03*
X1186417Y1105117D03*
X1178936D03*
X1186417Y1097637D03*
X1182676Y1105117D03*
X1178936Y1097637D03*
X1175196Y1105117D03*
X1186417Y1093897D03*
X1182676Y1101377D03*
X1178936Y1093897D03*
X1175196Y1101377D03*
X1186417Y1108858D03*
X1182676D03*
X1178936D03*
X1175196D03*
X1186417Y1120078D03*
X1182676D03*
X1178936D03*
X1175196D03*
X1186417Y1123818D03*
X1182676D03*
X1178936D03*
X1175196D03*
X1186417Y1116338D03*
X1178936D03*
Y1112598D03*
X1186417D03*
X1182676Y1116338D03*
X1175196Y1112598D03*
Y1116338D03*
X1182676Y1112598D03*
X1186417Y1127558D03*
X1182676D03*
X1178936D03*
X1175196D03*
X1182676Y1131299D03*
X1186417Y1135039D03*
X1182676D03*
X1178936D03*
X1175196D03*
X1182676Y1138779D03*
X1186417Y1131299D03*
Y1138779D03*
X1178936Y1131299D03*
X1175196D03*
X1178936Y1138779D03*
X1175196D03*
X1182676Y1142519D03*
X1178936D03*
X1175196D03*
X1182676Y1146259D03*
X1186417Y1149999D03*
X1182676D03*
X1178936D03*
X1175196D03*
X1186417Y1153740D03*
X1182676D03*
X1178936Y1146259D03*
X1175196D03*
X1178936Y1153740D03*
X1175196D03*
X1186417Y1142519D03*
Y1146259D03*
Y1157480D03*
X1182676D03*
X1175196D03*
X1186417Y1161220D03*
Y1164960D03*
X1175196D03*
X1186417Y1168700D03*
Y1172440D03*
X1182676D03*
X1175196D03*
X1182676Y1161220D03*
X1178936D03*
X1175196D03*
X1182676Y1164960D03*
X1178936D03*
X1182676Y1168700D03*
X1178936D03*
X1175196D03*
X1178936Y1157480D03*
Y1172440D03*
X1182676Y1183661D03*
Y1187401D03*
X1178936D03*
X1175196D03*
X1182676Y1176180D03*
X1178936Y1179921D03*
X1175196D03*
X1178936Y1183661D03*
X1175196D03*
X1178936Y1176180D03*
X1175196D03*
X1182676Y1179921D03*
X1186417Y1183661D03*
Y1187401D03*
Y1179921D03*
Y1176180D03*
X1182676Y1191141D03*
X1186417Y1194881D03*
X1182676D03*
X1178936D03*
X1175196D03*
X1182676Y1198621D03*
X1186417Y1202362D03*
X1182676D03*
X1178936D03*
X1175196D03*
X1186417Y1198621D03*
Y1191141D03*
X1178936Y1198621D03*
X1175196D03*
X1178936Y1191141D03*
X1175196D03*
X1186417Y1206102D03*
X1182676D03*
X1178936D03*
X1175196D03*
X1186417Y1209842D03*
X1182676D03*
X1178936D03*
X1175196D03*
X1186417Y1221062D03*
X1182676D03*
X1178936D03*
X1175196D03*
X1182676Y1217322D03*
X1186417Y1213582D03*
X1175196D03*
X1182676D03*
X1178936D03*
Y1217322D03*
X1186417D03*
X1175196D03*
X1186417Y1224803D03*
X1178936D03*
X1186417Y1228543D03*
X1178936D03*
X1182676Y1232283D03*
X1175196D03*
X1182676Y1236023D03*
X1175196D03*
X1186417Y1232283D03*
X1182676Y1224803D03*
X1178936Y1232283D03*
X1175196Y1224803D03*
X1186417Y1236023D03*
X1182676Y1228543D03*
X1178936Y1236023D03*
X1175196Y1228543D03*
X1186417Y1239763D03*
X1182676D03*
X1178936D03*
X1175196D03*
X1186417Y1243503D03*
X1178936D03*
X1186417Y1247243D03*
X1178936D03*
X1182676Y1250984D03*
X1175196D03*
X1186417D03*
X1182676Y1243503D03*
X1178936Y1250984D03*
X1175196Y1243503D03*
X1182676Y1247243D03*
X1175196D03*
X1182676Y1254724D03*
X1175196D03*
X1186417D03*
X1178936D03*
X1205117Y1075196D03*
X1197637D03*
X1190157D03*
X1201377D03*
X1193897D03*
X1205117Y1078936D03*
X1197637D03*
X1190157D03*
X1201377Y1082677D03*
X1193897D03*
X1201377Y1086417D03*
X1193897D03*
X1205117Y1090157D03*
X1201377D03*
X1197637D03*
X1193897D03*
X1190157D03*
X1205117Y1086417D03*
X1201377Y1078936D03*
X1197637Y1086417D03*
X1193897Y1078936D03*
X1190157Y1086417D03*
X1205117Y1082677D03*
X1197637D03*
X1190157D03*
X1205117Y1093897D03*
X1197637D03*
X1190157D03*
X1205117Y1097637D03*
X1197637D03*
X1190157D03*
X1201377Y1101377D03*
X1193897D03*
X1201377Y1105117D03*
X1193897D03*
X1205117D03*
X1201377Y1097637D03*
X1197637Y1105117D03*
X1193897Y1097637D03*
X1190157Y1105117D03*
X1205117Y1101377D03*
X1201377Y1093897D03*
X1197637Y1101377D03*
X1193897Y1093897D03*
X1190157Y1101377D03*
X1205117Y1108858D03*
X1201377D03*
X1197637D03*
X1193897D03*
X1190157D03*
X1205117Y1112598D03*
Y1116338D03*
Y1120078D03*
X1193897D03*
X1190157D03*
X1205117Y1123818D03*
X1193897D03*
X1190157D03*
X1197637Y1120078D03*
X1193897Y1112598D03*
Y1116338D03*
X1197637D03*
X1190157Y1112598D03*
X1197637Y1123818D03*
X1201377Y1116338D03*
Y1123818D03*
X1190157Y1116338D03*
X1201377Y1120078D03*
Y1112598D03*
X1197637D03*
X1205117Y1127558D03*
X1193897D03*
X1205117Y1131299D03*
X1193897D03*
X1205117Y1135039D03*
X1193897D03*
X1205117Y1138779D03*
X1193897D03*
X1190157D03*
Y1127558D03*
Y1135039D03*
Y1131299D03*
X1201377Y1127558D03*
Y1131299D03*
X1197637Y1127558D03*
Y1131299D03*
X1201377Y1138779D03*
X1197637Y1135039D03*
X1201377D03*
X1197637Y1138779D03*
X1205117Y1142519D03*
X1193897D03*
X1190157D03*
X1205117Y1146259D03*
X1193897D03*
X1190157D03*
X1205117Y1149999D03*
X1193897D03*
X1190157D03*
X1205117Y1153740D03*
X1201377D03*
X1197637D03*
X1193897D03*
X1190157D03*
X1197637Y1142519D03*
X1201377Y1149999D03*
X1197637D03*
Y1146259D03*
X1201377Y1142519D03*
Y1146259D03*
X1205117Y1157480D03*
X1201377D03*
X1193897D03*
X1205117Y1161220D03*
X1201377D03*
X1193897D03*
X1205117Y1164960D03*
X1201377D03*
X1193897D03*
X1205117Y1168700D03*
X1201377D03*
X1193897D03*
X1205117Y1172440D03*
X1201377D03*
X1193897D03*
X1197637Y1157480D03*
Y1161220D03*
Y1164960D03*
Y1168700D03*
Y1172440D03*
X1190157Y1157480D03*
Y1161220D03*
Y1164960D03*
Y1168700D03*
Y1172440D03*
X1205117Y1183661D03*
X1197637D03*
X1193897D03*
X1190157D03*
X1205117Y1187401D03*
X1193897D03*
X1190157D03*
X1205117Y1176180D03*
X1201377D03*
X1197637D03*
X1193897D03*
X1190157D03*
X1205117Y1179921D03*
X1197637D03*
X1190157D03*
X1201377Y1187401D03*
X1193897Y1179921D03*
X1197637Y1187401D03*
X1201377Y1179921D03*
Y1183661D03*
X1205117Y1191141D03*
X1197637D03*
X1193897D03*
X1190157D03*
X1205117Y1194881D03*
X1193897D03*
X1205117Y1198621D03*
X1193897D03*
X1205117Y1202362D03*
X1193897D03*
X1201377Y1191141D03*
X1190157Y1198621D03*
Y1202362D03*
Y1194881D03*
X1197637D03*
Y1202362D03*
X1201377Y1194881D03*
Y1202362D03*
Y1198621D03*
X1197637D03*
X1205117Y1206102D03*
X1193897D03*
X1205117Y1209842D03*
X1193897D03*
X1190157D03*
X1205117Y1213582D03*
Y1217322D03*
Y1221062D03*
X1201377D03*
X1197637D03*
X1193897D03*
X1190157D03*
Y1206102D03*
X1201377Y1217322D03*
X1197637Y1209842D03*
Y1213582D03*
X1190157Y1217322D03*
Y1213582D03*
X1193897D03*
X1197637Y1217322D03*
X1201377Y1213582D03*
Y1209842D03*
X1193897Y1217322D03*
X1197637Y1206102D03*
X1201377D03*
Y1224803D03*
X1193897D03*
X1201377Y1228543D03*
X1193897D03*
X1205117Y1232283D03*
X1197637D03*
X1190157D03*
X1205117Y1236023D03*
X1197637D03*
X1190157D03*
X1201377Y1232283D03*
X1197637Y1224803D03*
X1193897Y1232283D03*
X1190157Y1224803D03*
X1201377Y1236023D03*
X1197637Y1228543D03*
X1193897Y1236023D03*
X1190157Y1228543D03*
X1205117Y1224803D03*
Y1228543D03*
Y1239763D03*
X1201377D03*
X1197637D03*
X1193897D03*
X1190157D03*
X1201377Y1243503D03*
X1193897D03*
X1201377Y1247243D03*
X1193897D03*
X1205117Y1250984D03*
X1197637D03*
X1190157D03*
X1201377D03*
X1197637Y1243503D03*
X1193897Y1250984D03*
X1190157Y1243503D03*
X1197637Y1247243D03*
X1190157D03*
X1205117Y1243503D03*
Y1247243D03*
Y1254724D03*
X1197637D03*
X1190157D03*
X1201377D03*
X1193897D03*
X1220078Y1075196D03*
X1212598D03*
X1208858D03*
X1216338D03*
X1220078Y1078936D03*
X1212598D03*
X1216338Y1082677D03*
X1208858D03*
X1216338Y1086417D03*
X1208858D03*
X1220078Y1090157D03*
X1216338D03*
X1212598D03*
X1208858D03*
Y1078936D03*
X1212598Y1086417D03*
X1216338Y1078936D03*
X1220078Y1086417D03*
X1212598Y1082677D03*
X1220078D03*
Y1093897D03*
X1212598D03*
X1220078Y1097637D03*
X1212598D03*
X1216338Y1101377D03*
X1208858D03*
X1216338Y1105117D03*
X1208858D03*
Y1097637D03*
X1212598Y1105117D03*
X1216338Y1097637D03*
X1220078Y1105117D03*
X1208858Y1093897D03*
X1212598Y1101377D03*
X1216338Y1093897D03*
X1220078Y1101377D03*
Y1108858D03*
X1216338D03*
X1212598D03*
X1208858D03*
X1212598Y1112598D03*
X1208858D03*
X1220078Y1116338D03*
X1216338D03*
X1212598Y1120078D03*
X1208858D03*
X1220078Y1123818D03*
X1216338D03*
Y1112598D03*
X1208858Y1116338D03*
X1216338Y1120078D03*
X1208858Y1123818D03*
X1220078Y1112598D03*
X1212598Y1116338D03*
X1220078Y1120078D03*
X1212598Y1123818D03*
Y1127558D03*
X1208858D03*
X1220078Y1131299D03*
X1216338D03*
X1212598Y1135039D03*
X1208858D03*
X1220078Y1138779D03*
X1216338D03*
X1208858D03*
X1212598D03*
X1216338Y1127558D03*
X1208858Y1131299D03*
X1216338Y1135039D03*
X1220078Y1127558D03*
X1212598Y1131299D03*
X1220078Y1135039D03*
X1212598Y1142519D03*
X1208858D03*
X1220078Y1146259D03*
X1216338D03*
X1212598Y1149999D03*
X1208858D03*
X1220078Y1153740D03*
X1216338D03*
Y1142519D03*
X1208858Y1146259D03*
X1216338Y1149999D03*
X1208858Y1153740D03*
X1220078Y1142519D03*
X1212598Y1146259D03*
X1220078Y1149999D03*
X1212598Y1153740D03*
Y1157480D03*
X1208858D03*
X1220078Y1161220D03*
X1216338D03*
X1212598Y1164960D03*
X1208858D03*
X1220078Y1168700D03*
X1216338D03*
X1212598Y1172440D03*
X1208858D03*
X1216338Y1157480D03*
X1208858Y1161220D03*
X1216338Y1164960D03*
X1208858Y1168700D03*
X1216338Y1172440D03*
X1220078Y1157480D03*
X1212598Y1161220D03*
X1220078Y1164960D03*
X1212598Y1168700D03*
X1220078Y1172440D03*
Y1183661D03*
X1216338D03*
X1212598Y1187401D03*
X1208858D03*
X1220078Y1176180D03*
X1216338D03*
X1212598Y1179921D03*
X1208858D03*
Y1176180D03*
X1216338Y1179921D03*
X1208858Y1183661D03*
X1216338Y1187401D03*
X1212598Y1176180D03*
X1220078Y1179921D03*
X1212598Y1183661D03*
X1220078Y1187401D03*
Y1191141D03*
X1216338D03*
X1212598Y1194881D03*
X1208858D03*
X1220078Y1198621D03*
X1216338D03*
X1212598Y1202362D03*
X1208858D03*
Y1191141D03*
X1216338Y1194881D03*
X1212598Y1191141D03*
X1220078Y1194881D03*
X1216338Y1202362D03*
X1208858Y1198621D03*
X1220078Y1202362D03*
X1212598Y1198621D03*
X1220078Y1206102D03*
X1216338D03*
X1212598Y1209842D03*
X1208858D03*
X1220078Y1213582D03*
X1216338D03*
X1212598Y1217322D03*
X1208858D03*
X1220078Y1221062D03*
X1216338D03*
X1212598D03*
X1208858D03*
X1216338Y1217322D03*
X1208858Y1213582D03*
X1216338Y1209842D03*
X1208858Y1206102D03*
X1220078Y1217322D03*
X1212598Y1213582D03*
X1220078Y1209842D03*
X1212598Y1206102D03*
X1216338Y1224803D03*
X1208858D03*
X1216338Y1228543D03*
X1208858D03*
X1220078Y1232283D03*
X1212598D03*
X1220078Y1236023D03*
X1212598D03*
X1208858Y1232283D03*
X1212598Y1224803D03*
X1216338Y1232283D03*
X1220078Y1224803D03*
X1208858Y1236023D03*
X1212598Y1228543D03*
X1216338Y1236023D03*
X1220078Y1228543D03*
Y1239763D03*
X1216338D03*
X1212598D03*
X1208858D03*
X1216338Y1243503D03*
X1208858D03*
X1216338Y1247243D03*
X1208858D03*
X1220078Y1250984D03*
X1212598D03*
X1208858D03*
X1212598Y1243503D03*
X1216338Y1250984D03*
X1220078Y1243503D03*
X1212598Y1247243D03*
X1220078D03*
Y1254724D03*
X1212598D03*
X1208858D03*
X1216338D03*
X1235039Y1075196D03*
X1227558D03*
X1231298D03*
X1223818D03*
X1235039Y1078936D03*
X1227558D03*
X1231298Y1082677D03*
X1223818D03*
X1235039Y1086417D03*
X1231298D03*
X1223818D03*
X1231298Y1090157D03*
X1227558D03*
X1223818D03*
X1235039D03*
X1231298Y1078936D03*
X1235039Y1082677D03*
X1223818Y1078936D03*
X1227558Y1086417D03*
Y1082677D03*
X1235039Y1093897D03*
X1227558D03*
X1235039Y1097637D03*
X1227558D03*
X1231298Y1101377D03*
X1223818D03*
X1235039Y1105117D03*
X1231298D03*
X1223818D03*
X1231298Y1097637D03*
X1235039Y1101377D03*
X1223818Y1097637D03*
X1227558Y1105117D03*
X1231298Y1093897D03*
X1223818D03*
X1227558Y1101377D03*
X1231298Y1108858D03*
X1227558D03*
X1223818D03*
X1235039Y1112598D03*
X1223818D03*
X1231298Y1116338D03*
X1227558D03*
X1223818D03*
X1235039Y1120078D03*
X1223818D03*
X1231298Y1123818D03*
X1227558D03*
X1223818D03*
X1235039Y1108858D03*
X1227558Y1112598D03*
X1235039Y1116338D03*
X1227558Y1120078D03*
X1235039Y1123818D03*
X1231298Y1112598D03*
Y1120078D03*
X1235039Y1127558D03*
X1223818D03*
X1231298Y1131299D03*
X1227558D03*
X1223818D03*
X1235039Y1135039D03*
X1223818D03*
X1231298Y1138779D03*
X1227558D03*
X1223818D03*
X1235039D03*
X1227558Y1127558D03*
X1235039Y1131299D03*
X1227558Y1135039D03*
X1231298Y1127558D03*
Y1135039D03*
X1235039Y1142519D03*
X1223818D03*
X1231298Y1146259D03*
X1227558D03*
X1223818D03*
X1235039Y1149999D03*
X1223818D03*
X1231298Y1153740D03*
X1227558D03*
X1223818D03*
X1227558Y1142519D03*
X1235039Y1146259D03*
X1227558Y1149999D03*
X1235039Y1153740D03*
X1231298Y1142519D03*
Y1149999D03*
X1235039Y1157480D03*
X1223818D03*
X1231298Y1161220D03*
X1227558D03*
X1223818D03*
X1235039Y1164960D03*
X1223818D03*
X1231298Y1168700D03*
X1227558D03*
X1223818D03*
X1235039Y1172440D03*
X1223818D03*
X1227558Y1157480D03*
X1235039Y1161220D03*
X1227558Y1164960D03*
X1235039Y1168700D03*
X1227558Y1172440D03*
X1231298Y1157480D03*
Y1164960D03*
Y1172440D03*
Y1183661D03*
X1227558D03*
X1223818D03*
X1235039Y1187401D03*
X1223818D03*
X1231298Y1176180D03*
X1227558D03*
X1223818D03*
X1235039Y1179921D03*
X1223818D03*
X1235039Y1176180D03*
X1227558Y1179921D03*
X1235039Y1183661D03*
X1227558Y1187401D03*
X1231298Y1179921D03*
Y1187401D03*
Y1191141D03*
X1227558D03*
X1223818D03*
X1235039Y1194881D03*
X1223818D03*
X1231298Y1198621D03*
X1227558D03*
X1223818D03*
X1235039Y1202362D03*
X1223818D03*
X1235039Y1191141D03*
X1227558Y1194881D03*
X1231298D03*
X1227558Y1202362D03*
X1235039Y1198621D03*
X1231298Y1202362D03*
Y1206102D03*
X1227558D03*
X1223818D03*
X1235039Y1209842D03*
X1223818D03*
X1231298Y1213582D03*
X1227558D03*
X1223818D03*
X1235039Y1217322D03*
X1223818D03*
X1231298Y1221062D03*
X1227558D03*
X1223818D03*
X1235039D03*
X1227558Y1217322D03*
X1235039Y1213582D03*
X1227558Y1209842D03*
X1235039Y1206102D03*
X1231298Y1217322D03*
Y1209842D03*
X1235039Y1224803D03*
X1231298D03*
X1223818D03*
X1231298Y1228543D03*
X1223818D03*
X1235039Y1232283D03*
X1227558D03*
X1235039Y1236023D03*
X1227558D03*
X1223818Y1232283D03*
X1227558Y1224803D03*
X1231298Y1232283D03*
X1235039Y1228543D03*
X1223818Y1236023D03*
X1227558Y1228543D03*
X1231298Y1236023D03*
Y1239763D03*
X1227558D03*
X1223818D03*
X1235039Y1243503D03*
X1231298D03*
X1223818D03*
X1231298Y1247243D03*
X1223818D03*
X1235039Y1250984D03*
X1227558D03*
X1235039Y1239763D03*
X1223818Y1250984D03*
X1227558Y1243503D03*
X1231298Y1250984D03*
X1235039Y1247243D03*
X1227558D03*
X1235039Y1254724D03*
X1227558D03*
X1223818D03*
X1231298D03*
X1238779Y1078936D03*
Y1086417D03*
Y1090157D03*
Y1082677D03*
Y1093897D03*
Y1097637D03*
Y1105117D03*
Y1101377D03*
Y1112598D03*
Y1120078D03*
Y1108858D03*
Y1116338D03*
Y1123818D03*
Y1127558D03*
Y1135039D03*
Y1138779D03*
Y1131299D03*
Y1142519D03*
Y1149999D03*
Y1146259D03*
Y1153740D03*
Y1157480D03*
Y1164960D03*
Y1172440D03*
Y1161220D03*
Y1168700D03*
Y1187401D03*
Y1179921D03*
Y1176180D03*
Y1183661D03*
Y1194881D03*
Y1202362D03*
Y1191141D03*
Y1198621D03*
Y1209842D03*
Y1217322D03*
Y1221062D03*
Y1213582D03*
Y1206102D03*
Y1224803D03*
Y1232283D03*
Y1236023D03*
Y1228543D03*
Y1243503D03*
Y1250984D03*
Y1239763D03*
Y1247243D03*
X1527559Y1075196D03*
X1520078D03*
X1523819D03*
X1527559Y1078936D03*
X1520078D03*
X1516338D03*
X1523819Y1082677D03*
Y1086417D03*
X1520078D03*
X1516338D03*
X1527559Y1090157D03*
X1523819D03*
X1520078D03*
X1516338D03*
X1527559Y1086417D03*
X1523819Y1078936D03*
X1520078Y1082677D03*
X1527559D03*
X1516338D03*
X1527559Y1093897D03*
X1520078D03*
X1516338D03*
X1527559Y1097637D03*
X1520078D03*
X1516338D03*
X1523819Y1101377D03*
Y1105117D03*
X1520078D03*
X1516338D03*
X1527559D03*
X1523819Y1097637D03*
X1520078Y1101377D03*
X1527559D03*
X1523819Y1093897D03*
X1516338Y1101377D03*
X1527559Y1108858D03*
X1523819D03*
X1520078Y1112598D03*
X1516338D03*
X1527559Y1116338D03*
X1523819D03*
X1520078Y1120078D03*
X1516338D03*
X1527559Y1123818D03*
X1523819D03*
X1520078Y1108858D03*
X1527559Y1112598D03*
X1520078Y1116338D03*
X1527559Y1120078D03*
X1520078Y1123818D03*
X1516338Y1108858D03*
X1523819Y1112598D03*
X1516338Y1116338D03*
X1523819Y1120078D03*
X1516338Y1123818D03*
X1520078Y1127558D03*
X1516338D03*
X1527559Y1131299D03*
X1523819D03*
X1520078Y1135039D03*
X1516338D03*
X1527559Y1138779D03*
X1523819D03*
X1527559Y1127558D03*
X1520078Y1131299D03*
X1527559Y1135039D03*
X1520078Y1138779D03*
X1523819Y1127558D03*
X1516338Y1131299D03*
X1523819Y1135039D03*
X1516338Y1138779D03*
X1527559Y1142519D03*
X1523819D03*
X1520078D03*
X1516338D03*
X1523819Y1146259D03*
X1520078D03*
X1516338D03*
X1527559Y1149999D03*
X1523819D03*
Y1153740D03*
X1520078D03*
X1516338D03*
X1527559Y1146259D03*
X1520078Y1149999D03*
X1516338D03*
X1527559Y1153740D03*
Y1157480D03*
X1523819D03*
Y1161220D03*
X1520078D03*
X1516338D03*
X1527559Y1164960D03*
X1523819D03*
Y1168700D03*
X1520078D03*
X1516338D03*
X1527559Y1172440D03*
X1523819D03*
X1520078Y1157480D03*
X1516338D03*
X1527559Y1161220D03*
X1520078Y1164960D03*
X1516338D03*
X1527559Y1168700D03*
X1520078Y1172440D03*
X1516338D03*
X1527559Y1183661D03*
X1523819D03*
X1520078D03*
X1516338D03*
X1520078Y1187401D03*
X1516338D03*
X1523819Y1176180D03*
X1520078D03*
X1516338D03*
X1527559Y1179921D03*
X1523819D03*
X1520078D03*
X1516338D03*
X1527559Y1176180D03*
Y1187401D03*
X1523819D03*
X1527559Y1191141D03*
X1523819D03*
X1520078Y1194881D03*
X1516338D03*
X1527559Y1198621D03*
X1523819D03*
X1520078Y1202362D03*
X1516338D03*
X1527559D03*
X1520078Y1198621D03*
X1527559Y1194881D03*
X1520078Y1191141D03*
X1523819Y1202362D03*
X1516338Y1198621D03*
X1523819Y1194881D03*
X1516338Y1191141D03*
X1527559Y1206102D03*
X1523819D03*
X1520078Y1209842D03*
X1516338D03*
X1527559Y1213582D03*
X1523819D03*
X1520078Y1217322D03*
X1516338D03*
X1527559Y1221062D03*
X1523819D03*
X1520078D03*
X1527559Y1217322D03*
X1520078Y1213582D03*
X1527559Y1209842D03*
X1520078Y1206102D03*
X1516338Y1221062D03*
X1523819Y1217322D03*
X1516338Y1213582D03*
X1523819Y1209842D03*
X1516338Y1206102D03*
X1523819Y1224803D03*
X1520078D03*
X1516338D03*
X1523819Y1228543D03*
X1527559Y1232283D03*
X1520078D03*
X1516338D03*
X1527559Y1236023D03*
X1520078D03*
X1516338D03*
X1527559Y1224803D03*
X1523819Y1232283D03*
X1520078Y1228543D03*
X1527559D03*
X1523819Y1236023D03*
X1516338Y1228543D03*
X1527559Y1239763D03*
X1523819D03*
Y1243503D03*
X1520078D03*
X1516338D03*
X1523819Y1247243D03*
X1527559Y1250984D03*
X1520078D03*
X1516338D03*
X1520078Y1239763D03*
X1516338D03*
X1527559Y1243503D03*
X1523819Y1250984D03*
X1520078Y1247243D03*
X1527559D03*
X1516338D03*
X1527559Y1254724D03*
X1520078D03*
X1523819D03*
X1542519Y1075196D03*
X1535039D03*
X1538779D03*
X1531299D03*
X1546259D03*
X1542519Y1078936D03*
X1535039D03*
X1546259Y1082677D03*
X1538779D03*
X1531299D03*
X1546259Y1086417D03*
X1538779D03*
X1531299D03*
X1546259Y1090157D03*
X1542519D03*
X1538779D03*
X1535039D03*
X1531299D03*
X1542519Y1086417D03*
X1538779Y1078936D03*
X1535039Y1086417D03*
X1531299Y1078936D03*
X1542519Y1082677D03*
X1535039D03*
X1546259Y1078936D03*
X1542519Y1093897D03*
X1535039D03*
X1542519Y1097637D03*
X1535039D03*
X1546259Y1101377D03*
X1538779D03*
X1531299D03*
X1546259Y1105117D03*
X1538779D03*
X1531299D03*
X1542519D03*
X1538779Y1097637D03*
X1535039Y1105117D03*
X1531299Y1097637D03*
X1542519Y1101377D03*
X1538779Y1093897D03*
X1535039Y1101377D03*
X1531299Y1093897D03*
X1546259Y1097637D03*
Y1093897D03*
Y1108858D03*
X1542519D03*
X1538779D03*
X1535039D03*
X1531299D03*
X1546259Y1112598D03*
X1542519D03*
X1531299D03*
X1538779Y1116338D03*
X1535039D03*
X1531299D03*
X1546259Y1120078D03*
X1542519D03*
X1531299D03*
X1538779Y1123818D03*
X1535039D03*
X1531299D03*
X1538779Y1112598D03*
X1546259Y1116338D03*
X1538779Y1120078D03*
X1546259Y1123818D03*
X1535039Y1112598D03*
X1542519Y1116338D03*
X1535039Y1120078D03*
X1542519Y1123818D03*
X1546259Y1127558D03*
X1542519D03*
X1531299D03*
X1538779Y1131299D03*
X1535039D03*
X1531299D03*
X1546259Y1135039D03*
X1542519D03*
X1531299D03*
X1538779Y1138779D03*
X1535039D03*
X1531299D03*
X1538779Y1127558D03*
X1546259Y1131299D03*
X1538779Y1135039D03*
X1546259Y1138779D03*
X1535039Y1127558D03*
X1542519Y1131299D03*
X1535039Y1135039D03*
X1542519Y1138779D03*
X1546259Y1142519D03*
X1542519D03*
X1538779D03*
X1535039D03*
X1531299D03*
X1546259Y1146259D03*
X1542519D03*
X1535039D03*
X1546259Y1149999D03*
X1535039D03*
X1531299D03*
X1546259Y1153740D03*
X1535039D03*
X1531299Y1146259D03*
X1542519Y1153740D03*
X1538779Y1149999D03*
X1542519D03*
X1538779Y1146259D03*
Y1153740D03*
X1531299D03*
X1546259Y1157480D03*
X1535039D03*
X1531299D03*
X1546259Y1161220D03*
X1535039D03*
X1546259Y1164960D03*
X1535039D03*
X1531299D03*
X1546259Y1168700D03*
X1535039D03*
X1546259Y1172440D03*
X1535039D03*
X1531299D03*
X1542519Y1164960D03*
Y1172440D03*
Y1168700D03*
X1538779Y1172440D03*
Y1168700D03*
Y1164960D03*
X1542519Y1157480D03*
Y1161220D03*
X1538779D03*
Y1157480D03*
X1531299Y1161220D03*
Y1168700D03*
X1546259Y1183661D03*
X1542519D03*
X1538779D03*
X1535039D03*
X1531299D03*
X1546259Y1187401D03*
X1542519D03*
X1531299D03*
X1546259Y1176180D03*
X1535039D03*
X1546259Y1179921D03*
X1542519D03*
X1538779D03*
X1535039D03*
X1531299D03*
X1538779Y1176180D03*
X1542519D03*
X1531299D03*
X1538779Y1187401D03*
X1535039D03*
X1538779Y1191141D03*
X1535039D03*
X1531299D03*
X1546259Y1194881D03*
X1542519D03*
X1531299D03*
X1538779Y1198621D03*
X1535039D03*
X1531299D03*
X1546259Y1202362D03*
X1542519D03*
X1531299D03*
X1538779D03*
X1546259Y1198621D03*
X1538779Y1194881D03*
X1546259Y1191141D03*
X1535039Y1202362D03*
X1542519Y1198621D03*
X1535039Y1194881D03*
X1542519Y1191141D03*
X1538779Y1206102D03*
X1535039D03*
X1531299D03*
X1546259Y1209842D03*
X1542519D03*
X1531299D03*
X1538779Y1213582D03*
X1535039D03*
X1531299D03*
X1546259Y1217322D03*
X1542519D03*
X1531299D03*
X1546259Y1221062D03*
X1542519D03*
X1538779D03*
X1535039D03*
X1531299D03*
X1538779Y1217322D03*
X1546259Y1213582D03*
X1538779Y1209842D03*
X1546259Y1206102D03*
X1535039Y1217322D03*
X1542519Y1213582D03*
X1535039Y1209842D03*
X1542519Y1206102D03*
X1546259Y1224803D03*
X1538779D03*
X1531299D03*
X1546259Y1228543D03*
X1538779D03*
X1531299D03*
X1542519Y1232283D03*
X1535039D03*
X1542519Y1236023D03*
X1535039D03*
X1538779Y1232283D03*
X1535039Y1224803D03*
X1531299Y1232283D03*
X1538779Y1236023D03*
X1535039Y1228543D03*
X1531299Y1236023D03*
X1542519Y1224803D03*
X1546259Y1232283D03*
X1542519Y1228543D03*
X1546259Y1236023D03*
Y1239763D03*
X1542519D03*
X1538779D03*
X1535039D03*
X1531299D03*
X1546259Y1243503D03*
X1538779D03*
X1531299D03*
X1546259Y1247243D03*
X1538779D03*
X1531299D03*
X1542519Y1250984D03*
X1535039D03*
X1538779D03*
X1535039Y1243503D03*
X1531299Y1250984D03*
X1535039Y1247243D03*
X1542519Y1243503D03*
X1546259Y1250984D03*
X1542519Y1247243D03*
Y1254724D03*
X1535039D03*
X1538779D03*
X1531299D03*
X1546259D03*
X1557480Y1075196D03*
X1550000D03*
X1553740D03*
X1561220D03*
X1557480Y1078936D03*
X1550000D03*
X1561220Y1082677D03*
X1553740D03*
X1561220Y1086417D03*
X1553740D03*
X1561220Y1090157D03*
X1557480D03*
X1553740D03*
X1550000D03*
Y1086417D03*
X1553740Y1078936D03*
X1557480Y1086417D03*
X1561220Y1078936D03*
X1550000Y1082677D03*
X1557480D03*
Y1093897D03*
X1550000D03*
X1557480Y1097637D03*
X1550000D03*
X1561220Y1101377D03*
X1553740D03*
X1561220Y1105117D03*
X1553740D03*
X1550000D03*
X1553740Y1097637D03*
X1557480Y1105117D03*
X1561220Y1097637D03*
X1550000Y1101377D03*
X1553740Y1093897D03*
X1557480Y1101377D03*
X1561220Y1093897D03*
Y1108858D03*
X1557480D03*
X1553740D03*
X1550000D03*
X1553740Y1112598D03*
X1550000D03*
X1553740Y1116338D03*
X1550000D03*
X1561220Y1120078D03*
X1557480D03*
X1553740D03*
X1550000D03*
X1561220Y1123818D03*
X1557480D03*
X1553740D03*
X1550000D03*
X1561220Y1116338D03*
X1557480D03*
Y1112598D03*
X1561220D03*
Y1127558D03*
X1557480D03*
X1553740D03*
X1550000D03*
X1561220Y1131299D03*
X1557480D03*
X1553740D03*
X1550000D03*
X1561220Y1135039D03*
X1557480D03*
X1553740D03*
X1550000D03*
X1561220Y1138779D03*
X1553740D03*
X1550000D03*
X1557480D03*
Y1149999D03*
X1561220Y1153740D03*
Y1142519D03*
X1557480D03*
X1553740D03*
X1550000D03*
X1561220Y1146259D03*
X1553740D03*
Y1149999D03*
Y1153740D03*
X1557480Y1146259D03*
X1550000D03*
Y1149999D03*
Y1153740D03*
X1561220Y1149999D03*
X1557480Y1153740D03*
Y1157480D03*
X1561220Y1161220D03*
X1557480Y1164960D03*
X1561220Y1168700D03*
X1557480Y1172440D03*
X1553740Y1157480D03*
X1550000D03*
X1553740Y1161220D03*
Y1164960D03*
Y1168700D03*
X1550000D03*
X1553740Y1172440D03*
X1550000D03*
Y1161220D03*
Y1164960D03*
X1561220Y1172440D03*
Y1157480D03*
X1557480Y1161220D03*
X1561220Y1164960D03*
X1557480Y1168700D03*
X1561220Y1176180D03*
X1557480Y1179921D03*
X1561220Y1183661D03*
X1553740D03*
X1550000D03*
X1561220Y1187401D03*
X1557480D03*
X1553740D03*
X1550000D03*
X1553740Y1176180D03*
Y1179921D03*
X1550000Y1176180D03*
Y1179921D03*
X1557480Y1183661D03*
Y1176180D03*
X1561220Y1179921D03*
Y1191141D03*
X1557480D03*
X1553740D03*
X1550000D03*
X1561220Y1194881D03*
X1557480D03*
X1553740D03*
X1550000D03*
X1561220Y1198621D03*
X1557480D03*
X1553740D03*
X1550000D03*
X1561220Y1202362D03*
X1557480D03*
X1553740D03*
X1550000D03*
X1561220Y1206102D03*
X1557480D03*
X1553740D03*
X1550000D03*
X1561220Y1209842D03*
X1557480D03*
X1553740D03*
X1550000D03*
X1557480Y1213582D03*
X1553740D03*
X1550000D03*
X1553740Y1217322D03*
X1550000D03*
X1561220Y1221062D03*
X1557480D03*
X1553740D03*
X1550000D03*
X1561220Y1217322D03*
X1557480D03*
X1561220Y1213582D03*
Y1224803D03*
X1553740D03*
X1561220Y1228543D03*
X1553740D03*
X1557480Y1232283D03*
X1550000D03*
X1557480Y1236023D03*
X1550000D03*
Y1224803D03*
X1553740Y1232283D03*
X1557480Y1224803D03*
X1561220Y1232283D03*
X1550000Y1228543D03*
X1553740Y1236023D03*
X1557480Y1228543D03*
X1561220Y1236023D03*
Y1239763D03*
X1557480D03*
X1553740D03*
X1550000D03*
X1561220Y1243503D03*
X1553740D03*
X1561220Y1247243D03*
X1553740D03*
X1557480Y1250984D03*
X1550000D03*
Y1243503D03*
X1553740Y1250984D03*
X1557480Y1243503D03*
X1561220Y1250984D03*
X1550000Y1247243D03*
X1557480D03*
Y1254724D03*
X1550000D03*
X1553740D03*
X1561220D03*
X1572441Y1075196D03*
X1564960D03*
X1568700D03*
X1576181D03*
X1572441Y1078936D03*
X1564960D03*
X1576181Y1082677D03*
X1568700D03*
X1576181Y1086417D03*
X1568700D03*
X1576181Y1090157D03*
X1572441D03*
X1568700D03*
X1564960D03*
Y1086417D03*
X1568700Y1078936D03*
X1572441Y1086417D03*
X1576181Y1078936D03*
X1564960Y1082677D03*
X1572441D03*
Y1093897D03*
X1564960D03*
X1572441Y1097637D03*
X1564960D03*
X1576181Y1101377D03*
X1568700D03*
X1576181Y1105117D03*
X1568700D03*
X1564960D03*
X1568700Y1097637D03*
X1572441Y1105117D03*
X1576181Y1097637D03*
X1564960Y1101377D03*
X1568700Y1093897D03*
X1572441Y1101377D03*
X1576181Y1093897D03*
Y1108858D03*
X1572441D03*
X1568700D03*
X1564960D03*
X1576181Y1120078D03*
X1572441D03*
X1568700D03*
X1564960D03*
X1576181Y1123818D03*
X1572441D03*
X1568700D03*
X1564960D03*
X1572441Y1112598D03*
X1576181Y1116338D03*
X1572441D03*
X1576181Y1112598D03*
X1564960Y1116338D03*
Y1112598D03*
X1568700Y1116338D03*
Y1112598D03*
X1576181Y1127558D03*
X1572441D03*
X1568700D03*
X1564960D03*
X1568700Y1131299D03*
X1576181Y1135039D03*
X1572441D03*
X1568700D03*
Y1138779D03*
X1564960D03*
X1576181Y1131299D03*
X1572441D03*
X1576181Y1138779D03*
X1572441D03*
X1564960Y1131299D03*
Y1135039D03*
X1576181Y1142519D03*
X1572441D03*
X1568700Y1146259D03*
X1576181Y1149999D03*
X1572441D03*
X1564960D03*
X1568700Y1153740D03*
X1576181Y1146259D03*
X1572441D03*
X1576181Y1153740D03*
X1572441D03*
X1564960Y1142519D03*
X1568700D03*
X1564960Y1146259D03*
X1568700Y1149999D03*
X1564960Y1153740D03*
X1572441Y1157480D03*
X1564960D03*
X1576181Y1161220D03*
X1568700D03*
X1572441Y1164960D03*
X1564960D03*
X1576181Y1168700D03*
X1568700D03*
X1572441Y1172440D03*
X1564960D03*
X1576181Y1157480D03*
X1568700D03*
X1572441Y1161220D03*
X1564960D03*
X1576181Y1164960D03*
X1568700D03*
X1572441Y1168700D03*
X1564960D03*
X1576181Y1172440D03*
X1568700D03*
Y1183661D03*
X1576181Y1187401D03*
X1572441D03*
X1568700D03*
X1564960D03*
X1568700Y1176180D03*
X1576181Y1179921D03*
X1572441D03*
X1564960D03*
X1576181Y1183661D03*
X1572441D03*
X1576181Y1176180D03*
X1572441D03*
X1564960Y1183661D03*
Y1176180D03*
X1568700Y1179921D03*
Y1191141D03*
X1576181Y1194881D03*
X1572441D03*
X1568700D03*
Y1198621D03*
X1576181Y1202362D03*
X1572441D03*
X1568700D03*
X1564960D03*
Y1191141D03*
X1576181Y1198621D03*
X1572441D03*
X1576181Y1191141D03*
X1572441D03*
X1564960Y1198621D03*
Y1194881D03*
X1576181Y1206102D03*
X1572441D03*
X1568700D03*
X1564960D03*
X1576181Y1209842D03*
X1572441D03*
X1568700D03*
X1564960D03*
Y1213582D03*
Y1217322D03*
X1576181Y1221062D03*
X1572441D03*
X1568700D03*
X1564960D03*
X1576181Y1213582D03*
X1572441D03*
X1576181Y1217322D03*
X1568700Y1213582D03*
X1572441Y1217322D03*
X1568700D03*
X1576181Y1224803D03*
X1568700D03*
X1576181Y1228543D03*
X1568700D03*
X1572441Y1232283D03*
X1564960D03*
X1572441Y1236023D03*
X1564960D03*
Y1224803D03*
X1568700Y1232283D03*
X1572441Y1224803D03*
X1576181Y1232283D03*
X1564960Y1228543D03*
X1568700Y1236023D03*
X1572441Y1228543D03*
X1576181Y1236023D03*
Y1239763D03*
X1572441D03*
X1568700D03*
X1564960D03*
X1576181Y1243503D03*
X1568700D03*
X1576181Y1247243D03*
X1568700D03*
X1572441Y1250984D03*
X1564960D03*
Y1243503D03*
X1568700Y1250984D03*
X1572441Y1243503D03*
X1576181Y1250984D03*
X1564960Y1247243D03*
X1572441D03*
Y1254724D03*
X1564960D03*
X1568700D03*
X1576181D03*
X1594882Y1075196D03*
X1587401D03*
X1579921D03*
X1583661D03*
X1591141D03*
X1594882Y1078936D03*
X1587401D03*
X1579921D03*
X1591141Y1082677D03*
X1583661D03*
X1591141Y1086417D03*
X1583661D03*
X1594882Y1090157D03*
X1591141D03*
X1587401D03*
X1583661D03*
X1579921D03*
Y1086417D03*
X1583661Y1078936D03*
X1587401Y1086417D03*
X1591141Y1078936D03*
X1594882Y1086417D03*
X1579921Y1082677D03*
X1587401D03*
X1594882D03*
Y1093897D03*
X1587401D03*
X1579921D03*
X1594882Y1097637D03*
X1587401D03*
X1579921D03*
X1591141Y1101377D03*
X1583661D03*
X1591141Y1105117D03*
X1583661D03*
X1579921D03*
X1583661Y1097637D03*
X1587401Y1105117D03*
X1591141Y1097637D03*
X1594882Y1105117D03*
X1579921Y1101377D03*
X1583661Y1093897D03*
X1587401Y1101377D03*
X1591141Y1093897D03*
X1594882Y1101377D03*
Y1108858D03*
X1591141D03*
X1587401D03*
X1583661D03*
X1579921D03*
X1587401Y1112598D03*
Y1116338D03*
X1594882Y1120078D03*
X1591141D03*
X1587401D03*
X1583661D03*
X1579921D03*
X1594882Y1123818D03*
X1591141D03*
X1587401D03*
X1583661D03*
X1579921D03*
X1594882Y1112598D03*
Y1116338D03*
X1591141D03*
Y1112598D03*
X1579921Y1116338D03*
Y1112598D03*
X1583661Y1116338D03*
Y1112598D03*
X1594882Y1127558D03*
X1591141D03*
X1587401D03*
X1583661D03*
X1579921D03*
X1594882Y1135039D03*
X1591141D03*
X1587401D03*
X1583661D03*
X1579921D03*
X1594882Y1131299D03*
X1591141D03*
X1587401D03*
X1583661D03*
X1579921D03*
X1594882Y1138779D03*
X1591141D03*
X1587401D03*
X1583661D03*
X1579921D03*
X1594882Y1142519D03*
X1591141D03*
X1587401D03*
X1583661D03*
X1579921D03*
X1594882Y1149999D03*
X1591141D03*
X1587401D03*
X1583661D03*
X1579921D03*
X1594882Y1146259D03*
X1591141D03*
X1587401D03*
X1583661D03*
X1579921D03*
X1594882Y1153740D03*
X1591141D03*
X1587401D03*
X1583661D03*
X1579921D03*
X1594882Y1157480D03*
X1587401D03*
X1579921D03*
X1591141Y1161220D03*
X1583661D03*
X1594882Y1164960D03*
X1587401D03*
X1579921D03*
X1591141Y1168700D03*
X1583661D03*
X1594882Y1172440D03*
X1587401D03*
X1579921D03*
X1591141Y1157480D03*
X1583661D03*
X1594882Y1161220D03*
X1587401D03*
X1579921D03*
X1591141Y1164960D03*
X1583661D03*
X1594882Y1168700D03*
X1587401D03*
X1579921D03*
X1591141Y1172440D03*
X1583661D03*
X1594882Y1187401D03*
X1591141D03*
X1587401D03*
X1583661D03*
X1579921D03*
X1594882Y1179921D03*
X1591141D03*
X1587401D03*
X1583661D03*
X1579921D03*
X1594882Y1183661D03*
X1591141D03*
X1587401D03*
X1583661D03*
X1579921D03*
X1594882Y1176180D03*
X1591141D03*
X1587401D03*
X1583661D03*
X1579921D03*
X1594882Y1194881D03*
X1591141D03*
X1587401D03*
X1583661D03*
X1579921D03*
X1594882Y1202362D03*
X1591141D03*
X1587401D03*
X1583661D03*
X1579921D03*
X1594882Y1198621D03*
X1591141D03*
X1587401D03*
X1583661D03*
X1579921D03*
X1594882Y1191141D03*
X1591141D03*
X1587401D03*
X1583661D03*
X1579921D03*
X1594882Y1206102D03*
X1591141D03*
X1587401D03*
X1583661D03*
X1579921D03*
X1594882Y1209842D03*
X1591141D03*
X1587401D03*
X1583661D03*
X1579921D03*
X1591141Y1213582D03*
Y1217322D03*
X1594882Y1221062D03*
X1591141D03*
X1587401D03*
X1583661D03*
X1579921D03*
X1594882Y1213582D03*
Y1217322D03*
X1583661Y1213582D03*
X1579921Y1217322D03*
X1587401D03*
X1579921Y1213582D03*
X1587401D03*
X1583661Y1217322D03*
X1591141Y1224803D03*
X1583661D03*
X1591141Y1228543D03*
X1583661D03*
X1594882Y1232283D03*
X1587401D03*
X1579921D03*
X1594882Y1236023D03*
X1587401D03*
X1579921D03*
X1587401Y1224803D03*
X1591141Y1232283D03*
X1594882Y1224803D03*
X1579921D03*
X1583661Y1232283D03*
X1587401Y1228543D03*
X1591141Y1236023D03*
X1594882Y1228543D03*
X1579921D03*
X1583661Y1236023D03*
X1594882Y1239763D03*
X1591141D03*
X1587401D03*
X1583661D03*
X1579921D03*
X1591141Y1243503D03*
X1583661D03*
X1591141Y1247243D03*
X1583661D03*
X1594882Y1250984D03*
X1587401D03*
X1579921D03*
X1587401Y1243503D03*
X1591141Y1250984D03*
X1594882Y1243503D03*
X1579921D03*
X1583661Y1250984D03*
X1587401Y1247243D03*
X1594882D03*
X1579921D03*
X1594882Y1254724D03*
X1587401D03*
X1579921D03*
X1591141D03*
X1583661D03*
X1609842Y1075196D03*
X1602362D03*
X1598622D03*
X1606102D03*
X1609842Y1078936D03*
X1602362D03*
X1606102Y1082677D03*
X1598622D03*
X1606102Y1086417D03*
X1598622D03*
X1609842Y1090157D03*
X1606102D03*
X1602362D03*
X1598622D03*
Y1078936D03*
X1602362Y1086417D03*
Y1082677D03*
X1609842Y1086417D03*
X1606102Y1078936D03*
X1609842Y1082677D03*
Y1093897D03*
X1602362D03*
X1609842Y1097637D03*
X1602362D03*
X1606102Y1101377D03*
X1598622D03*
X1606102Y1105117D03*
X1598622D03*
Y1097637D03*
X1602362Y1105117D03*
X1598622Y1093897D03*
X1602362Y1101377D03*
X1609842Y1105117D03*
X1606102Y1097637D03*
X1609842Y1101377D03*
X1606102Y1093897D03*
X1609842Y1108858D03*
X1606102D03*
X1602362D03*
X1598622D03*
X1602362Y1112598D03*
Y1116338D03*
X1609842Y1120078D03*
X1606102D03*
X1602362D03*
X1598622D03*
X1609842Y1123818D03*
X1606102D03*
X1602362D03*
X1598622D03*
Y1116338D03*
Y1112598D03*
X1609842Y1116338D03*
X1606102Y1112598D03*
Y1116338D03*
X1609842Y1112598D03*
Y1127558D03*
X1606102D03*
X1602362D03*
X1598622D03*
X1609842Y1135039D03*
X1606102D03*
X1602362D03*
X1598622D03*
X1609842Y1131299D03*
X1606102D03*
X1602362D03*
X1598622D03*
X1609842Y1138779D03*
X1606102D03*
X1602362D03*
X1598622D03*
X1609842Y1142519D03*
X1606102D03*
X1602362D03*
X1598622D03*
X1609842Y1149999D03*
X1606102D03*
X1602362D03*
X1598622D03*
X1609842Y1146259D03*
X1606102D03*
X1602362D03*
X1598622D03*
X1609842Y1153740D03*
X1606102D03*
X1602362D03*
X1598622D03*
X1609842Y1157480D03*
X1602362D03*
X1606102Y1161220D03*
X1598622D03*
X1609842Y1164960D03*
X1602362D03*
X1606102Y1168700D03*
X1598622D03*
X1609842Y1172440D03*
X1602362D03*
X1606102Y1157480D03*
X1598622D03*
X1609842Y1161220D03*
X1602362D03*
X1606102Y1164960D03*
X1598622D03*
X1609842Y1168700D03*
X1602362D03*
X1606102Y1172440D03*
X1598622D03*
X1609842Y1187401D03*
X1606102D03*
X1602362D03*
X1598622D03*
X1609842Y1179921D03*
X1606102D03*
X1602362D03*
X1598622D03*
X1609842Y1183661D03*
X1606102D03*
X1602362D03*
X1598622D03*
X1609842Y1176180D03*
X1606102D03*
X1602362D03*
X1598622D03*
X1609842Y1194881D03*
X1606102D03*
X1602362D03*
X1598622D03*
X1609842Y1202362D03*
X1606102D03*
X1602362D03*
X1598622D03*
X1609842Y1198621D03*
X1606102D03*
X1602362D03*
X1598622D03*
X1609842Y1191141D03*
X1606102D03*
X1602362D03*
X1598622D03*
X1609842Y1206102D03*
X1606102D03*
X1602362D03*
X1598622D03*
X1609842Y1209842D03*
X1606102D03*
X1602362D03*
X1598622D03*
X1609842Y1221062D03*
X1606102D03*
X1602362D03*
X1598622D03*
X1609842Y1217322D03*
X1602362Y1213582D03*
X1598622Y1217322D03*
Y1213582D03*
X1602362Y1217322D03*
X1606102D03*
Y1213582D03*
X1609842D03*
X1606102Y1224803D03*
X1598622D03*
X1606102Y1228543D03*
X1598622D03*
X1609842Y1232283D03*
X1602362D03*
X1609842Y1236023D03*
X1602362D03*
X1598622Y1232283D03*
Y1236023D03*
X1609842Y1224803D03*
X1606102Y1232283D03*
X1602362Y1224803D03*
X1609842Y1228543D03*
X1606102Y1236023D03*
X1602362Y1228543D03*
X1609842Y1239763D03*
X1606102D03*
X1602362D03*
X1598622D03*
X1606102Y1243503D03*
X1598622D03*
X1606102Y1247243D03*
X1598622D03*
X1609842Y1250984D03*
X1602362D03*
X1598622D03*
X1609842Y1243503D03*
X1606102Y1250984D03*
X1602362Y1243503D03*
X1609842Y1247243D03*
X1602362D03*
X1609842Y1254724D03*
X1602362D03*
X1598622D03*
X1606102D03*
X1624803Y1075196D03*
X1617322D03*
X1621063D03*
X1613582D03*
X1624803Y1078936D03*
X1617322D03*
X1621063Y1082677D03*
X1613582D03*
X1621063Y1086417D03*
X1613582D03*
X1624803Y1090157D03*
X1621063D03*
X1617322D03*
X1613582D03*
X1624803Y1086417D03*
X1621063Y1078936D03*
X1617322Y1086417D03*
X1613582Y1078936D03*
X1624803Y1082677D03*
X1617322D03*
X1624803Y1093897D03*
X1617322D03*
X1624803Y1097637D03*
X1617322D03*
X1621063Y1101377D03*
X1613582D03*
X1621063Y1105117D03*
X1613582D03*
X1624803D03*
X1621063Y1097637D03*
X1617322Y1105117D03*
X1613582Y1097637D03*
X1624803Y1101377D03*
X1621063Y1093897D03*
X1617322Y1101377D03*
X1613582Y1093897D03*
X1624803Y1108858D03*
X1621063D03*
X1617322D03*
X1613582D03*
X1624803Y1120078D03*
X1621063D03*
X1617322D03*
X1613582D03*
X1624803Y1123818D03*
X1621063D03*
X1617322D03*
X1613582D03*
X1624803Y1116338D03*
X1621063D03*
X1617322D03*
X1621063Y1112598D03*
X1617322D03*
X1613582Y1116338D03*
Y1112598D03*
X1624803D03*
Y1127558D03*
X1621063D03*
X1617322D03*
X1613582D03*
X1624803Y1135039D03*
X1621063D03*
X1617322D03*
X1613582D03*
X1624803Y1131299D03*
X1621063D03*
X1617322D03*
X1613582D03*
X1624803Y1138779D03*
X1621063D03*
X1617322D03*
X1613582D03*
X1624803Y1142519D03*
X1621063D03*
X1617322D03*
X1613582D03*
X1624803Y1149999D03*
X1621063D03*
X1617322D03*
X1613582D03*
X1624803Y1146259D03*
X1621063D03*
X1617322D03*
X1613582D03*
X1624803Y1153740D03*
X1621063D03*
X1617322D03*
X1613582D03*
X1624803Y1157480D03*
X1617322D03*
X1621063Y1161220D03*
X1613582D03*
X1624803Y1164960D03*
X1617322D03*
X1621063Y1168700D03*
X1613582D03*
X1624803Y1172440D03*
X1617322D03*
X1621063Y1157480D03*
X1613582D03*
X1624803Y1161220D03*
X1617322D03*
X1621063Y1164960D03*
X1613582D03*
X1624803Y1168700D03*
X1617322D03*
X1621063Y1172440D03*
X1613582D03*
X1624803Y1187401D03*
X1621063D03*
X1617322D03*
X1613582D03*
X1624803Y1179921D03*
X1621063D03*
X1617322D03*
X1613582D03*
X1624803Y1183661D03*
X1621063D03*
X1617322D03*
X1613582D03*
X1624803Y1176180D03*
X1621063D03*
X1617322D03*
X1613582D03*
X1624803Y1194881D03*
X1621063D03*
X1617322D03*
X1613582D03*
X1624803Y1202362D03*
X1621063D03*
X1617322D03*
X1613582D03*
X1624803Y1198621D03*
X1621063D03*
X1617322D03*
X1613582D03*
X1624803Y1191141D03*
X1621063D03*
X1617322D03*
X1613582D03*
X1624803Y1206102D03*
X1621063D03*
X1617322D03*
X1613582D03*
X1624803Y1209842D03*
X1621063D03*
X1617322D03*
X1613582D03*
X1624803Y1221062D03*
X1621063D03*
X1617322D03*
X1613582D03*
X1617322Y1213582D03*
X1621063D03*
Y1217322D03*
X1624803Y1213582D03*
X1613582D03*
X1617322Y1217322D03*
X1613582D03*
X1624803D03*
X1621063Y1224803D03*
X1613582D03*
X1621063Y1228543D03*
X1613582D03*
X1624803Y1232283D03*
X1617322D03*
X1624803Y1236023D03*
X1617322D03*
X1624803Y1224803D03*
X1621063Y1232283D03*
X1617322Y1224803D03*
X1613582Y1232283D03*
X1624803Y1228543D03*
X1621063Y1236023D03*
X1617322Y1228543D03*
X1613582Y1236023D03*
X1624803Y1239763D03*
X1621063D03*
X1617322D03*
X1613582D03*
X1621063Y1243503D03*
X1613582D03*
X1621063Y1247243D03*
X1613582D03*
X1624803Y1250984D03*
X1617322D03*
X1624803Y1243503D03*
X1621063Y1250984D03*
X1617322Y1243503D03*
X1613582Y1250984D03*
X1624803Y1247243D03*
X1617322D03*
X1624803Y1254724D03*
X1617322D03*
X1621063D03*
X1613582D03*
X1639763Y1075196D03*
X1632283D03*
X1643504D03*
X1636023D03*
X1628543D03*
X1639763Y1078936D03*
X1632283D03*
X1643504Y1082677D03*
X1636023D03*
X1628543D03*
X1643504Y1086417D03*
X1636023D03*
X1628543D03*
X1643504Y1090157D03*
X1639763D03*
X1636023D03*
X1632283D03*
X1628543D03*
X1643504Y1078936D03*
X1639763Y1086417D03*
X1636023Y1078936D03*
X1632283Y1086417D03*
X1628543Y1078936D03*
X1639763Y1082677D03*
X1632283D03*
X1639763Y1093897D03*
X1632283D03*
X1639763Y1097637D03*
X1632283D03*
X1643504Y1101377D03*
X1636023D03*
X1628543D03*
X1643504Y1105117D03*
X1636023D03*
X1628543D03*
X1643504Y1097637D03*
X1639763Y1105117D03*
X1636023Y1097637D03*
X1632283Y1105117D03*
X1628543Y1097637D03*
X1643504Y1093897D03*
X1639763Y1101377D03*
X1636023Y1093897D03*
X1632283Y1101377D03*
X1628543Y1093897D03*
X1643504Y1108858D03*
X1639763D03*
X1636023D03*
X1632283D03*
X1628543D03*
X1643504Y1120078D03*
X1639763D03*
X1636023D03*
X1632283D03*
X1628543D03*
X1643504Y1123818D03*
X1639763D03*
X1636023D03*
X1632283D03*
X1628543D03*
X1643504Y1116338D03*
X1636023D03*
Y1112598D03*
X1643504D03*
X1639763Y1116338D03*
X1628543D03*
X1632283Y1112598D03*
X1628543D03*
X1632283Y1116338D03*
X1639763Y1112598D03*
X1643504Y1127558D03*
X1639763D03*
X1636023D03*
X1632283D03*
X1628543D03*
X1639763Y1131299D03*
X1643504Y1135039D03*
X1639763D03*
X1636023D03*
X1632283D03*
X1628543D03*
X1639763Y1138779D03*
X1643504Y1131299D03*
Y1138779D03*
X1636023Y1131299D03*
X1632283D03*
X1628543D03*
X1636023Y1138779D03*
X1632283D03*
X1628543D03*
X1639763Y1142519D03*
X1636023D03*
X1632283D03*
X1628543D03*
X1639763Y1146259D03*
X1643504Y1149999D03*
X1639763D03*
X1636023D03*
X1632283D03*
X1628543D03*
X1643504Y1153740D03*
X1639763D03*
X1636023Y1146259D03*
X1632283D03*
X1628543D03*
X1636023Y1153740D03*
X1632283D03*
X1628543D03*
X1643504Y1142519D03*
Y1146259D03*
Y1157480D03*
X1639763D03*
X1632283D03*
X1643504Y1161220D03*
X1628543D03*
X1643504Y1164960D03*
X1632283D03*
X1643504Y1168700D03*
X1628543D03*
X1643504Y1172440D03*
X1639763D03*
X1632283D03*
X1639763Y1161220D03*
X1636023D03*
X1632283D03*
X1639763Y1164960D03*
X1636023D03*
X1639763Y1168700D03*
X1636023D03*
X1632283D03*
X1636023Y1157480D03*
X1628543D03*
Y1164960D03*
X1636023Y1172440D03*
X1628543D03*
X1639763Y1183661D03*
Y1187401D03*
X1636023D03*
X1632283D03*
X1628543D03*
X1639763Y1176180D03*
X1636023Y1179921D03*
X1632283D03*
X1628543D03*
X1636023Y1183661D03*
X1632283D03*
X1628543D03*
X1636023Y1176180D03*
X1632283D03*
X1628543D03*
X1639763Y1179921D03*
X1643504Y1183661D03*
Y1187401D03*
Y1179921D03*
Y1176180D03*
X1639763Y1191141D03*
X1643504Y1194881D03*
X1639763D03*
X1636023D03*
X1632283D03*
X1628543D03*
X1639763Y1198621D03*
X1643504Y1202362D03*
X1639763D03*
X1636023D03*
X1632283D03*
X1628543D03*
X1643504Y1198621D03*
Y1191141D03*
X1636023Y1198621D03*
X1632283D03*
X1628543D03*
X1636023Y1191141D03*
X1632283D03*
X1628543D03*
X1643504Y1206102D03*
X1639763D03*
X1636023D03*
X1632283D03*
X1628543D03*
X1643504Y1209842D03*
X1639763D03*
X1636023D03*
X1632283D03*
X1628543D03*
X1643504Y1221062D03*
X1639763D03*
X1636023D03*
X1632283D03*
X1628543D03*
X1639763Y1217322D03*
X1643504Y1213582D03*
X1632283D03*
X1628543Y1217322D03*
X1639763Y1213582D03*
X1636023D03*
Y1217322D03*
X1628543Y1213582D03*
X1643504Y1217322D03*
X1632283D03*
X1643504Y1224803D03*
X1636023D03*
X1628543D03*
X1643504Y1228543D03*
X1636023D03*
X1628543D03*
X1639763Y1232283D03*
X1632283D03*
X1639763Y1236023D03*
X1632283D03*
X1643504Y1232283D03*
X1639763Y1224803D03*
X1636023Y1232283D03*
X1632283Y1224803D03*
X1628543Y1232283D03*
X1643504Y1236023D03*
X1639763Y1228543D03*
X1636023Y1236023D03*
X1632283Y1228543D03*
X1628543Y1236023D03*
X1643504Y1239763D03*
X1639763D03*
X1636023D03*
X1632283D03*
X1628543D03*
X1643504Y1243503D03*
X1636023D03*
X1628543D03*
X1643504Y1247243D03*
X1636023D03*
X1628543D03*
X1639763Y1250984D03*
X1632283D03*
X1643504D03*
X1639763Y1243503D03*
X1636023Y1250984D03*
X1632283Y1243503D03*
X1628543Y1250984D03*
X1639763Y1247243D03*
X1632283D03*
X1639763Y1254724D03*
X1632283D03*
X1643504D03*
X1636023D03*
X1628543D03*
X1654724Y1075196D03*
X1647244D03*
X1658464D03*
X1650984D03*
X1654724Y1078936D03*
X1647244D03*
X1658464Y1082677D03*
X1650984D03*
X1658464Y1086417D03*
X1650984D03*
X1658464Y1090157D03*
X1654724D03*
X1650984D03*
X1647244D03*
X1658464Y1078936D03*
X1654724Y1086417D03*
X1650984Y1078936D03*
X1647244Y1086417D03*
X1654724Y1082677D03*
X1647244D03*
X1654724Y1093897D03*
X1647244D03*
X1654724Y1097637D03*
X1647244D03*
X1658464Y1101377D03*
X1650984D03*
X1658464Y1105117D03*
X1650984D03*
X1658464Y1097637D03*
X1654724Y1105117D03*
X1650984Y1097637D03*
X1647244Y1105117D03*
X1658464Y1093897D03*
X1654724Y1101377D03*
X1650984Y1093897D03*
X1647244Y1101377D03*
X1658464Y1108858D03*
X1654724D03*
X1650984D03*
X1647244D03*
X1650984Y1120078D03*
X1647244D03*
X1650984Y1123818D03*
X1647244D03*
X1654724Y1120078D03*
X1650984Y1112598D03*
Y1116338D03*
X1654724D03*
X1647244Y1112598D03*
X1654724Y1123818D03*
X1658464Y1116338D03*
Y1123818D03*
X1647244Y1116338D03*
X1658464Y1120078D03*
Y1112598D03*
X1654724D03*
X1650984Y1127558D03*
Y1131299D03*
Y1135039D03*
Y1138779D03*
X1647244D03*
Y1127558D03*
Y1135039D03*
Y1131299D03*
X1658464Y1127558D03*
Y1131299D03*
X1654724Y1127558D03*
Y1131299D03*
X1658464Y1138779D03*
X1654724Y1135039D03*
X1658464D03*
X1654724Y1138779D03*
X1650984Y1142519D03*
X1647244D03*
X1650984Y1146259D03*
X1647244D03*
X1650984Y1149999D03*
X1647244D03*
X1658464Y1153740D03*
X1654724D03*
X1650984D03*
X1647244D03*
X1654724Y1142519D03*
X1658464Y1149999D03*
X1654724D03*
Y1146259D03*
X1658464Y1142519D03*
Y1146259D03*
Y1157480D03*
X1650984D03*
X1658464Y1161220D03*
X1650984D03*
X1658464Y1164960D03*
X1650984D03*
X1658464Y1168700D03*
X1650984D03*
X1658464Y1172440D03*
X1650984D03*
X1654724Y1157480D03*
Y1161220D03*
Y1164960D03*
Y1168700D03*
Y1172440D03*
X1647244Y1157480D03*
Y1161220D03*
Y1164960D03*
Y1168700D03*
Y1172440D03*
X1654724Y1183661D03*
X1650984D03*
X1647244D03*
X1650984Y1187401D03*
X1647244D03*
X1658464Y1176180D03*
X1654724D03*
X1650984D03*
X1647244D03*
X1654724Y1179921D03*
X1647244D03*
X1658464Y1187401D03*
X1650984Y1179921D03*
X1654724Y1187401D03*
X1658464Y1179921D03*
Y1183661D03*
X1654724Y1191141D03*
X1650984D03*
X1647244D03*
X1650984Y1194881D03*
Y1198621D03*
Y1202362D03*
X1658464Y1191141D03*
X1647244Y1198621D03*
Y1202362D03*
Y1194881D03*
X1654724D03*
Y1202362D03*
X1658464Y1194881D03*
Y1202362D03*
Y1198621D03*
X1654724D03*
X1650984Y1206102D03*
Y1209842D03*
X1647244D03*
X1658464Y1221062D03*
X1654724D03*
X1650984D03*
X1647244D03*
Y1206102D03*
X1658464Y1217322D03*
X1654724Y1209842D03*
Y1213582D03*
X1647244Y1217322D03*
Y1213582D03*
X1650984D03*
X1654724Y1217322D03*
X1658464Y1213582D03*
Y1209842D03*
X1650984Y1217322D03*
X1654724Y1206102D03*
X1658464D03*
Y1224803D03*
X1650984D03*
X1658464Y1228543D03*
X1650984D03*
X1654724Y1232283D03*
X1647244D03*
X1654724Y1236023D03*
X1647244D03*
X1658464Y1232283D03*
X1654724Y1224803D03*
X1650984Y1232283D03*
X1647244Y1224803D03*
X1658464Y1236023D03*
X1654724Y1228543D03*
X1650984Y1236023D03*
X1647244Y1228543D03*
X1658464Y1239763D03*
X1654724D03*
X1650984D03*
X1647244D03*
X1658464Y1243503D03*
X1650984D03*
X1658464Y1247243D03*
X1650984D03*
X1654724Y1250984D03*
X1647244D03*
X1658464D03*
X1654724Y1243503D03*
X1650984Y1250984D03*
X1647244Y1243503D03*
X1654724Y1247243D03*
X1647244D03*
X1654724Y1254724D03*
X1647244D03*
X1658464D03*
X1650984D03*
X1669685Y1075196D03*
X1662204D03*
X1665945D03*
X1673425D03*
X1669685Y1078936D03*
X1662204D03*
X1673425Y1082677D03*
X1665945D03*
X1673425Y1086417D03*
X1665945D03*
X1673425Y1090157D03*
X1669685D03*
X1665945D03*
X1662204D03*
Y1086417D03*
Y1082677D03*
X1665945Y1078936D03*
X1669685Y1086417D03*
X1673425Y1078936D03*
X1669685Y1082677D03*
Y1093897D03*
X1662204D03*
X1669685Y1097637D03*
X1662204D03*
X1673425Y1101377D03*
X1665945D03*
X1673425Y1105117D03*
X1665945D03*
X1662204D03*
Y1101377D03*
X1665945Y1097637D03*
X1669685Y1105117D03*
X1673425Y1097637D03*
X1665945Y1093897D03*
X1669685Y1101377D03*
X1673425Y1093897D03*
Y1108858D03*
X1669685D03*
X1665945D03*
X1662204D03*
X1669685Y1112598D03*
X1665945D03*
X1662204D03*
X1673425Y1116338D03*
X1662204D03*
X1669685Y1120078D03*
X1665945D03*
X1662204D03*
X1673425Y1123818D03*
X1662204D03*
X1673425Y1112598D03*
X1665945Y1116338D03*
X1673425Y1120078D03*
X1665945Y1123818D03*
X1669685Y1116338D03*
Y1123818D03*
Y1127558D03*
X1665945D03*
X1662204D03*
X1673425Y1131299D03*
X1662204D03*
X1669685Y1135039D03*
X1665945D03*
X1662204D03*
X1673425Y1138779D03*
X1662204D03*
X1665945D03*
X1669685D03*
X1673425Y1127558D03*
X1665945Y1131299D03*
X1673425Y1135039D03*
X1669685Y1131299D03*
Y1142519D03*
X1665945D03*
X1662204D03*
X1673425Y1146259D03*
X1662204D03*
X1669685Y1149999D03*
X1665945D03*
X1662204D03*
X1673425Y1153740D03*
X1662204D03*
X1673425Y1142519D03*
X1665945Y1146259D03*
X1673425Y1149999D03*
X1665945Y1153740D03*
X1669685Y1146259D03*
Y1153740D03*
Y1157480D03*
X1665945D03*
X1662204D03*
X1673425Y1161220D03*
X1662204D03*
X1669685Y1164960D03*
X1665945D03*
X1662204D03*
X1673425Y1168700D03*
X1662204D03*
X1669685Y1172440D03*
X1665945D03*
X1662204D03*
X1673425Y1157480D03*
X1665945Y1161220D03*
X1673425Y1164960D03*
X1665945Y1168700D03*
X1673425Y1172440D03*
X1669685Y1161220D03*
Y1168700D03*
X1673425Y1183661D03*
X1662204D03*
X1669685Y1187401D03*
X1665945D03*
X1662204D03*
X1673425Y1176180D03*
X1662204D03*
X1669685Y1179921D03*
X1665945D03*
X1662204D03*
X1665945Y1176180D03*
X1673425Y1179921D03*
X1665945Y1183661D03*
X1673425Y1187401D03*
X1669685Y1176180D03*
Y1183661D03*
X1673425Y1191141D03*
X1662204D03*
X1669685Y1194881D03*
X1665945D03*
X1662204D03*
X1673425Y1198621D03*
X1662204D03*
X1669685Y1202362D03*
X1665945D03*
X1662204D03*
X1665945Y1191141D03*
X1673425Y1194881D03*
X1669685Y1191141D03*
X1673425Y1202362D03*
X1665945Y1198621D03*
X1669685D03*
X1673425Y1206102D03*
X1662204D03*
X1669685Y1209842D03*
X1665945D03*
X1662204D03*
X1673425Y1213582D03*
X1662204D03*
X1669685Y1217322D03*
X1665945D03*
X1662204D03*
X1673425Y1221062D03*
X1669685D03*
X1665945D03*
X1662204D03*
X1673425Y1217322D03*
X1665945Y1213582D03*
X1673425Y1209842D03*
X1665945Y1206102D03*
X1669685Y1213582D03*
Y1206102D03*
X1673425Y1224803D03*
X1665945D03*
X1673425Y1228543D03*
X1665945D03*
X1669685Y1232283D03*
X1662204D03*
X1669685Y1236023D03*
X1662204D03*
Y1224803D03*
X1665945Y1232283D03*
X1669685Y1224803D03*
X1673425Y1232283D03*
X1662204Y1228543D03*
X1665945Y1236023D03*
X1669685Y1228543D03*
X1673425Y1236023D03*
Y1239763D03*
X1669685D03*
X1665945D03*
X1662204D03*
X1673425Y1243503D03*
X1665945D03*
X1673425Y1247243D03*
X1665945D03*
X1669685Y1250984D03*
X1662204D03*
Y1243503D03*
X1665945Y1250984D03*
X1669685Y1243503D03*
X1673425Y1250984D03*
X1662204Y1247243D03*
X1669685D03*
Y1254724D03*
X1662204D03*
X1665945D03*
X1673425D03*
X1692126Y1075196D03*
X1684645D03*
X1677165D03*
X1688385D03*
X1680905D03*
X1692126Y1078936D03*
X1684645D03*
X1677165D03*
X1688385Y1082677D03*
X1680905D03*
X1692126Y1086417D03*
X1688385D03*
X1680905D03*
X1688385Y1090157D03*
X1684645D03*
X1680905D03*
X1677165D03*
X1692126D03*
X1688385Y1078936D03*
X1692126Y1082677D03*
X1677165Y1086417D03*
X1680905Y1078936D03*
X1684645Y1086417D03*
X1677165Y1082677D03*
X1684645D03*
X1692126Y1093897D03*
X1684645D03*
X1677165D03*
X1692126Y1097637D03*
X1684645D03*
X1677165D03*
X1688385Y1101377D03*
X1680905D03*
X1692126Y1105117D03*
X1688385D03*
X1680905D03*
X1688385Y1097637D03*
X1692126Y1101377D03*
X1677165Y1105117D03*
X1680905Y1097637D03*
X1684645Y1105117D03*
X1688385Y1093897D03*
X1677165Y1101377D03*
X1680905Y1093897D03*
X1684645Y1101377D03*
X1688385Y1108858D03*
X1684645D03*
X1680905D03*
X1677165D03*
X1692126Y1112598D03*
X1680905D03*
X1688385Y1116338D03*
X1684645D03*
X1680905D03*
X1677165D03*
X1692126Y1120078D03*
X1680905D03*
X1688385Y1123818D03*
X1684645D03*
X1680905D03*
X1677165D03*
Y1112598D03*
Y1120078D03*
X1692126Y1108858D03*
X1684645Y1112598D03*
X1692126Y1116338D03*
X1684645Y1120078D03*
X1692126Y1123818D03*
X1688385Y1112598D03*
Y1120078D03*
X1692126Y1127558D03*
X1680905D03*
X1688385Y1131299D03*
X1684645D03*
X1680905D03*
X1677165D03*
X1692126Y1135039D03*
X1680905D03*
X1688385Y1138779D03*
X1684645D03*
X1680905D03*
X1677165D03*
X1692126D03*
X1677165Y1127558D03*
Y1135039D03*
X1684645Y1127558D03*
X1692126Y1131299D03*
X1684645Y1135039D03*
X1688385Y1127558D03*
Y1135039D03*
X1692126Y1142519D03*
X1680905D03*
X1688385Y1146259D03*
X1684645D03*
X1680905D03*
X1677165D03*
X1692126Y1149999D03*
X1680905D03*
X1688385Y1153740D03*
X1684645D03*
X1680905D03*
X1677165D03*
Y1142519D03*
Y1149999D03*
X1684645Y1142519D03*
X1692126Y1146259D03*
X1684645Y1149999D03*
X1692126Y1153740D03*
X1688385Y1142519D03*
Y1149999D03*
X1692126Y1157480D03*
X1680905D03*
X1688385Y1161220D03*
X1684645D03*
X1680905D03*
X1677165D03*
X1692126Y1164960D03*
X1680905D03*
X1688385Y1168700D03*
X1684645D03*
X1680905D03*
X1677165D03*
X1692126Y1172440D03*
X1680905D03*
X1677165Y1157480D03*
Y1164960D03*
Y1172440D03*
X1684645Y1157480D03*
X1692126Y1161220D03*
X1684645Y1164960D03*
X1692126Y1168700D03*
X1684645Y1172440D03*
X1688385Y1157480D03*
Y1164960D03*
Y1172440D03*
Y1183661D03*
X1684645D03*
X1680905D03*
X1677165D03*
X1692126Y1187401D03*
X1680905D03*
X1688385Y1176180D03*
X1684645D03*
X1680905D03*
X1677165D03*
X1692126Y1179921D03*
X1680905D03*
X1677165D03*
Y1187401D03*
X1692126Y1176180D03*
X1684645Y1179921D03*
X1692126Y1183661D03*
X1684645Y1187401D03*
X1688385Y1179921D03*
Y1187401D03*
Y1191141D03*
X1684645D03*
X1680905D03*
X1677165D03*
X1692126Y1194881D03*
X1680905D03*
X1688385Y1198621D03*
X1684645D03*
X1680905D03*
X1677165D03*
X1692126Y1202362D03*
X1680905D03*
X1677165Y1194881D03*
X1692126Y1191141D03*
X1684645Y1194881D03*
X1688385D03*
X1677165Y1202362D03*
X1684645D03*
X1692126Y1198621D03*
X1688385Y1202362D03*
Y1206102D03*
X1684645D03*
X1680905D03*
X1677165D03*
X1692126Y1209842D03*
X1680905D03*
X1688385Y1213582D03*
X1684645D03*
X1680905D03*
X1677165D03*
X1692126Y1217322D03*
X1680905D03*
X1688385Y1221062D03*
X1684645D03*
X1680905D03*
X1677165D03*
Y1217322D03*
Y1209842D03*
X1692126Y1221062D03*
X1684645Y1217322D03*
X1692126Y1213582D03*
X1684645Y1209842D03*
X1692126Y1206102D03*
X1688385Y1217322D03*
Y1209842D03*
X1692126Y1224803D03*
X1688385D03*
X1680905D03*
X1688385Y1228543D03*
X1680905D03*
X1692126Y1232283D03*
X1684645D03*
X1677165D03*
X1692126Y1236023D03*
X1684645D03*
X1677165D03*
Y1224803D03*
X1680905Y1232283D03*
X1684645Y1224803D03*
X1688385Y1232283D03*
X1692126Y1228543D03*
X1677165D03*
X1680905Y1236023D03*
X1684645Y1228543D03*
X1688385Y1236023D03*
Y1239763D03*
X1684645D03*
X1680905D03*
X1677165D03*
X1692126Y1243503D03*
X1688385D03*
X1680905D03*
X1688385Y1247243D03*
X1680905D03*
X1692126Y1250984D03*
X1684645D03*
X1677165D03*
X1692126Y1239763D03*
X1677165Y1243503D03*
X1680905Y1250984D03*
X1684645Y1243503D03*
X1688385Y1250984D03*
X1692126Y1247243D03*
X1677165D03*
X1684645D03*
X1692126Y1254724D03*
X1684645D03*
X1677165D03*
X1680905D03*
X1688385D03*
X1695866Y1078936D03*
Y1086417D03*
Y1090157D03*
Y1082677D03*
Y1093897D03*
Y1097637D03*
Y1105117D03*
Y1101377D03*
Y1112598D03*
Y1120078D03*
Y1108858D03*
Y1116338D03*
Y1123818D03*
Y1127558D03*
Y1135039D03*
Y1138779D03*
Y1131299D03*
Y1142519D03*
Y1149999D03*
Y1146259D03*
Y1153740D03*
Y1157480D03*
Y1164960D03*
Y1172440D03*
Y1161220D03*
Y1168700D03*
Y1187401D03*
Y1179921D03*
Y1176180D03*
Y1183661D03*
Y1194881D03*
Y1202362D03*
Y1191141D03*
Y1198621D03*
Y1209842D03*
Y1217322D03*
Y1221062D03*
Y1213582D03*
Y1206102D03*
Y1224803D03*
Y1232283D03*
Y1236023D03*
Y1228543D03*
Y1243503D03*
Y1250984D03*
Y1239763D03*
Y1247243D03*
G54D69*
X45755Y1204259D03*
Y1202684D03*
Y1201110D03*
Y1210558D03*
Y1208984D03*
Y1207409D03*
Y1205834D03*
X410938Y872074D03*
Y873648D03*
Y875223D03*
Y876798D03*
Y878373D03*
Y879948D03*
Y881522D03*
X438087Y636111D03*
Y634536D03*
Y632961D03*
Y631386D03*
Y629811D03*
Y628237D03*
Y637685D03*
X889445Y1219561D03*
Y1217987D03*
Y1216412D03*
Y1214837D03*
Y1213262D03*
Y1211687D03*
Y1210113D03*
X953422Y1219561D03*
Y1217987D03*
Y1216412D03*
Y1214837D03*
Y1213262D03*
Y1211687D03*
Y1210113D03*
X1797402Y1220047D03*
Y1218473D03*
Y1216898D03*
Y1215323D03*
Y1213748D03*
Y1212173D03*
Y1210599D03*
G54D189*
X899988Y579293D03*
G54D199*
X939314Y712147D03*
G54D97*
X181269Y384429D03*
Y386791D03*
Y382067D03*
Y391516D03*
Y389154D03*
Y398602D03*
Y405689D03*
Y393878D03*
Y400965D03*
Y408051D03*
Y396240D03*
Y403327D03*
Y412776D03*
Y419862D03*
Y415138D03*
Y422224D03*
Y410413D03*
Y417500D03*
Y424587D03*
Y434036D03*
Y441122D03*
Y426949D03*
Y436398D03*
Y429311D03*
Y431673D03*
Y438760D03*
Y443484D03*
Y445847D03*
Y465177D03*
Y469902D03*
Y472264D03*
Y467539D03*
Y474626D03*
Y476988D03*
Y484075D03*
Y479350D03*
Y486437D03*
Y481713D03*
Y488799D03*
Y491162D03*
Y493524D03*
Y495886D03*
Y514036D03*
Y521122D03*
Y516398D03*
Y523484D03*
Y511673D03*
Y518760D03*
Y528209D03*
Y535295D03*
Y530571D03*
Y537658D03*
Y525847D03*
Y532933D03*
Y542382D03*
Y544744D03*
Y554193D03*
Y540020D03*
Y547106D03*
Y549469D03*
Y551831D03*
Y556555D03*
Y558917D03*
Y561280D03*
Y563642D03*
Y566004D03*
Y568366D03*
Y570728D03*
Y573091D03*
Y575453D03*
Y597480D03*
Y599843D03*
Y604567D03*
Y592756D03*
Y595118D03*
Y602205D03*
Y609291D03*
Y606929D03*
Y618740D03*
Y614016D03*
Y616378D03*
Y611654D03*
Y623465D03*
Y621102D03*
X199380Y384429D03*
Y386791D03*
Y382067D03*
Y391516D03*
Y389154D03*
Y398602D03*
Y405689D03*
Y393878D03*
Y400965D03*
Y408051D03*
Y396240D03*
Y403327D03*
Y412776D03*
Y419862D03*
Y415138D03*
Y422224D03*
Y410413D03*
Y417500D03*
Y424587D03*
Y434036D03*
Y441122D03*
Y426949D03*
Y436398D03*
Y429311D03*
Y431673D03*
Y438760D03*
Y443484D03*
Y445847D03*
Y465177D03*
Y469902D03*
Y472264D03*
Y467539D03*
Y474626D03*
Y476988D03*
Y484075D03*
Y479350D03*
Y486437D03*
Y481713D03*
Y488799D03*
Y491162D03*
Y493524D03*
Y495886D03*
Y514036D03*
Y521122D03*
Y516398D03*
Y523484D03*
Y511673D03*
Y518760D03*
Y528209D03*
Y535295D03*
Y530571D03*
Y537658D03*
Y525847D03*
Y532933D03*
Y542382D03*
Y544744D03*
Y549469D03*
Y554193D03*
Y551831D03*
Y540020D03*
Y547106D03*
Y556555D03*
Y558917D03*
Y561280D03*
Y563642D03*
Y566004D03*
Y568366D03*
Y570728D03*
Y573091D03*
Y575453D03*
Y597480D03*
Y599843D03*
Y604567D03*
Y592756D03*
Y595118D03*
Y602205D03*
Y618740D03*
Y611654D03*
Y609291D03*
Y606929D03*
Y614016D03*
Y616378D03*
Y621102D03*
Y623465D03*
X270305Y386772D03*
Y391496D03*
Y389134D03*
Y384410D03*
Y382047D03*
Y393858D03*
Y408032D03*
Y405669D03*
Y396221D03*
Y398583D03*
Y400945D03*
Y403307D03*
Y412756D03*
Y410394D03*
Y441870D03*
Y439508D03*
Y437146D03*
Y434784D03*
Y432421D03*
Y430059D03*
Y448957D03*
Y446595D03*
Y444232D03*
Y456043D03*
Y451319D03*
Y453681D03*
Y458406D03*
Y463130D03*
Y460768D03*
Y470217D03*
Y467854D03*
Y472579D03*
Y465492D03*
Y484390D03*
Y477303D03*
Y489114D03*
Y482028D03*
Y474941D03*
Y486752D03*
Y479665D03*
Y491476D03*
Y493839D03*
Y521437D03*
Y514350D03*
Y519075D03*
Y511988D03*
Y516713D03*
Y509626D03*
Y535610D03*
Y528524D03*
Y533248D03*
Y526162D03*
Y537973D03*
Y530886D03*
Y523799D03*
Y540335D03*
Y571476D03*
Y564390D03*
Y569114D03*
Y562028D03*
Y566752D03*
Y559665D03*
Y585650D03*
Y578563D03*
Y583288D03*
Y576201D03*
Y588012D03*
Y580925D03*
Y573839D03*
Y599823D03*
Y592736D03*
Y604547D03*
Y597461D03*
Y590374D03*
Y602185D03*
Y595099D03*
Y618721D03*
Y613996D03*
Y606910D03*
Y611634D03*
Y616358D03*
Y609272D03*
Y621083D03*
Y623445D03*
X288416Y382047D03*
Y384410D03*
Y386772D03*
Y391496D03*
Y389134D03*
Y396221D03*
Y408032D03*
Y405669D03*
Y398583D03*
Y400945D03*
Y403307D03*
Y393858D03*
Y412756D03*
Y410394D03*
Y441870D03*
Y439508D03*
Y437146D03*
Y434784D03*
Y432421D03*
Y430059D03*
Y451319D03*
Y458406D03*
Y448957D03*
Y446595D03*
Y444232D03*
Y456043D03*
Y453681D03*
Y463130D03*
Y460768D03*
Y470217D03*
Y467854D03*
Y472579D03*
Y465492D03*
Y484390D03*
Y477303D03*
Y489114D03*
Y482028D03*
Y474941D03*
Y486752D03*
Y479665D03*
Y491476D03*
Y493839D03*
Y521437D03*
Y514350D03*
Y519075D03*
Y511988D03*
Y516713D03*
Y509626D03*
Y535610D03*
Y528524D03*
Y533248D03*
Y526162D03*
Y537973D03*
Y530886D03*
Y523799D03*
Y540335D03*
Y571476D03*
Y564390D03*
Y569114D03*
Y562028D03*
Y566752D03*
Y559665D03*
Y585650D03*
Y578563D03*
Y583288D03*
Y576201D03*
Y588012D03*
Y580925D03*
Y573839D03*
Y599823D03*
Y592736D03*
Y604547D03*
Y597461D03*
Y590374D03*
Y602185D03*
Y595099D03*
Y618721D03*
Y613996D03*
Y606910D03*
Y611634D03*
Y616358D03*
Y609272D03*
Y621083D03*
Y623445D03*
X638355Y384429D03*
Y386791D03*
Y382067D03*
Y391516D03*
Y389154D03*
Y398602D03*
Y405689D03*
Y393878D03*
Y400965D03*
Y408051D03*
Y396240D03*
Y403327D03*
Y412776D03*
Y419862D03*
Y415138D03*
Y422224D03*
Y410413D03*
Y417500D03*
Y424587D03*
Y434036D03*
Y441122D03*
Y426949D03*
Y436398D03*
Y429311D03*
Y431673D03*
Y438760D03*
Y443484D03*
Y445847D03*
Y465177D03*
Y469902D03*
Y472264D03*
Y467539D03*
Y474626D03*
Y476988D03*
Y484075D03*
Y479350D03*
Y486437D03*
Y481713D03*
Y488799D03*
Y491162D03*
Y493524D03*
Y495886D03*
Y514036D03*
Y521122D03*
Y516398D03*
Y523484D03*
Y511673D03*
Y518760D03*
Y528209D03*
Y535295D03*
Y530571D03*
Y537658D03*
Y525847D03*
Y532933D03*
Y542382D03*
Y544744D03*
Y554193D03*
Y540020D03*
Y547106D03*
Y549469D03*
Y551831D03*
Y556555D03*
Y558917D03*
Y561280D03*
Y563642D03*
Y566004D03*
Y568366D03*
Y570728D03*
Y573091D03*
Y575453D03*
Y597480D03*
Y599843D03*
Y604567D03*
Y592756D03*
Y595118D03*
Y602205D03*
Y609291D03*
Y606929D03*
Y618740D03*
Y614016D03*
Y616378D03*
Y611654D03*
Y623465D03*
Y621102D03*
X656466Y384429D03*
Y386791D03*
Y382067D03*
Y391516D03*
Y389154D03*
Y398602D03*
Y405689D03*
Y393878D03*
Y400965D03*
Y408051D03*
Y396240D03*
Y403327D03*
Y412776D03*
Y419862D03*
Y415138D03*
Y422224D03*
Y410413D03*
Y417500D03*
Y424587D03*
Y434036D03*
Y441122D03*
Y426949D03*
Y436398D03*
Y429311D03*
Y431673D03*
Y438760D03*
Y443484D03*
Y445847D03*
Y465177D03*
Y469902D03*
Y472264D03*
Y467539D03*
Y474626D03*
Y476988D03*
Y484075D03*
Y479350D03*
Y486437D03*
Y481713D03*
Y488799D03*
Y491162D03*
Y493524D03*
Y495886D03*
Y514036D03*
Y521122D03*
Y516398D03*
Y523484D03*
Y511673D03*
Y518760D03*
Y528209D03*
Y535295D03*
Y530571D03*
Y537658D03*
Y525847D03*
Y532933D03*
Y542382D03*
Y544744D03*
Y549469D03*
Y554193D03*
Y551831D03*
Y540020D03*
Y547106D03*
Y556555D03*
Y558917D03*
Y561280D03*
Y563642D03*
Y566004D03*
Y568366D03*
Y570728D03*
Y573091D03*
Y575453D03*
Y597480D03*
Y599843D03*
Y604567D03*
Y592756D03*
Y595118D03*
Y602205D03*
Y618740D03*
Y611654D03*
Y609291D03*
Y606929D03*
Y614016D03*
Y616378D03*
Y621102D03*
Y623465D03*
X727391Y386772D03*
Y391496D03*
Y389134D03*
Y384410D03*
Y382047D03*
Y393858D03*
Y408032D03*
Y405669D03*
Y396221D03*
Y398583D03*
Y400945D03*
Y403307D03*
Y412756D03*
Y410394D03*
Y441870D03*
Y439508D03*
Y437146D03*
Y434784D03*
Y432421D03*
Y430059D03*
Y448957D03*
Y446595D03*
Y444232D03*
Y456043D03*
Y451319D03*
Y453681D03*
Y458406D03*
Y463130D03*
Y460768D03*
Y470217D03*
Y467854D03*
Y472579D03*
Y465492D03*
Y484390D03*
Y477303D03*
Y489114D03*
Y482028D03*
Y474941D03*
Y486752D03*
Y479665D03*
Y491476D03*
Y493839D03*
Y521437D03*
Y514350D03*
Y519075D03*
Y511988D03*
Y516713D03*
Y509626D03*
Y535610D03*
Y528524D03*
Y533248D03*
Y526162D03*
Y537973D03*
Y530886D03*
Y523799D03*
Y540335D03*
Y571476D03*
Y564390D03*
Y569114D03*
Y562028D03*
Y566752D03*
Y559665D03*
Y585650D03*
Y578563D03*
Y583288D03*
Y576201D03*
Y588012D03*
Y580925D03*
Y573839D03*
Y599823D03*
Y592736D03*
Y604547D03*
Y597461D03*
Y590374D03*
Y602185D03*
Y595099D03*
Y618721D03*
Y613996D03*
Y606910D03*
Y611634D03*
Y616358D03*
Y609272D03*
Y621083D03*
Y623445D03*
X745502Y382047D03*
Y384410D03*
Y386772D03*
Y391496D03*
Y389134D03*
Y396221D03*
Y408032D03*
Y405669D03*
Y398583D03*
Y400945D03*
Y403307D03*
Y393858D03*
Y412756D03*
Y410394D03*
Y441870D03*
Y439508D03*
Y437146D03*
Y434784D03*
Y432421D03*
Y430059D03*
Y451319D03*
Y458406D03*
Y448957D03*
Y446595D03*
Y444232D03*
Y456043D03*
Y453681D03*
Y463130D03*
Y460768D03*
Y470217D03*
Y467854D03*
Y472579D03*
Y465492D03*
Y484390D03*
Y477303D03*
Y489114D03*
Y482028D03*
Y474941D03*
Y486752D03*
Y479665D03*
Y491476D03*
Y493839D03*
Y521437D03*
Y514350D03*
Y519075D03*
Y511988D03*
Y516713D03*
Y509626D03*
Y535610D03*
Y528524D03*
Y533248D03*
Y526162D03*
Y537973D03*
Y530886D03*
Y523799D03*
Y540335D03*
Y571476D03*
Y564390D03*
Y569114D03*
Y562028D03*
Y566752D03*
Y559665D03*
Y585650D03*
Y578563D03*
Y583288D03*
Y576201D03*
Y588012D03*
Y580925D03*
Y573839D03*
Y599823D03*
Y592736D03*
Y604547D03*
Y597461D03*
Y590374D03*
Y602185D03*
Y595099D03*
Y618721D03*
Y613996D03*
Y606910D03*
Y611634D03*
Y616358D03*
Y609272D03*
Y621083D03*
Y623445D03*
X1095442Y384429D03*
Y386791D03*
Y382067D03*
Y391516D03*
Y389154D03*
Y398602D03*
Y405689D03*
Y393878D03*
Y400965D03*
Y408051D03*
Y396240D03*
Y403327D03*
Y412776D03*
Y419862D03*
Y415138D03*
Y422224D03*
Y410413D03*
Y417500D03*
Y424587D03*
Y434036D03*
Y441122D03*
Y426949D03*
Y436398D03*
Y429311D03*
Y431673D03*
Y438760D03*
Y443484D03*
Y445847D03*
Y465177D03*
Y469902D03*
Y472264D03*
Y467539D03*
Y474626D03*
Y476988D03*
Y484075D03*
Y479350D03*
Y486437D03*
Y481713D03*
Y488799D03*
Y491162D03*
Y493524D03*
Y495886D03*
Y514036D03*
Y521122D03*
Y516398D03*
Y523484D03*
Y511673D03*
Y518760D03*
Y528209D03*
Y535295D03*
Y530571D03*
Y537658D03*
Y525847D03*
Y532933D03*
Y542382D03*
Y544744D03*
Y554193D03*
Y540020D03*
Y547106D03*
Y549469D03*
Y551831D03*
Y556555D03*
Y558917D03*
Y561280D03*
Y563642D03*
Y566004D03*
Y568366D03*
Y570728D03*
Y573091D03*
Y575453D03*
Y597480D03*
Y599843D03*
Y604567D03*
Y592756D03*
Y595118D03*
Y602205D03*
Y609291D03*
Y606929D03*
Y618740D03*
Y614016D03*
Y616378D03*
Y611654D03*
Y623465D03*
Y621102D03*
X1113553Y384429D03*
Y386791D03*
Y382067D03*
Y391516D03*
Y389154D03*
Y398602D03*
Y405689D03*
Y393878D03*
Y400965D03*
Y408051D03*
Y396240D03*
Y403327D03*
Y412776D03*
Y419862D03*
Y415138D03*
Y422224D03*
Y410413D03*
Y417500D03*
Y424587D03*
Y434036D03*
Y441122D03*
Y426949D03*
Y436398D03*
Y429311D03*
Y431673D03*
Y438760D03*
Y443484D03*
Y445847D03*
Y465177D03*
Y469902D03*
Y472264D03*
Y467539D03*
Y474626D03*
Y476988D03*
Y484075D03*
Y479350D03*
Y486437D03*
Y481713D03*
Y488799D03*
Y491162D03*
Y493524D03*
Y495886D03*
Y514036D03*
Y521122D03*
Y516398D03*
Y523484D03*
Y511673D03*
Y518760D03*
Y528209D03*
Y535295D03*
Y530571D03*
Y537658D03*
Y525847D03*
Y532933D03*
Y542382D03*
Y544744D03*
Y549469D03*
Y554193D03*
Y551831D03*
Y540020D03*
Y547106D03*
Y556555D03*
Y558917D03*
Y561280D03*
Y563642D03*
Y566004D03*
Y568366D03*
Y570728D03*
Y573091D03*
Y575453D03*
Y597480D03*
Y599843D03*
Y604567D03*
Y592756D03*
Y595118D03*
Y602205D03*
Y618740D03*
Y611654D03*
Y609291D03*
Y606929D03*
Y614016D03*
Y616378D03*
Y621102D03*
Y623465D03*
X1184478Y386772D03*
Y391496D03*
Y389134D03*
Y384410D03*
Y382047D03*
Y393858D03*
Y408032D03*
Y405669D03*
Y396221D03*
Y398583D03*
Y400945D03*
Y403307D03*
Y412756D03*
Y410394D03*
Y441870D03*
Y439508D03*
Y437146D03*
Y434784D03*
Y432421D03*
Y430059D03*
Y448957D03*
Y446595D03*
Y444232D03*
Y456043D03*
Y451319D03*
Y453681D03*
Y458406D03*
Y463130D03*
Y460768D03*
Y470217D03*
Y467854D03*
Y472579D03*
Y465492D03*
Y484390D03*
Y477303D03*
Y489114D03*
Y482028D03*
Y474941D03*
Y486752D03*
Y479665D03*
Y491476D03*
Y493839D03*
Y521437D03*
Y514350D03*
Y519075D03*
Y511988D03*
Y516713D03*
Y509626D03*
Y535610D03*
Y528524D03*
Y533248D03*
Y526162D03*
Y537973D03*
Y530886D03*
Y523799D03*
Y540335D03*
Y571476D03*
Y564390D03*
Y569114D03*
Y562028D03*
Y566752D03*
Y559665D03*
Y585650D03*
Y578563D03*
Y583288D03*
Y576201D03*
Y588012D03*
Y580925D03*
Y573839D03*
Y599823D03*
Y592736D03*
Y604547D03*
Y597461D03*
Y590374D03*
Y602185D03*
Y595099D03*
Y618721D03*
Y613996D03*
Y606910D03*
Y611634D03*
Y616358D03*
Y609272D03*
Y621083D03*
Y623445D03*
X1202589Y382047D03*
Y384410D03*
Y386772D03*
Y391496D03*
Y389134D03*
Y396221D03*
Y408032D03*
Y405669D03*
Y398583D03*
Y400945D03*
Y403307D03*
Y393858D03*
Y412756D03*
Y410394D03*
Y441870D03*
Y439508D03*
Y437146D03*
Y434784D03*
Y432421D03*
Y430059D03*
Y451319D03*
Y458406D03*
Y448957D03*
Y446595D03*
Y444232D03*
Y456043D03*
Y453681D03*
Y463130D03*
Y460768D03*
Y470217D03*
Y467854D03*
Y472579D03*
Y465492D03*
Y484390D03*
Y477303D03*
Y489114D03*
Y482028D03*
Y474941D03*
Y486752D03*
Y479665D03*
Y491476D03*
Y493839D03*
Y521437D03*
Y514350D03*
Y519075D03*
Y511988D03*
Y516713D03*
Y509626D03*
Y535610D03*
Y528524D03*
Y533248D03*
Y526162D03*
Y537973D03*
Y530886D03*
Y523799D03*
Y540335D03*
Y571476D03*
Y564390D03*
Y569114D03*
Y562028D03*
Y566752D03*
Y559665D03*
Y585650D03*
Y578563D03*
Y583288D03*
Y576201D03*
Y588012D03*
Y580925D03*
Y573839D03*
Y599823D03*
Y592736D03*
Y604547D03*
Y597461D03*
Y590374D03*
Y602185D03*
Y595099D03*
Y618721D03*
Y613996D03*
Y606910D03*
Y611634D03*
Y616358D03*
Y609272D03*
Y621083D03*
Y623445D03*
X1552529Y384429D03*
Y386791D03*
Y382067D03*
Y391516D03*
Y389154D03*
Y398602D03*
Y405689D03*
Y393878D03*
Y400965D03*
Y408051D03*
Y396240D03*
Y403327D03*
Y412776D03*
Y419862D03*
Y415138D03*
Y422224D03*
Y410413D03*
Y417500D03*
Y424587D03*
Y434036D03*
Y441122D03*
Y426949D03*
Y436398D03*
Y429311D03*
Y431673D03*
Y438760D03*
Y443484D03*
Y445847D03*
Y465177D03*
Y469902D03*
Y472264D03*
Y467539D03*
Y474626D03*
Y476988D03*
Y484075D03*
Y479350D03*
Y486437D03*
Y481713D03*
Y488799D03*
Y491162D03*
Y493524D03*
Y495886D03*
Y514036D03*
Y521122D03*
Y516398D03*
Y523484D03*
Y511673D03*
Y518760D03*
Y528209D03*
Y535295D03*
Y530571D03*
Y537658D03*
Y525847D03*
Y532933D03*
Y542382D03*
Y544744D03*
Y554193D03*
Y540020D03*
Y547106D03*
Y549469D03*
Y551831D03*
Y556555D03*
Y558917D03*
Y561280D03*
Y563642D03*
Y566004D03*
Y568366D03*
Y570728D03*
Y573091D03*
Y575453D03*
Y597480D03*
Y599843D03*
Y604567D03*
Y592756D03*
Y595118D03*
Y602205D03*
Y609291D03*
Y606929D03*
Y618740D03*
Y614016D03*
Y616378D03*
Y611654D03*
Y623465D03*
Y621102D03*
X1570640Y384429D03*
Y386791D03*
Y382067D03*
Y391516D03*
Y389154D03*
Y398602D03*
Y405689D03*
Y393878D03*
Y400965D03*
Y408051D03*
Y396240D03*
Y403327D03*
Y412776D03*
Y419862D03*
Y415138D03*
Y422224D03*
Y410413D03*
Y417500D03*
Y424587D03*
Y434036D03*
Y441122D03*
Y426949D03*
Y436398D03*
Y429311D03*
Y431673D03*
Y438760D03*
Y443484D03*
Y445847D03*
Y465177D03*
Y469902D03*
Y472264D03*
Y467539D03*
Y474626D03*
Y476988D03*
Y484075D03*
Y479350D03*
Y486437D03*
Y481713D03*
Y488799D03*
Y491162D03*
Y493524D03*
Y495886D03*
Y514036D03*
Y521122D03*
Y516398D03*
Y523484D03*
Y511673D03*
Y518760D03*
Y528209D03*
Y535295D03*
Y530571D03*
Y537658D03*
Y525847D03*
Y532933D03*
Y542382D03*
Y544744D03*
Y549469D03*
Y554193D03*
Y551831D03*
Y540020D03*
Y547106D03*
Y556555D03*
Y558917D03*
Y561280D03*
Y563642D03*
Y566004D03*
Y568366D03*
Y570728D03*
Y573091D03*
Y575453D03*
Y597480D03*
Y599843D03*
Y604567D03*
Y592756D03*
Y595118D03*
Y602205D03*
Y618740D03*
Y611654D03*
Y609291D03*
Y606929D03*
Y614016D03*
Y616378D03*
Y621102D03*
Y623465D03*
X1641565Y386772D03*
Y391496D03*
Y389134D03*
Y384410D03*
Y382047D03*
Y393858D03*
Y408032D03*
Y405669D03*
Y396221D03*
Y398583D03*
Y400945D03*
Y403307D03*
Y412756D03*
Y410394D03*
Y441870D03*
Y439508D03*
Y437146D03*
Y434784D03*
Y432421D03*
Y430059D03*
Y448957D03*
Y446595D03*
Y444232D03*
Y456043D03*
Y451319D03*
Y453681D03*
Y458406D03*
Y463130D03*
Y460768D03*
Y470217D03*
Y467854D03*
Y472579D03*
Y465492D03*
Y484390D03*
Y477303D03*
Y489114D03*
Y482028D03*
Y474941D03*
Y486752D03*
Y479665D03*
Y491476D03*
Y493839D03*
Y521437D03*
Y514350D03*
Y519075D03*
Y511988D03*
Y516713D03*
Y509626D03*
Y535610D03*
Y528524D03*
Y533248D03*
Y526162D03*
Y537973D03*
Y530886D03*
Y523799D03*
Y540335D03*
Y571476D03*
Y564390D03*
Y569114D03*
Y562028D03*
Y566752D03*
Y559665D03*
Y585650D03*
Y578563D03*
Y583288D03*
Y576201D03*
Y588012D03*
Y580925D03*
Y573839D03*
Y599823D03*
Y592736D03*
Y604547D03*
Y597461D03*
Y590374D03*
Y602185D03*
Y595099D03*
Y618721D03*
Y613996D03*
Y606910D03*
Y611634D03*
Y616358D03*
Y609272D03*
Y621083D03*
Y623445D03*
X1659676Y382047D03*
Y384410D03*
Y386772D03*
Y391496D03*
Y389134D03*
Y396221D03*
Y408032D03*
Y405669D03*
Y398583D03*
Y400945D03*
Y403307D03*
Y393858D03*
Y412756D03*
Y410394D03*
Y441870D03*
Y439508D03*
Y437146D03*
Y434784D03*
Y432421D03*
Y430059D03*
Y451319D03*
Y458406D03*
Y448957D03*
Y446595D03*
Y444232D03*
Y456043D03*
Y453681D03*
Y463130D03*
Y460768D03*
Y470217D03*
Y467854D03*
Y472579D03*
Y465492D03*
Y484390D03*
Y477303D03*
Y489114D03*
Y482028D03*
Y474941D03*
Y486752D03*
Y479665D03*
Y491476D03*
Y493839D03*
Y521437D03*
Y514350D03*
Y519075D03*
Y511988D03*
Y516713D03*
Y509626D03*
Y535610D03*
Y528524D03*
Y533248D03*
Y526162D03*
Y537973D03*
Y530886D03*
Y523799D03*
Y540335D03*
Y571476D03*
Y564390D03*
Y569114D03*
Y562028D03*
Y566752D03*
Y559665D03*
Y585650D03*
Y578563D03*
Y583288D03*
Y576201D03*
Y588012D03*
Y580925D03*
Y573839D03*
Y599823D03*
Y592736D03*
Y604547D03*
Y597461D03*
Y590374D03*
Y602185D03*
Y595099D03*
Y618721D03*
Y613996D03*
Y606910D03*
Y611634D03*
Y616358D03*
Y609272D03*
Y621083D03*
Y623445D03*
G54D79*
X67191Y1046138D03*
X67163Y1050784D03*
X67209Y1055646D03*
X67273Y1060812D03*
X68999Y111123D03*
X71099D03*
X68999Y114723D03*
X71099D03*
X79401Y118235D03*
X81501D03*
X79401Y121835D03*
X81501D03*
X79401Y132409D03*
X81501D03*
X68999Y125296D03*
X71099D03*
X68999Y128896D03*
X71099D03*
X79401Y136009D03*
X81501D03*
X69291Y1046138D03*
X69263Y1050784D03*
X69309Y1055646D03*
X69373Y1060812D03*
X108138Y1009759D03*
X106038D03*
X147696Y401613D03*
X145596D03*
X147696Y398013D03*
X145596D03*
X145296Y415787D03*
X143196D03*
X145296Y412187D03*
X143196D03*
X145296Y429960D03*
X143196D03*
X145296Y440533D03*
X143196D03*
X145296Y426360D03*
X143196D03*
X145296Y444133D03*
X143196D03*
X145296Y472887D03*
X143196D03*
X145296Y469287D03*
X143196D03*
X145296Y487060D03*
X143196D03*
X145296Y483460D03*
X143196D03*
X145296Y517021D03*
X143196D03*
X145296Y513421D03*
X143196D03*
X145296Y531194D03*
X143196D03*
X145296Y527594D03*
X143196D03*
X155698Y390901D03*
X153598D03*
X155698Y394501D03*
X153598D03*
X155698Y408674D03*
X153598D03*
X155698Y405074D03*
X153598D03*
X155698Y422847D03*
X153598D03*
X155698Y419247D03*
X153598D03*
X155698Y437021D03*
X153598D03*
X155698Y433421D03*
X153598D03*
X155698Y490573D03*
X153598D03*
X155698Y476399D03*
X153598D03*
X155698Y479999D03*
X153598D03*
X155698Y494173D03*
X153598D03*
X155698Y520533D03*
X153598D03*
X155698Y524133D03*
X153598D03*
X155698Y538306D03*
X153598D03*
X155698Y534706D03*
X153598D03*
X171361Y111123D03*
X173461D03*
X171361Y114723D03*
X173461D03*
X181763Y118235D03*
Y132409D03*
Y121835D03*
X171361Y125296D03*
X173461D03*
X171361Y128896D03*
X173461D03*
X181763Y136009D03*
X183863Y118235D03*
Y132409D03*
Y121835D03*
Y136009D03*
X219559Y1447353D03*
X221659D03*
X219559Y1450953D03*
X221659D03*
X219559Y1458353D03*
X221659D03*
X219559Y1461953D03*
X221659D03*
X273723Y111123D03*
X275823D03*
X273723Y114723D03*
X275823D03*
X273723Y125296D03*
X275823D03*
X273723Y128896D03*
X275823D03*
X284125Y118235D03*
X286225D03*
X284125Y121835D03*
X286225D03*
X284125Y132409D03*
X286225D03*
X284125Y136009D03*
X286225D03*
X313987Y467206D03*
X316087D03*
X313987Y470806D03*
X316087D03*
X324389Y474318D03*
X326489D03*
X324389Y488491D03*
X326489D03*
X313987Y484979D03*
X316087D03*
X324389Y477918D03*
X326489D03*
X313987Y481379D03*
X316087D03*
X324389Y492091D03*
X326489D03*
X324389Y518452D03*
X326489D03*
X324389Y522052D03*
X326489D03*
X313987Y511339D03*
X316087D03*
X313987Y514939D03*
X316087D03*
X324389Y536225D03*
X326489D03*
X324389Y532625D03*
X326489D03*
X313987Y525513D03*
X316087D03*
X313987Y529113D03*
X316087D03*
X324389Y568491D03*
X326489D03*
X324389Y572091D03*
X326489D03*
X313987Y564979D03*
X316087D03*
X313987Y561379D03*
X316087D03*
X313987Y579152D03*
X316087D03*
X313987Y575552D03*
X316087D03*
X324389Y582665D03*
X326489D03*
X324389Y586265D03*
X326489D03*
X313987Y593325D03*
X316087D03*
X313987Y589725D03*
X316087D03*
X313987Y603899D03*
X316087D03*
X324389Y600438D03*
X326489D03*
X324389Y596838D03*
X326489D03*
X313987Y607499D03*
X316087D03*
X324389Y611011D03*
X326489D03*
X324389Y614611D03*
X326489D03*
X376085Y111123D03*
Y114723D03*
Y125296D03*
Y128896D03*
X378185Y111123D03*
Y114723D03*
Y125296D03*
Y128896D03*
X386487Y118235D03*
X388587D03*
X386487Y121835D03*
X388587D03*
X386487Y132409D03*
X388587D03*
X386487Y136009D03*
X388587D03*
X526086Y111123D03*
X528186D03*
X526086Y114723D03*
X528186D03*
X536488Y118235D03*
X538588D03*
X536488Y121835D03*
X538588D03*
X526086Y125296D03*
X528186D03*
X526086Y128896D03*
X528186D03*
X536488Y132409D03*
X538588D03*
X536488Y136009D03*
X538588D03*
X565225Y1009759D03*
X563125D03*
X602682Y398013D03*
Y401613D03*
X602382Y412187D03*
X600282D03*
X602382Y415787D03*
X600282D03*
X602382Y429960D03*
X600282D03*
X602382Y426360D03*
X600282D03*
X602382Y440533D03*
X600282D03*
X602382Y444133D03*
X600282D03*
X602382Y469287D03*
X600282D03*
X602382Y472887D03*
X600282D03*
X602382Y487060D03*
X600282D03*
X602382Y483460D03*
X600282D03*
X602382Y517021D03*
X600282D03*
X602382Y513421D03*
X600282D03*
X602382Y527594D03*
X600282D03*
X602382Y531194D03*
X600282D03*
X612784Y390901D03*
X610684D03*
X604782Y398013D03*
Y401613D03*
X612784Y394501D03*
X610684D03*
X612784Y408674D03*
X610684D03*
X612784Y405074D03*
X610684D03*
X612784Y422847D03*
X610684D03*
X612784Y419247D03*
X610684D03*
X612784Y433421D03*
X610684D03*
X612784Y437021D03*
X610684D03*
X612784Y490573D03*
X610684D03*
X612784Y476399D03*
X610684D03*
X612784Y479999D03*
X610684D03*
X612784Y494173D03*
X610684D03*
X612784Y520533D03*
X610684D03*
X612784Y524133D03*
X610684D03*
X612784Y534706D03*
X610684D03*
X612784Y538306D03*
X610684D03*
X628448Y111123D03*
X630548D03*
X628448Y114723D03*
X630548D03*
X628448Y125296D03*
X630548D03*
X628448Y128896D03*
X630548D03*
X638850Y118235D03*
X640950D03*
X638850Y121835D03*
X640950D03*
X638850Y132409D03*
X640950D03*
X638850Y136009D03*
X640950D03*
X730810Y114723D03*
X732910D03*
X730810Y111123D03*
X732910D03*
X730810Y125296D03*
X732910D03*
X730810Y128896D03*
X732910D03*
X741212Y118235D03*
X743312D03*
X741212Y132409D03*
X743312D03*
X741212Y121835D03*
X743312D03*
X741212Y136009D03*
X743312D03*
X771073Y470806D03*
X773173D03*
X771073Y467206D03*
X773173D03*
X781475Y474318D03*
Y488491D03*
Y477918D03*
X771073Y481379D03*
X773173D03*
X771073Y484979D03*
X773173D03*
X781475Y492091D03*
Y518452D03*
Y522052D03*
X771073Y511339D03*
X773173D03*
X771073Y514939D03*
X773173D03*
X771073Y525513D03*
X773173D03*
X781475Y532625D03*
Y536225D03*
X771073Y529113D03*
X773173D03*
X771073Y564979D03*
X773173D03*
X781475Y572091D03*
Y568491D03*
X771073Y561379D03*
X773173D03*
X781475Y582665D03*
Y586265D03*
X771073Y575552D03*
X773173D03*
X771073Y579152D03*
X773173D03*
X771073Y593325D03*
X773173D03*
X771073Y589725D03*
X773173D03*
X781475Y596838D03*
Y600438D03*
X771073Y603899D03*
X773173D03*
X771073Y607499D03*
X773173D03*
X781475Y611011D03*
Y614611D03*
X783575Y474318D03*
Y488491D03*
Y477918D03*
Y492091D03*
Y518452D03*
Y522052D03*
Y532625D03*
Y536225D03*
Y572091D03*
Y568491D03*
Y582665D03*
Y586265D03*
Y596838D03*
Y600438D03*
Y611011D03*
Y614611D03*
X833172Y111123D03*
X835272D03*
X833172Y114723D03*
X835272D03*
X833172Y125296D03*
X835272D03*
X833172Y128896D03*
X835272D03*
X843574Y118235D03*
X845674D03*
X843574Y121835D03*
X845674D03*
X843574Y132409D03*
X845674D03*
X843574Y136009D03*
X845674D03*
X911893Y1022889D03*
X911841Y1028101D03*
X913993Y1022889D03*
X913941Y1028101D03*
X919276Y1088717D03*
X921376D03*
X919304Y1080832D03*
X921404D03*
X983172Y111123D03*
X985272D03*
X983172Y114723D03*
X985272D03*
X993574Y118235D03*
Y121835D03*
X983172Y125296D03*
X985272D03*
X983172Y128896D03*
X985272D03*
X993574Y132409D03*
Y136009D03*
X995674Y118235D03*
Y121835D03*
Y132409D03*
Y136009D03*
X1022311Y1009759D03*
X1020211D03*
X1057369Y412187D03*
Y415787D03*
Y429960D03*
Y426360D03*
Y440533D03*
Y444133D03*
Y472887D03*
Y469287D03*
Y487060D03*
Y483460D03*
Y517021D03*
Y513421D03*
Y531194D03*
Y527594D03*
X1069871Y390901D03*
X1067771D03*
X1061869Y398013D03*
X1059769D03*
X1061869Y401613D03*
X1059769D03*
X1069871Y394501D03*
X1067771D03*
X1069871Y405074D03*
X1067771D03*
X1069871Y408674D03*
X1067771D03*
X1059469Y412187D03*
Y415787D03*
X1069871Y422847D03*
X1067771D03*
X1069871Y419247D03*
X1067771D03*
X1059469Y429960D03*
Y426360D03*
Y440533D03*
X1069871Y437021D03*
X1067771D03*
X1069871Y433421D03*
X1067771D03*
X1059469Y444133D03*
Y472887D03*
Y469287D03*
X1069871Y490573D03*
X1067771D03*
X1059469Y487060D03*
Y483460D03*
X1069871Y476399D03*
X1067771D03*
X1069871Y479999D03*
X1067771D03*
X1069871Y494173D03*
X1067771D03*
X1069871Y520533D03*
X1067771D03*
X1059469Y517021D03*
Y513421D03*
X1069871Y524133D03*
X1067771D03*
X1069871Y534706D03*
X1067771D03*
X1069871Y538306D03*
X1067771D03*
X1059469Y531194D03*
Y527594D03*
X1085534Y114723D03*
X1087634D03*
X1085534Y111123D03*
X1087634D03*
X1085534Y125296D03*
X1087634D03*
X1085534Y128896D03*
X1087634D03*
X1095936Y118235D03*
X1098036D03*
X1095936Y121835D03*
X1098036D03*
X1095936Y132409D03*
X1098036D03*
X1095936Y136009D03*
X1098036D03*
X1187896Y111123D03*
Y114723D03*
Y125296D03*
Y128896D03*
X1189996Y111123D03*
Y114723D03*
Y125296D03*
Y128896D03*
X1198298Y118235D03*
X1200398D03*
X1198298Y121835D03*
X1200398D03*
X1198298Y132409D03*
X1200398D03*
X1198298Y136009D03*
X1200398D03*
X1228160Y467206D03*
X1230260D03*
X1228160Y470806D03*
X1230260D03*
X1228160Y481379D03*
X1230260D03*
X1228160Y484979D03*
X1230260D03*
X1228160Y511339D03*
X1230260D03*
X1228160Y514939D03*
X1230260D03*
X1228160Y525513D03*
X1230260D03*
X1228160Y529113D03*
X1230260D03*
X1228160Y564979D03*
X1230260D03*
X1228160Y561379D03*
X1230260D03*
X1228160Y579152D03*
X1230260D03*
X1228160Y575552D03*
X1230260D03*
X1228160Y593325D03*
X1230260D03*
X1228160Y589725D03*
X1230260D03*
X1228160Y603899D03*
X1230260D03*
X1228160Y607499D03*
X1230260D03*
X1238562Y474318D03*
X1240662D03*
X1238562Y488491D03*
X1240662D03*
X1238562Y477918D03*
X1240662D03*
X1238562Y492091D03*
X1240662D03*
X1238562Y518452D03*
X1240662D03*
X1238562Y522052D03*
X1240662D03*
X1238562Y532625D03*
X1240662D03*
X1238562Y536225D03*
X1240662D03*
X1238562Y572091D03*
X1240662D03*
X1238562Y568491D03*
X1240662D03*
X1238562Y582665D03*
X1240662D03*
X1238562Y586265D03*
X1240662D03*
X1238562Y596838D03*
X1240662D03*
X1238562Y600438D03*
X1240662D03*
X1238562Y611011D03*
X1240662D03*
X1238562Y614611D03*
X1240662D03*
X1290258Y111123D03*
X1292358D03*
X1290258Y114723D03*
X1292358D03*
X1300660Y118235D03*
X1302760D03*
X1290258Y128896D03*
X1292358D03*
X1300660Y132409D03*
X1302760D03*
X1300660Y121835D03*
X1302760D03*
X1290258Y125296D03*
X1292358D03*
X1300660Y136009D03*
X1302760D03*
X1424453Y1491198D03*
X1426553D03*
X1440259Y111123D03*
X1442359D03*
X1440259Y114723D03*
X1442359D03*
X1440259Y125296D03*
X1442359D03*
X1440259Y128896D03*
X1442359D03*
X1450661Y118235D03*
X1452761D03*
X1450661Y132409D03*
X1452761D03*
X1450661Y121835D03*
X1452761D03*
X1450661Y136009D03*
X1452761D03*
X1479398Y1009759D03*
X1477298D03*
X1526958Y390901D03*
X1524858D03*
X1526958Y394501D03*
X1524858D03*
X1518956Y398013D03*
X1516856D03*
X1518956Y401613D03*
X1516856D03*
X1526958Y408674D03*
X1524858D03*
X1526958Y405074D03*
X1524858D03*
X1516556Y415787D03*
X1514456D03*
X1516556Y412187D03*
X1514456D03*
X1526958Y422847D03*
X1524858D03*
X1526958Y419247D03*
X1524858D03*
X1526958Y437021D03*
X1524858D03*
X1526958Y433421D03*
X1524858D03*
X1516556Y429960D03*
X1514456D03*
X1516556Y426360D03*
X1514456D03*
X1516556Y440533D03*
X1514456D03*
X1516556Y444133D03*
X1514456D03*
X1516556Y472887D03*
X1514456D03*
X1516556Y469287D03*
X1514456D03*
X1516556Y487060D03*
X1514456D03*
X1526958Y490573D03*
X1524858D03*
X1526958Y476399D03*
X1524858D03*
X1526958Y479999D03*
X1524858D03*
X1516556Y483460D03*
X1514456D03*
X1526958Y494173D03*
X1524858D03*
X1516556Y517021D03*
X1514456D03*
X1516556Y513421D03*
X1514456D03*
X1526958Y520533D03*
X1524858D03*
X1516556Y531194D03*
X1514456D03*
X1516556Y527594D03*
X1514456D03*
X1526958Y524133D03*
X1524858D03*
X1526958Y534706D03*
X1524858D03*
X1526958Y538306D03*
X1524858D03*
X1542621Y111123D03*
X1544721D03*
X1542621Y114723D03*
X1544721D03*
X1542621Y125296D03*
X1544721D03*
X1542621Y128896D03*
X1544721D03*
X1553023Y118235D03*
X1555123D03*
X1553023Y121835D03*
X1555123D03*
X1553023Y132409D03*
X1555123D03*
X1553023Y136009D03*
X1555123D03*
X1644983Y111123D03*
X1647083D03*
X1644983Y114723D03*
X1647083D03*
X1655385Y118235D03*
X1657485D03*
X1655385Y121835D03*
X1657485D03*
X1655385Y132409D03*
X1657485D03*
X1644983Y125296D03*
X1647083D03*
X1644983Y128896D03*
X1647083D03*
X1655385Y136009D03*
X1657485D03*
X1685247Y467206D03*
X1687347D03*
X1685247Y470806D03*
X1687347D03*
X1685247Y481379D03*
X1687347D03*
X1685247Y484979D03*
X1687347D03*
X1685247Y511339D03*
X1687347D03*
X1685247Y514939D03*
X1687347D03*
X1685247Y525513D03*
X1687347D03*
X1685247Y529113D03*
X1687347D03*
X1685247Y564979D03*
X1687347D03*
X1685247Y561379D03*
X1687347D03*
X1685247Y579152D03*
X1687347D03*
X1685247Y575552D03*
X1687347D03*
X1685247Y593325D03*
X1687347D03*
X1685247Y589725D03*
X1687347D03*
X1685247Y603899D03*
X1687347D03*
X1685247Y607499D03*
X1687347D03*
X1695649Y474318D03*
X1697749D03*
X1695649Y488491D03*
X1697749D03*
X1695649Y477918D03*
X1697749D03*
X1695649Y492091D03*
X1697749D03*
X1695649Y518452D03*
X1697749D03*
X1695649Y522052D03*
X1697749D03*
X1695649Y532625D03*
X1697749D03*
X1695649Y536225D03*
X1697749D03*
X1695649Y568491D03*
X1697749D03*
X1695649Y572091D03*
X1697749D03*
X1695649Y582665D03*
X1697749D03*
X1695649Y586265D03*
X1697749D03*
X1695649Y596838D03*
X1697749D03*
X1695649Y600438D03*
X1697749D03*
X1695649Y614611D03*
X1697749D03*
X1695649Y611011D03*
X1697749D03*
X1747345Y111123D03*
X1749445D03*
X1747345Y114723D03*
X1749445D03*
X1757747Y118235D03*
Y121835D03*
X1747345Y125296D03*
X1749445D03*
X1747345Y128896D03*
X1749445D03*
X1757747Y132409D03*
Y136009D03*
X1759847Y118235D03*
Y121835D03*
Y132409D03*
Y136009D03*
X1818878Y1041550D03*
X1816778D03*
X1819068Y1056783D03*
X1816968D03*
X1818959Y1051219D03*
X1816859D03*
X1818902Y1046756D03*
X1816802D03*
G54D88*
X82638Y1417010D03*
X931080Y313436D03*
G54D89*
X90658Y1003349D03*
X94398D03*
X547745D03*
X551485D03*
X1004831D03*
X1008571D03*
X1259368Y854487D03*
X1263108D03*
X1259368Y864487D03*
X1263108D03*
X1259368Y859487D03*
X1263108D03*
X1259368Y874487D03*
X1263108D03*
X1259368Y879487D03*
X1263108D03*
X1259368Y869487D03*
X1263108D03*
X1259368Y884487D03*
X1263108D03*
X1259368Y889487D03*
X1263108D03*
X1273264Y895646D03*
X1277004D03*
X1461918Y1003349D03*
X1465658D03*
G54D98*
X173829Y455492D03*
Y583957D03*
X202844Y455492D03*
Y583957D03*
X266841Y421555D03*
Y550020D03*
X295856Y421555D03*
Y550020D03*
X630915Y455492D03*
Y583957D03*
X659930Y455492D03*
Y583957D03*
X723927Y421555D03*
Y550020D03*
X752942Y421555D03*
Y550020D03*
X1088002Y455492D03*
Y583957D03*
X1117017Y455492D03*
Y583957D03*
X1181014Y421555D03*
Y550020D03*
X1210029Y421555D03*
Y550020D03*
X1545089Y455492D03*
Y583957D03*
X1574104Y455492D03*
Y583957D03*
X1638101Y421555D03*
Y550020D03*
X1667116Y421555D03*
Y550020D03*
G54D99*
X190325Y368760D03*
X279360Y636752D03*
X647411Y368760D03*
X736446Y636752D03*
X1104498Y368760D03*
X1193533Y636752D03*
X1561585Y368760D03*
X1650620Y636752D03*
M02*
